(kicad_pcb
	(version 20260206)
	(generator "pcbnew")
	(generator_version "10.0")
	(general
		(thickness 1.21888)
		(legacy_teardrops no)
	)
	(paper "A4")
	(layers
		(0 "F.Cu" signal "TOP")
		(4 "In1.Cu" signal "SGND")
		(6 "In2.Cu" signal "IN1")
		(8 "In3.Cu" signal "IN2")
		(10 "In4.Cu" signal "SGND1")
		(2 "B.Cu" signal "BOTTOM")
		(9 "F.Adhes" user "F.Adhesive")
		(11 "B.Adhes" user "B.Adhesive")
		(13 "F.Paste" user "Top Paste")
		(15 "B.Paste" user "Bottom Paste")
		(5 "F.SilkS" user "Top Overlay")
		(7 "B.SilkS" user "Bottom Overlay")
		(1 "F.Mask" user "Top Solder")
		(3 "B.Mask" user "Bottom Solder")
		(17 "Dwgs.User" user "User.Drawings")
		(19 "Cmts.User" user "User.Comments")
		(21 "Eco1.User" user "User.Eco1")
		(23 "Eco2.User" user "User.Eco2")
		(25 "Edge.Cuts" user)
		(27 "Margin" user)
		(31 "F.CrtYd" user "Top Courtyard")
		(29 "B.CrtYd" user "Bottom Courtyard")
		(35 "F.Fab" user "Top Component Center")
		(33 "B.Fab" user "Bottom Component Center")
	)
	(setup
		(pad_to_mask_clearance 0.1016)
		(allow_soldermask_bridges_in_footprints no)
		(tenting
			(front yes)
			(back yes)
		)
		(covering
			(front no)
			(back no)
		)
		(plugging
			(front no)
			(back no)
		)
		(capping no)
		(filling no)
		(aux_axis_origin -61.8784 262.2786)
		(grid_origin -61.8784 262.2786)
		(pcbplotparams
			(layerselection 0x00000000_00000000_55555555_5755f5ff)
			(plot_on_all_layers_selection 0x00000000_00000000_00000000_00000000)
			(disableapertmacros no)
			(usegerberextensions no)
			(usegerberattributes yes)
			(usegerberadvancedattributes yes)
			(creategerberjobfile yes)
			(dashed_line_dash_ratio 12)
			(dashed_line_gap_ratio 3)
			(svgprecision 4)
			(plotframeref no)
			(mode 1)
			(useauxorigin no)
			(pdf_front_fp_property_popups yes)
			(pdf_back_fp_property_popups yes)
			(pdf_metadata yes)
			(pdf_single_document no)
			(dxfpolygonmode yes)
			(dxfimperialunits yes)
			(dxfusepcbnewfont yes)
			(psnegative no)
			(psa4output no)
			(plot_black_and_white yes)
			(sketchpadsonfab no)
			(plotpadnumbers no)
			(hidednponfab no)
			(sketchdnponfab yes)
			(crossoutdnponfab yes)
			(subtractmaskfromsilk no)
			(outputformat 1)
			(mirror no)
			(drillshape 1)
			(scaleselection 1)
			(outputdirectory "")
		)
	)
	(footprint "Vault:SMTC-TSW-105-05-X-S"
		(layer "F.Cu")
		(at 147.8216 94.6162 90)
		(property "Reference" "P1"
			(at 2.808605 -1.973079 90)
			(unlocked yes)
			(layer "F.SilkS")
			(effects
				(font
					(size 0.762 0.762)
					(thickness 0.2286)
				)
			)
		)
		(property "Value" "TSW-105-05-L-S"
			(at -2.910071 6.360355 0)
			(unlocked yes)
			(layer "F.SilkS")
			(hide yes)
			(effects
				(font
					(size 0.762 0.762)
					(thickness 0.2286)
				)
			)
		)
		(sheetname "05-GPS_IMU_SENSORS")
		(sheetfile "05-GPS_IMU_SENSORS.kicad_sch")
		(duplicate_pad_numbers_are_jumpers no)
		(fp_line
			(start 11.62 -1.27)
			(end 11.62 1.27)
			(stroke
				(width 0.2)
				(type solid)
			)
			(layer "F.SilkS")
		)
		(fp_line
			(start -1.46 -1.27)
			(end 11.62 -1.27)
			(stroke
				(width 0.2)
				(type solid)
			)
			(layer "F.SilkS")
		)
		(fp_line
			(start -1.46 -1.27)
			(end -1.46 1.27)
			(stroke
				(width 0.2)
				(type solid)
			)
			(layer "F.SilkS")
		)
		(fp_line
			(start -1.46 1.27)
			(end 11.62 1.27)
			(stroke
				(width 0.2)
				(type solid)
			)
			(layer "F.SilkS")
		)
		(pad "1" thru_hole rect
			(at 0 0 90)
			(size 1.55 1.55)
			(drill 1.02)
			(layers "*.Cu" "*.Mask")
			(remove_unused_layers no)
			(net "+3.3V")
		)
		(pad "2" thru_hole circle
			(at 2.54 0 90)
			(size 1.55 1.55)
			(drill 1.02)
			(layers "*.Cu" "*.Mask")
			(remove_unused_layers no)
			(net "GND")
			(thermal_bridge_angle 90)
		)
		(pad "3" thru_hole circle
			(at 5.08 0 90)
			(size 1.55 1.55)
			(drill 1.02)
			(layers "*.Cu" "*.Mask")
			(remove_unused_layers no)
			(net "ANADC_I2C_SCL")
			(thermal_bridge_angle 90)
		)
		(pad "4" thru_hole circle
			(at 7.62 0 90)
			(size 1.55 1.55)
			(drill 1.02)
			(layers "*.Cu" "*.Mask")
			(remove_unused_layers no)
			(net "ANADC_I2C_SDA")
			(thermal_bridge_angle 90)
		)
		(pad "5" thru_hole circle
			(at 10.16 0 90)
			(size 1.55 1.55)
			(drill 1.02)
			(layers "*.Cu" "*.Mask")
			(remove_unused_layers no)
			(net "NetP1_5")
			(thermal_bridge_angle 90)
		)
	)
	(footprint "Vault:RESC1005X40X25NL05T05"
		(layer "F.Cu")
		(at 166.7216 116.4162)
		(property "Reference" "R127"
			(at -2.3968 0.226921 0)
			(unlocked yes)
			(layer "F.SilkS")
			(effects
				(font
					(size 0.762 0.762)
					(thickness 0.2032)
				)
			)
		)
		(property "Value" "27_1%_0402"
			(at -2.732281 7.35092 270)
			(unlocked yes)
			(layer "F.SilkS")
			(hide yes)
			(effects
				(font
					(size 0.762 0.762)
					(thickness 0.2032)
				)
			)
		)
		(sheetname "08-DIPSwitches_I2C")
		(sheetfile "08-DIPSwitches_I2C.kicad_sch")
		(duplicate_pad_numbers_are_jumpers no)
		(pad "1" smd rect
			(at -0.45 0 90)
			(size 0.55 0.55)
			(layers "F.Cu" "F.Mask" "F.Paste")
			(net "GND")
		)
		(pad "2" smd rect
			(at 0.45 0 90)
			(size 0.55 0.55)
			(layers "F.Cu" "F.Mask" "F.Paste")
			(net "NetR127_2")
		)
	)
	(footprint "Vault:FP-LTST-C191KGKT-MFG"
		(layer "F.Cu")
		(at 224.7216 112.7162)
		(property "Reference" "D22"
			(at -3.44522 0.026921 0)
			(unlocked yes)
			(layer "F.SilkS")
			(effects
				(font
					(size 0.762 0.762)
					(thickness 0.2286)
				)
			)
		)
		(property "Value" "LTST-C191KGKT"
			(at -3.697471 8.34107 270)
			(unlocked yes)
			(layer "F.SilkS")
			(hide yes)
			(effects
				(font
					(size 0.762 0.762)
					(thickness 0.2286)
				)
			)
		)
		(sheetname "08-DIPSwitches_I2C")
		(sheetfile "08-DIPSwitches_I2C.kicad_sch")
		(duplicate_pad_numbers_are_jumpers no)
		(fp_line
			(start -0.85 -0.775)
			(end 0.85 -0.775)
			(stroke
				(width 0.2)
				(type solid)
			)
			(layer "F.SilkS")
		)
		(fp_line
			(start -0.85 0.775)
			(end 0.85 0.775)
			(stroke
				(width 0.2)
				(type solid)
			)
			(layer "F.SilkS")
		)
		(fp_circle
			(center -1.7 0)
			(end -1.7 -0.125)
			(stroke
				(width 0.25)
				(type solid)
			)
			(fill no)
			(layer "F.SilkS")
		)
		(fp_line
			(start -1.25 -0.55)
			(end 1.25 -0.55)
			(stroke
				(width 0.2)
				(type solid)
			)
			(layer "F.CrtYd")
		)
		(fp_line
			(start -1.25 0.55)
			(end -1.25 -0.55)
			(stroke
				(width 0.2)
				(type solid)
			)
			(layer "F.CrtYd")
		)
		(fp_line
			(start -1.25 0.55)
			(end 1.25 0.55)
			(stroke
				(width 0.2)
				(type solid)
			)
			(layer "F.CrtYd")
		)
		(fp_line
			(start 1.25 0.55)
			(end 1.25 -0.55)
			(stroke
				(width 0.2)
				(type solid)
			)
			(layer "F.CrtYd")
		)
		(fp_line
			(start -1.25 -0.55)
			(end 1.25 -0.55)
			(stroke
				(width 0.2)
				(type solid)
			)
			(layer "F.Fab")
		)
		(fp_line
			(start -1.25 0.55)
			(end -1.25 -0.55)
			(stroke
				(width 0.2)
				(type solid)
			)
			(layer "F.Fab")
		)
		(fp_line
			(start -1.25 0.55)
			(end 1.25 0.55)
			(stroke
				(width 0.2)
				(type solid)
			)
			(layer "F.Fab")
		)
		(fp_line
			(start -0.5 0)
			(end 0.5 0)
			(stroke
				(width 0.1)
				(type solid)
			)
			(layer "F.Fab")
		)
		(fp_line
			(start 0 0.5)
			(end 0 -0.5)
			(stroke
				(width 0.1)
				(type solid)
			)
			(layer "F.Fab")
		)
		(fp_line
			(start 1.25 0.55)
			(end 1.25 -0.55)
			(stroke
				(width 0.2)
				(type solid)
			)
			(layer "F.Fab")
		)
		(fp_text user "${REFERENCE}"
			(at 0 0.29534 360)
			(unlocked yes)
			(layer "F.Fab")
			(effects
				(font
					(face "Arial")
					(size 0.63 0.63)
					(thickness 0.1)
				)
				(justify left bottom)
			)
		)
		(pad "1" smd rect
			(at -0.75 0)
			(size 0.8 0.8)
			(layers "F.Cu" "F.Mask" "F.Paste")
			(net "NetD22_1")
			(solder_mask_margin 0)
			(solder_paste_margin 0)
		)
		(pad "2" smd rect
			(at 0.75 0)
			(size 0.8 0.8)
			(layers "F.Cu" "F.Mask" "F.Paste")
			(net "+3.3V")
			(solder_mask_margin 0)
			(solder_paste_margin 0)
		)
	)
	(footprint "Vault:FP-0402-L_1_0_1-W_0_5_0_1-IPC_C"
		(layer "F.Cu")
		(at 171.34767 83.56164 90)
		(property "Reference" "C83"
			(at 1.91684 0.246999 270)
			(unlocked yes)
			(layer "F.SilkS")
			(effects
				(font
					(size 0.762 0.762)
					(thickness 0.2286)
				)
			)
		)
		(property "Value" "0.1uF_25V_0402"
			(at -2.465561 9.839205 0)
			(unlocked yes)
			(layer "F.SilkS")
			(hide yes)
			(effects
				(font
					(size 0.762 0.762)
					(thickness 0.2286)
				)
			)
		)
		(sheetname "03-POWER")
		(sheetfile "03-POWER.kicad_sch")
		(duplicate_pad_numbers_are_jumpers no)
		(fp_line
			(start -0.65607 -0.7)
			(end 0.65606 -0.7)
			(stroke
				(width 0.2)
				(type solid)
			)
			(layer "F.SilkS")
		)
		(fp_line
			(start -0.65607 0.7)
			(end 0.65606 0.7)
			(stroke
				(width 0.2)
				(type solid)
			)
			(layer "F.SilkS")
		)
		(fp_line
			(start 0.75606 -0.4)
			(end 0.75606 0.4)
			(stroke
				(width 0.2)
				(type solid)
			)
			(layer "F.CrtYd")
		)
		(fp_line
			(start -0.75607 -0.4)
			(end 0.75606 -0.4)
			(stroke
				(width 0.2)
				(type solid)
			)
			(layer "F.CrtYd")
		)
		(fp_line
			(start -0.75607 -0.4)
			(end -0.75607 0.4)
			(stroke
				(width 0.2)
				(type solid)
			)
			(layer "F.CrtYd")
		)
		(fp_line
			(start -0.75607 0.4)
			(end 0.75606 0.4)
			(stroke
				(width 0.2)
				(type solid)
			)
			(layer "F.CrtYd")
		)
		(fp_line
			(start 0 -0.5)
			(end 0 0.5)
			(stroke
				(width 0.1)
				(type solid)
			)
			(layer "F.Fab")
		)
		(fp_line
			(start 0.75606 -0.4)
			(end 0.75606 0.4)
			(stroke
				(width 0.2)
				(type solid)
			)
			(layer "F.Fab")
		)
		(fp_line
			(start -0.75607 -0.4)
			(end 0.75606 -0.4)
			(stroke
				(width 0.2)
				(type solid)
			)
			(layer "F.Fab")
		)
		(fp_line
			(start -0.75607 -0.4)
			(end -0.75607 0.4)
			(stroke
				(width 0.2)
				(type solid)
			)
			(layer "F.Fab")
		)
		(fp_line
			(start -0.5 0)
			(end 0.49999 0)
			(stroke
				(width 0.1)
				(type solid)
			)
			(layer "F.Fab")
		)
		(fp_line
			(start -0.75607 0.4)
			(end 0.75606 0.4)
			(stroke
				(width 0.2)
				(type solid)
			)
			(layer "F.Fab")
		)
		(fp_text user "${REFERENCE}"
			(at -0.00002 0.09601 90)
			(unlocked yes)
			(layer "F.Fab")
			(effects
				(font
					(face "Arial")
					(size 0.63 0.63)
					(thickness 0.1)
				)
				(justify left bottom)
			)
		)
		(pad "1" smd rect
			(at -0.36554 0 90)
			(size 0.58106 0.51213)
			(layers "F.Cu" "F.Mask" "F.Paste")
			(net "+3.3V")
			(solder_mask_margin 0)
			(solder_paste_margin 0)
		)
		(pad "2" smd rect
			(at 0.36553 0 90)
			(size 0.58106 0.51213)
			(layers "F.Cu" "F.Mask" "F.Paste")
			(net "GND")
			(solder_mask_margin 0)
			(solder_paste_margin 0)
		)
	)
	(footprint "Vault:RESC1005X40X25LL05T10"
		(layer "F.Cu")
		(at 106.5216 57.6162 180)
		(property "Reference" "R152"
			(at 2.213 0.082179 0)
			(unlocked yes)
			(layer "F.SilkS")
			(effects
				(font
					(size 0.762 0.762)
					(thickness 0.2032)
				)
			)
		)
		(property "Value" "49.9_1%_0402"
			(at -2.579871 8.798275 90)
			(unlocked yes)
			(layer "F.SilkS")
			(hide yes)
			(effects
				(font
					(size 0.762 0.762)
					(thickness 0.2032)
				)
			)
		)
		(sheetname "11-M2_RCB_MUX")
		(sheetfile "11-M2_RCB_MUX.kicad_sch")
		(duplicate_pad_numbers_are_jumpers no)
		(pad "1" smd rect
			(at -0.375 0 270)
			(size 0.45 0.5)
			(layers "F.Cu" "F.Mask" "F.Paste")
			(net "NetR152_1")
		)
		(pad "2" smd rect
			(at 0.375 0 270)
			(size 0.45 0.5)
			(layers "F.Cu" "F.Mask" "F.Paste")
			(net "GPS1_RX")
		)
	)
	(footprint "Resistors:RESC2012X50N"
		(layer "F.Cu")
		(at 184.10761 145.49763)
		(property "Reference" "R18"
			(at -0.68526 -1.068085 0)
			(unlocked yes)
			(layer "F.SilkS")
			(effects
				(font
					(size 0.762 0.762)
					(thickness 0.2286)
				)
				(justify left bottom)
			)
		)
		(property "Value" "CRCW080533R0FKEA"
			(at -5.52491 -8.929165 0)
			(unlocked yes)
			(layer "F.SilkS")
			(hide yes)
			(effects
				(font
					(size 0.762 0.762)
					(thickness 0.2286)
				)
				(justify left bottom)
			)
		)
		(sheetname "04-PCIe_JTAG")
		(sheetfile "04-PCIe_JTAG.kicad_sch")
		(duplicate_pad_numbers_are_jumpers no)
		(fp_line
			(start 0 0.762)
			(end 0 -0.762)
			(stroke
				(width 0.1524)
				(type solid)
			)
			(layer "F.SilkS")
		)
		(pad "1" smd rect
			(at -1 0 90)
			(size 1.45 0.95)
			(layers "F.Cu" "F.Mask" "F.Paste")
			(net "FPGA_TCK")
		)
		(pad "2" smd rect
			(at 1 0 90)
			(size 1.45 0.95)
			(layers "F.Cu" "F.Mask" "F.Paste")
			(net "NetP4_1")
		)
	)
	(footprint "FPGA_CONN:SingleFPGAConn"
		(locked yes)
		(layer "F.Cu")
		(at 138.43638 129.97062)
		(property "Reference" "J36"
			(at -1.77665 -22.527499 0)
			(unlocked yes)
			(layer "F.SilkS")
			(effects
				(font
					(size 0.762 0.762)
					(thickness 0.2286)
				)
			)
		)
		(property "Value" "Single FPGA Conn"
			(at 9.25452 3.621231 0)
			(unlocked yes)
			(layer "F.SilkS")
			(hide yes)
			(effects
				(font
					(size 0.762 0.762)
					(thickness 0.2286)
				)
			)
		)
		(sheetname "07-FPGA")
		(sheetfile "07-FPGA.kicad_sch")
		(duplicate_pad_numbers_are_jumpers no)
		(fp_line
			(start -2 -20.69999)
			(end -1.40005 -20.69999)
			(stroke
				(width 0.15011)
				(type solid)
			)
			(layer "F.SilkS")
		)
		(fp_line
			(start -2 -20.03298)
			(end -2 -20.69999)
			(stroke
				(width 0.15011)
				(type solid)
			)
			(layer "F.SilkS")
		)
		(fp_line
			(start -2 0.70002)
			(end -2 0.03302)
			(stroke
				(width 0.15011)
				(type solid)
			)
			(layer "F.SilkS")
		)
		(fp_line
			(start -2 0.70002)
			(end -1.40005 0.70002)
			(stroke
				(width 0.15011)
				(type solid)
			)
			(layer "F.SilkS")
		)
		(fp_line
			(start -1.40005 -21.2499)
			(end 1.40004 -21.2499)
			(stroke
				(width 0.15011)
				(type solid)
			)
			(layer "F.SilkS")
		)
		(fp_line
			(start -1.40005 -20.69999)
			(end -1.40005 -21.2499)
			(stroke
				(width 0.15011)
				(type solid)
			)
			(layer "F.SilkS")
		)
		(fp_line
			(start -1.40005 1.24993)
			(end -1.40005 0.70002)
			(stroke
				(width 0.15011)
				(type solid)
			)
			(layer "F.SilkS")
		)
		(fp_line
			(start -1.40005 1.24993)
			(end 1.40004 1.24993)
			(stroke
				(width 0.15011)
				(type solid)
			)
			(layer "F.SilkS")
		)
		(fp_line
			(start 1.40004 -21.2499)
			(end 1.99999 -20.69999)
			(stroke
				(width 0.15011)
				(type solid)
			)
			(layer "F.SilkS")
		)
		(fp_line
			(start 1.40004 1.24993)
			(end 1.99999 0.70002)
			(stroke
				(width 0.15011)
				(type solid)
			)
			(layer "F.SilkS")
		)
		(fp_line
			(start 1.99999 -20.03298)
			(end 1.99999 -20.69999)
			(stroke
				(width 0.15011)
				(type solid)
			)
			(layer "F.SilkS")
		)
		(fp_line
			(start 1.99999 0.70002)
			(end 1.99999 0.03302)
			(stroke
				(width 0.15011)
				(type solid)
			)
			(layer "F.SilkS")
		)
		(fp_circle
			(center 3.5052 -0.22454)
			(end 3.5052 -0.42469)
			(stroke
				(width 0.40005)
				(type solid)
			)
			(fill no)
			(layer "F.SilkS")
		)
		(pad "1" smd rect
			(at 2.02488 -0.24994)
			(size 1.54991 0.24994)
			(layers "F.Cu" "F.Mask" "F.Paste")
			(net "GPS2_TX_FPGA")
		)
		(pad "2" smd rect
			(at -2.02489 -0.24994)
			(size 1.54991 0.24994)
			(layers "F.Cu" "F.Mask" "F.Paste")
			(net "GPS2_RX_FPGA")
		)
		(pad "3" smd rect
			(at 2.02488 -0.75007)
			(size 1.54991 0.24994)
			(layers "F.Cu" "F.Mask" "F.Paste")
		)
		(pad "4" smd rect
			(at -2.02489 -0.75007)
			(size 1.54991 0.24994)
			(layers "F.Cu" "F.Mask" "F.Paste")
		)
		(pad "5" smd rect
			(at 2.02488 -1.24994)
			(size 1.54991 0.24994)
			(layers "F.Cu" "F.Mask" "F.Paste")
			(net "GPS2_TP1")
		)
		(pad "6" smd rect
			(at -2.02489 -1.24994)
			(size 1.54991 0.24994)
			(layers "F.Cu" "F.Mask" "F.Paste")
		)
		(pad "7" smd rect
			(at 2.02488 -1.75006)
			(size 1.54991 0.24994)
			(layers "F.Cu" "F.Mask" "F.Paste")
			(net "GPS2_TP2")
		)
		(pad "8" smd rect
			(at -2.02489 -1.75006)
			(size 1.54991 0.24994)
			(layers "F.Cu" "F.Mask" "F.Paste")
		)
		(pad "9" smd rect
			(at 2.02488 -2.24994)
			(size 1.54991 0.24994)
			(layers "F.Cu" "F.Mask" "F.Paste")
			(net "GND")
		)
		(pad "10" smd rect
			(at -2.02489 -2.24994)
			(size 1.54991 0.24994)
			(layers "F.Cu" "F.Mask" "F.Paste")
			(net "GND")
		)
		(pad "11" smd rect
			(at 2.02488 -2.75006)
			(size 1.54991 0.24994)
			(layers "F.Cu" "F.Mask" "F.Paste")
			(net "GPS2_RST")
		)
		(pad "12" smd rect
			(at -2.02489 -2.75006)
			(size 1.54991 0.24994)
			(layers "F.Cu" "F.Mask" "F.Paste")
			(net "IO_LED1")
		)
		(pad "13" smd rect
			(at 2.02488 -3.24993)
			(size 1.54991 0.24994)
			(layers "F.Cu" "F.Mask" "F.Paste")
		)
		(pad "14" smd rect
			(at -2.02489 -3.24993)
			(size 1.54991 0.24994)
			(layers "F.Cu" "F.Mask" "F.Paste")
			(net "IO_LED2")
		)
		(pad "15" smd rect
			(at 2.02488 -3.75006)
			(size 1.54991 0.24994)
			(layers "F.Cu" "F.Mask" "F.Paste")
		)
		(pad "16" smd rect
			(at -2.02489 -3.75006)
			(size 1.54991 0.24994)
			(layers "F.Cu" "F.Mask" "F.Paste")
			(net "IO_LED3")
		)
		(pad "17" smd rect
			(at 2.02488 -4.24993)
			(size 1.54991 0.24994)
			(layers "F.Cu" "F.Mask" "F.Paste")
		)
		(pad "18" smd rect
			(at -2.02489 -4.24993)
			(size 1.54991 0.24994)
			(layers "F.Cu" "F.Mask" "F.Paste")
			(net "IO_LED4")
		)
		(pad "19" smd rect
			(at 2.02488 -4.75006)
			(size 1.54991 0.24994)
			(layers "F.Cu" "F.Mask" "F.Paste")
			(net "GND")
		)
		(pad "20" smd rect
			(at -2.02489 -4.75006)
			(size 1.54991 0.24994)
			(layers "F.Cu" "F.Mask" "F.Paste")
			(net "GND")
		)
		(pad "21" smd rect
			(at 2.02488 -5.24993)
			(size 1.54991 0.24994)
			(layers "F.Cu" "F.Mask" "F.Paste")
			(net "PCIE_PERST")
		)
		(pad "22" smd rect
			(at -2.02489 -5.24993)
			(size 1.54991 0.24994)
			(layers "F.Cu" "F.Mask" "F.Paste")
		)
		(pad "23" smd rect
			(at 2.02488 -5.75006)
			(size 1.54991 0.24994)
			(layers "F.Cu" "F.Mask" "F.Paste")
			(net "KEY1")
		)
		(pad "24" smd rect
			(at -2.02489 -5.75006)
			(size 1.54991 0.24994)
			(layers "F.Cu" "F.Mask" "F.Paste")
		)
		(pad "25" smd rect
			(at 2.02488 -6.24993)
			(size 1.54991 0.24994)
			(layers "F.Cu" "F.Mask" "F.Paste")
		)
		(pad "26" smd rect
			(at -2.02489 -6.24993)
			(size 1.54991 0.24994)
			(layers "F.Cu" "F.Mask" "F.Paste")
		)
		(pad "27" smd rect
			(at 2.02488 -6.75005)
			(size 1.54991 0.24994)
			(layers "F.Cu" "F.Mask" "F.Paste")
		)
		(pad "28" smd rect
			(at -2.02489 -6.75005)
			(size 1.54991 0.24994)
			(layers "F.Cu" "F.Mask" "F.Paste")
		)
		(pad "29" smd rect
			(at 2.02488 -7.24993)
			(size 1.54991 0.24994)
			(layers "F.Cu" "F.Mask" "F.Paste")
			(net "GND")
		)
		(pad "30" smd rect
			(at -2.02489 -7.24993)
			(size 1.54991 0.24994)
			(layers "F.Cu" "F.Mask" "F.Paste")
			(net "GND")
		)
		(pad "31" smd rect
			(at 2.02488 -7.75005)
			(size 1.54991 0.24994)
			(layers "F.Cu" "F.Mask" "F.Paste")
			(net "ANT1_IO_OUT")
		)
		(pad "32" smd rect
			(at -2.02489 -7.75005)
			(size 1.54991 0.24994)
			(layers "F.Cu" "F.Mask" "F.Paste")
			(net "EXT_GPIO_7")
		)
		(pad "33" smd rect
			(at 2.02488 -8.24992)
			(size 1.54991 0.24994)
			(layers "F.Cu" "F.Mask" "F.Paste")
			(net "ANT1_IO_IN")
		)
		(pad "34" smd rect
			(at -2.02489 -8.24992)
			(size 1.54991 0.24994)
			(layers "F.Cu" "F.Mask" "F.Paste")
			(net "EXT_GPIO_8")
		)
		(pad "35" smd rect
			(at 2.02488 -8.75005)
			(size 1.54991 0.24994)
			(layers "F.Cu" "F.Mask" "F.Paste")
			(net "ANT2_IO_OUT")
		)
		(pad "36" smd rect
			(at -2.02489 -8.75005)
			(size 1.54991 0.24994)
			(layers "F.Cu" "F.Mask" "F.Paste")
			(net "EXT_GPIO_9")
		)
		(pad "37" smd rect
			(at 2.02488 -9.24992)
			(size 1.54991 0.24994)
			(layers "F.Cu" "F.Mask" "F.Paste")
			(net "ANT2_IO_IN")
		)
		(pad "38" smd rect
			(at -2.02489 -9.24992)
			(size 1.54991 0.24994)
			(layers "F.Cu" "F.Mask" "F.Paste")
			(net "EXT_GPIO_10")
		)
		(pad "39" smd rect
			(at 2.02488 -9.75005)
			(size 1.54991 0.24994)
			(layers "F.Cu" "F.Mask" "F.Paste")
			(net "GND")
		)
		(pad "40" smd rect
			(at -2.02489 -9.75005)
			(size 1.54991 0.24994)
			(layers "F.Cu" "F.Mask" "F.Paste")
			(net "GND")
		)
		(pad "41" smd rect
			(at 2.02488 -10.24992)
			(size 1.54991 0.24994)
			(layers "F.Cu" "F.Mask" "F.Paste")
			(net "ANT3_IO_OUT")
		)
		(pad "42" smd rect
			(at -2.02489 -10.24992)
			(size 1.54991 0.24994)
			(layers "F.Cu" "F.Mask" "F.Paste")
			(net "EXT_GPIO_1")
		)
		(pad "43" smd rect
			(at 2.02488 -10.75005)
			(size 1.54991 0.24994)
			(layers "F.Cu" "F.Mask" "F.Paste")
			(net "ANT3_IO_IN")
		)
		(pad "44" smd rect
			(at -2.02489 -10.75005)
			(size 1.54991 0.24994)
			(layers "F.Cu" "F.Mask" "F.Paste")
			(net "EXT_GPIO_2")
		)
		(pad "45" smd rect
			(at 2.02488 -11.24992)
			(size 1.54991 0.24994)
			(layers "F.Cu" "F.Mask" "F.Paste")
			(net "ANT4_IO_OUT")
		)
		(pad "46" smd rect
			(at -2.02489 -11.24992)
			(size 1.54991 0.24994)
			(layers "F.Cu" "F.Mask" "F.Paste")
			(net "EXT_GPIO_3")
		)
		(pad "47" smd rect
			(at 2.02488 -11.75004)
			(size 1.54991 0.24994)
			(layers "F.Cu" "F.Mask" "F.Paste")
			(net "ANT4_IO_IN")
		)
		(pad "48" smd rect
			(at -2.02489 -11.75004)
			(size 1.54991 0.24994)
			(layers "F.Cu" "F.Mask" "F.Paste")
			(net "EXT_GPIO_4")
		)
		(pad "49" smd rect
			(at 2.02488 -12.24992)
			(size 1.54991 0.24994)
			(layers "F.Cu" "F.Mask" "F.Paste")
			(net "GND")
		)
		(pad "50" smd rect
			(at -2.02489 -12.24992)
			(size 1.54991 0.24994)
			(layers "F.Cu" "F.Mask" "F.Paste")
			(net "GND")
		)
		(pad "51" smd rect
			(at 2.02488 -12.75004)
			(size 1.54991 0.24994)
			(layers "F.Cu" "F.Mask" "F.Paste")
		)
		(pad "52" smd rect
			(at -2.02489 -12.75004)
			(size 1.54991 0.24994)
			(layers "F.Cu" "F.Mask" "F.Paste")
		)
		(pad "53" smd rect
			(at 2.02488 -13.24991)
			(size 1.54991 0.24994)
			(layers "F.Cu" "F.Mask" "F.Paste")
		)
		(pad "54" smd rect
			(at -2.02489 -13.24991)
			(size 1.54991 0.24994)
			(layers "F.Cu" "F.Mask" "F.Paste")
		)
		(pad "55" smd rect
			(at 2.02488 -13.75004)
			(size 1.54991 0.24994)
			(layers "F.Cu" "F.Mask" "F.Paste")
		)
		(pad "56" smd rect
			(at -2.02489 -13.75004)
			(size 1.54991 0.24994)
			(layers "F.Cu" "F.Mask" "F.Paste")
		)
		(pad "57" smd rect
			(at 2.02488 -14.24991)
			(size 1.54991 0.24994)
			(layers "F.Cu" "F.Mask" "F.Paste")
		)
		(pad "58" smd rect
			(at -2.02489 -14.24991)
			(size 1.54991 0.24994)
			(layers "F.Cu" "F.Mask" "F.Paste")
		)
		(pad "59" smd rect
			(at 2.02488 -14.75004)
			(size 1.54991 0.24994)
			(layers "F.Cu" "F.Mask" "F.Paste")
			(net "GND")
		)
		(pad "60" smd rect
			(at -2.02489 -14.75004)
			(size 1.54991 0.24994)
			(layers "F.Cu" "F.Mask" "F.Paste")
			(net "GND")
		)
		(pad "61" smd rect
			(at 2.02488 -15.24991)
			(size 1.54991 0.24994)
			(layers "F.Cu" "F.Mask" "F.Paste")
		)
		(pad "62" smd rect
			(at -2.02489 -15.24991)
			(size 1.54991 0.24994)
			(layers "F.Cu" "F.Mask" "F.Paste")
		)
		(pad "63" smd rect
			(at 2.02488 -15.75004)
			(size 1.54991 0.24994)
			(layers "F.Cu" "F.Mask" "F.Paste")
		)
		(pad "64" smd rect
			(at -2.02489 -15.75004)
			(size 1.54991 0.24994)
			(layers "F.Cu" "F.Mask" "F.Paste")
		)
		(pad "65" smd rect
			(at 2.02488 -16.24991)
			(size 1.54991 0.24994)
			(layers "F.Cu" "F.Mask" "F.Paste")
		)
		(pad "66" smd rect
			(at -2.02489 -16.24991)
			(size 1.54991 0.24994)
			(layers "F.Cu" "F.Mask" "F.Paste")
		)
		(pad "67" smd rect
			(at 2.02488 -16.75003)
			(size 1.54991 0.24994)
			(layers "F.Cu" "F.Mask" "F.Paste")
		)
		(pad "68" smd rect
			(at -2.02489 -16.75003)
			(size 1.54991 0.24994)
			(layers "F.Cu" "F.Mask" "F.Paste")
		)
		(pad "69" smd rect
			(at 2.02488 -17.24991)
			(size 1.54991 0.24994)
			(layers "F.Cu" "F.Mask" "F.Paste")
			(net "GND")
		)
		(pad "70" smd rect
			(at -2.02489 -17.24991)
			(size 1.54991 0.24994)
			(layers "F.Cu" "F.Mask" "F.Paste")
			(net "GND")
		)
		(pad "71" smd rect
			(at 2.02488 -17.75003)
			(size 1.54991 0.24994)
			(layers "F.Cu" "F.Mask" "F.Paste")
		)
		(pad "72" smd rect
			(at -2.02489 -17.75003)
			(size 1.54991 0.24994)
			(layers "F.Cu" "F.Mask" "F.Paste")
		)
		(pad "73" smd rect
			(at 2.02488 -18.2499)
			(size 1.54991 0.24994)
			(layers "F.Cu" "F.Mask" "F.Paste")
		)
		(pad "74" smd rect
			(at -2.02489 -18.2499)
			(size 1.54991 0.24994)
			(layers "F.Cu" "F.Mask" "F.Paste")
		)
		(pad "75" smd rect
			(at 2.02488 -18.75003)
			(size 1.54991 0.24994)
			(layers "F.Cu" "F.Mask" "F.Paste")
		)
		(pad "76" smd rect
			(at -2.02489 -18.75003)
			(size 1.54991 0.24994)
			(layers "F.Cu" "F.Mask" "F.Paste")
		)
		(pad "77" smd rect
			(at 2.02488 -19.2499)
			(size 1.54991 0.24994)
			(layers "F.Cu" "F.Mask" "F.Paste")
			(net "FPGA_TCK")
		)
		(pad "78" smd rect
			(at -2.02489 -19.2499)
			(size 1.54991 0.24994)
			(layers "F.Cu" "F.Mask" "F.Paste")
			(net "FPGA_TDI")
		)
		(pad "79" smd rect
			(at 2.02488 -19.75003)
			(size 1.54991 0.24994)
			(layers "F.Cu" "F.Mask" "F.Paste")
			(net "FPGA_TDO")
		)
		(pad "80" smd rect
			(at -2.02489 -19.75003)
			(size 1.54991 0.24994)
			(layers "F.Cu" "F.Mask" "F.Paste")
			(net "FPGA_TMS")
		)
		(pad "81" smd rect
			(at 0.01135 1.17626)
			(size 1.70002 1.35001)
			(layers "F.Cu" "F.Mask" "F.Paste")
		)
		(pad "82" thru_hole circle
			(at 0 0)
			(size 0.55016 0.55016)
			(drill 0.55016)
			(layers "*.Cu" "*.Mask")
			(remove_unused_layers no)
			(thermal_bridge_angle 90)
		)
		(pad "83" thru_hole circle
			(at 0 -19.99996)
			(size 0.55016 0.55016)
			(drill 0.55016)
			(layers "*.Cu" "*.Mask")
			(remove_unused_layers no)
			(thermal_bridge_angle 90)
		)
		(pad "84" smd rect
			(at 0.01135 -21.17375)
			(size 1.70002 1.35001)
			(layers "F.Cu" "F.Mask" "F.Paste")
		)
	)
	(footprint "Vault:RESC1005X40X25NL10T10"
		(layer "F.Cu")
		(at 73.4216 114.7162)
		(property "Reference" "R30"
			(at -1 -0.906655 0)
			(unlocked yes)
			(layer "F.SilkS")
			(effects
				(font
					(size 0.762 0.762)
					(thickness 0.2286)
				)
				(justify left bottom)
			)
		)
		(property "Value" "4.7K_1%_0402"
			(at -0.4445 3.636645 0)
			(unlocked yes)
			(layer "F.SilkS")
			(hide yes)
			(effects
				(font
					(size 0.762 0.762)
					(thickness 0.2286)
				)
				(justify left bottom)
			)
		)
		(sheetname "01-USER_IO")
		(sheetfile "01-USER_IO.kicad_sch")
		(duplicate_pad_numbers_are_jumpers no)
		(pad "1" smd rect
			(at -0.425 0 90)
			(size 0.6 0.65)
			(layers "F.Cu" "F.Mask" "F.Paste")
			(net "+3.3V")
		)
		(pad "2" smd rect
			(at 0.425 0 90)
			(size 0.6 0.65)
			(layers "F.Cu" "F.Mask" "F.Paste")
			(net "ANT2_IO_IN")
		)
	)
	(footprint "Vault:RESC1005X40X25NL10T10"
		(layer "F.Cu")
		(at 170.3216 118.8162 -90)
		(property "Reference" "R119"
			(at 2.7032 0.242331 270)
			(unlocked yes)
			(layer "F.SilkS")
			(effects
				(font
					(size 0.762 0.762)
					(thickness 0.2032)
				)
			)
		)
		(property "Value" "4.7K_1%_0402"
			(at -2.732271 8.747465 180)
			(unlocked yes)
			(layer "F.SilkS")
			(hide yes)
			(effects
				(font
					(size 0.762 0.762)
					(thickness 0.2032)
				)
			)
		)
		(sheetname "08-DIPSwitches_I2C")
		(sheetfile "08-DIPSwitches_I2C.kicad_sch")
		(duplicate_pad_numbers_are_jumpers no)
		(pad "1" smd rect
			(at -0.425 0)
			(size 0.6 0.65)
			(layers "F.Cu" "F.Mask" "F.Paste")
			(net "MAC_I2C_SDA")
		)
		(pad "2" smd rect
			(at 0.425 0)
			(size 0.6 0.65)
			(layers "F.Cu" "F.Mask" "F.Paste")
			(net "+3.3V")
		)
	)
	(footprint "Vault:FP-T495D107K016ATE125-MFG"
		(layer "F.Cu")
		(at 87.5216 51.9162)
		(property "Reference" "C10"
			(at -4.406655 1.1 90)
			(unlocked yes)
			(layer "F.SilkS")
			(effects
				(font
					(size 0.762 0.762)
					(thickness 0.2286)
				)
				(justify left bottom)
			)
		)
		(property "Value" "100uF_16V_2917"
			(at -2.5927 16.320035 0)
			(unlocked yes)
			(layer "F.SilkS")
			(hide yes)
			(effects
				(font
					(size 0.762 0.762)
					(thickness 0.2286)
				)
				(justify left bottom)
			)
		)
		(sheetname "03-POWER")
		(sheetfile "03-POWER.kicad_sch")
		(duplicate_pad_numbers_are_jumpers no)
		(fp_line
			(start -3.8 -2.3)
			(end 3.8 -2.3)
			(stroke
				(width 0.2)
				(type solid)
			)
			(layer "F.SilkS")
		)
		(fp_line
			(start -3.8 -1.54)
			(end -3.8 -2.3)
			(stroke
				(width 0.2)
				(type solid)
			)
			(layer "F.SilkS")
		)
		(fp_line
			(start -3.8 2.3)
			(end -3.8 1.54)
			(stroke
				(width 0.2)
				(type solid)
			)
			(layer "F.SilkS")
		)
		(fp_line
			(start -3.8 2.3)
			(end 3.8 2.3)
			(stroke
				(width 0.2)
				(type solid)
			)
			(layer "F.SilkS")
		)
		(fp_line
			(start 3.8 -1.54)
			(end 3.8 -2.3)
			(stroke
				(width 0.2)
				(type solid)
			)
			(layer "F.SilkS")
		)
		(fp_line
			(start 3.8 2.3)
			(end 3.8 1.54)
			(stroke
				(width 0.2)
				(type solid)
			)
			(layer "F.SilkS")
		)
		(fp_line
			(start 4.4 0)
			(end 5 0)
			(stroke
				(width 0.2)
				(type solid)
			)
			(layer "F.SilkS")
		)
		(fp_line
			(start 4.7 0.3)
			(end 4.7 -0.3)
			(stroke
				(width 0.2)
				(type solid)
			)
			(layer "F.SilkS")
		)
		(fp_line
			(start -4.105 -2.4)
			(end 4.105 -2.4)
			(stroke
				(width 0.2)
				(type solid)
			)
			(layer "F.CrtYd")
		)
		(fp_line
			(start -4.105 2.4)
			(end -4.105 -2.4)
			(stroke
				(width 0.2)
				(type solid)
			)
			(layer "F.CrtYd")
		)
		(fp_line
			(start -4.105 2.4)
			(end 4.105 2.4)
			(stroke
				(width 0.2)
				(type solid)
			)
			(layer "F.CrtYd")
		)
		(fp_line
			(start 4.105 2.4)
			(end 4.105 -2.4)
			(stroke
				(width 0.2)
				(type solid)
			)
			(layer "F.CrtYd")
		)
		(fp_line
			(start -4.105 -2.4)
			(end 4.105 -2.4)
			(stroke
				(width 0.2)
				(type solid)
			)
			(layer "F.Fab")
		)
		(fp_line
			(start -4.105 2.4)
			(end -4.105 -2.4)
			(stroke
				(width 0.2)
				(type solid)
			)
			(layer "F.Fab")
		)
		(fp_line
			(start -4.105 2.4)
			(end 4.105 2.4)
			(stroke
				(width 0.2)
				(type solid)
			)
			(layer "F.Fab")
		)
		(fp_line
			(start -0.5 0)
			(end 0.5 0)
			(stroke
				(width 0.1)
				(type solid)
			)
			(layer "F.Fab")
		)
		(fp_line
			(start 0 0.5)
			(end 0 -0.5)
			(stroke
				(width 0.1)
				(type solid)
			)
			(layer "F.Fab")
		)
		(fp_line
			(start 4.105 2.4)
			(end 4.105 -2.4)
			(stroke
				(width 0.2)
				(type solid)
			)
			(layer "F.Fab")
		)
		(fp_text user "${REFERENCE}"
			(at 0 0.28425 360)
			(unlocked yes)
			(layer "F.Fab")
			(effects
				(font
					(face "Arial")
					(size 0.63 0.63)
					(thickness 0.1)
				)
				(justify left bottom)
			)
		)
		(pad "1" smd rect
			(at -3.01 0)
			(size 1.99 2.33)
			(layers "F.Cu" "F.Mask" "F.Paste")
			(net "GND")
			(solder_mask_margin 0)
			(solder_paste_margin 0)
		)
		(pad "2" smd rect
			(at 3.01 0)
			(size 1.99 2.33)
			(layers "F.Cu" "F.Mask" "F.Paste")
			(net "+12V")
			(solder_mask_margin 0)
			(solder_paste_margin 0)
		)
	)
	(footprint "Vault:RESC1005X40X25NL05T05"
		(layer "F.Cu")
		(at 154.0216 118.8162)
		(property "Reference" "R75"
			(at 0.5286 1.126921 0)
			(unlocked yes)
			(layer "F.SilkS")
			(effects
				(font
					(size 0.762 0.762)
					(thickness 0.2286)
				)
			)
		)
		(property "Value" "DNI_27_1%_0402"
			(at -2.732271 9.407655 270)
			(unlocked yes)
			(layer "F.SilkS")
			(hide yes)
			(effects
				(font
					(size 0.762 0.762)
					(thickness 0.2286)
				)
			)
		)
		(sheetname "08-DIPSwitches_I2C")
		(sheetfile "08-DIPSwitches_I2C.kicad_sch")
		(duplicate_pad_numbers_are_jumpers no)
		(pad "1" smd rect
			(at -0.45 0 90)
			(size 0.55 0.55)
			(layers "F.Cu" "F.Mask" "F.Paste")
			(net "MAC_FPGA_UART_RX")
		)
		(pad "2" smd rect
			(at 0.45 0 90)
			(size 0.55 0.55)
			(layers "F.Cu" "F.Mask" "F.Paste")
			(net "MAC_RX")
		)
	)
	(footprint "Vault:FP-C3216-160-0_2-MFG"
		(layer "F.Cu")
		(at 165.8216 83.5162 180)
		(property "Reference" "C78"
			(at 2.2714 1.173079 0)
			(unlocked yes)
			(layer "F.SilkS")
			(effects
				(font
					(size 0.762 0.762)
					(thickness 0.2286)
				)
			)
		)
		(property "Value" "47uF_16V_1206"
			(at -4.014951 8.77266 90)
			(unlocked yes)
			(layer "F.SilkS")
			(hide yes)
			(effects
				(font
					(size 0.762 0.762)
					(thickness 0.2286)
				)
			)
		)
		(sheetname "03-POWER")
		(sheetfile "03-POWER.kicad_sch")
		(duplicate_pad_numbers_are_jumpers no)
		(fp_line
			(start 0.725 0.9)
			(end -0.725 0.9)
			(stroke
				(width 0.2)
				(type solid)
			)
			(layer "F.SilkS")
		)
		(fp_line
			(start 0.725 -0.9)
			(end -0.725 -0.9)
			(stroke
				(width 0.2)
				(type solid)
			)
			(layer "F.SilkS")
		)
		(fp_line
			(start 2.3 1)
			(end -2.3 1)
			(stroke
				(width 0.2)
				(type solid)
			)
			(layer "F.CrtYd")
		)
		(fp_line
			(start 2.3 -1)
			(end 2.3 1)
			(stroke
				(width 0.2)
				(type solid)
			)
			(layer "F.CrtYd")
		)
		(fp_line
			(start 2.3 -1)
			(end -2.3 -1)
			(stroke
				(width 0.2)
				(type solid)
			)
			(layer "F.CrtYd")
		)
		(fp_line
			(start -2.3 -1)
			(end -2.3 1)
			(stroke
				(width 0.2)
				(type solid)
			)
			(layer "F.CrtYd")
		)
		(fp_line
			(start 2.3 1)
			(end -2.3 1)
			(stroke
				(width 0.2)
				(type solid)
			)
			(layer "F.Fab")
		)
		(fp_line
			(start 2.3 -1)
			(end 2.3 1)
			(stroke
				(width 0.2)
				(type solid)
			)
			(layer "F.Fab")
		)
		(fp_line
			(start 2.3 -1)
			(end -2.3 -1)
			(stroke
				(width 0.2)
				(type solid)
			)
			(layer "F.Fab")
		)
		(fp_line
			(start 0.5 0)
			(end -0.5 0)
			(stroke
				(width 0.1)
				(type solid)
			)
			(layer "F.Fab")
		)
		(fp_line
			(start 0 -0.5)
			(end 0 0.5)
			(stroke
				(width 0.1)
				(type solid)
			)
			(layer "F.Fab")
		)
		(fp_line
			(start -2.3 -1)
			(end -2.3 1)
			(stroke
				(width 0.2)
				(type solid)
			)
			(layer "F.Fab")
		)
		(fp_text user "${REFERENCE}"
			(at -0.00001 0.09601 180)
			(unlocked yes)
			(layer "F.Fab")
			(effects
				(font
					(face "Arial")
					(size 0.63 0.63)
					(thickness 0.1)
				)
				(justify left bottom)
			)
		)
		(pad "1" smd rect
			(at -1.65 0 180)
			(size 1.1 1.35)
			(layers "F.Cu" "F.Mask" "F.Paste")
			(net "+3.3V")
			(solder_mask_margin 0)
			(solder_paste_margin 0)
		)
		(pad "2" smd rect
			(at 1.65 0 180)
			(size 1.1 1.35)
			(layers "F.Cu" "F.Mask" "F.Paste")
			(net "GND")
			(solder_mask_margin 0)
			(solder_paste_margin 0)
		)
	)
	(footprint "Vault:RESC1005X40X25LL05T10"
		(layer "F.Cu")
		(at 144.7216 102.2162 -90)
		(property "Reference" "R98"
			(at -2.3286 0.173079 90)
			(unlocked yes)
			(layer "F.SilkS")
			(effects
				(font
					(size 0.762 0.762)
					(thickness 0.2286)
				)
			)
		)
		(property "Value" "49.9_1%_0402"
			(at -2.579871 8.823665 180)
			(unlocked yes)
			(layer "F.SilkS")
			(hide yes)
			(effects
				(font
					(size 0.762 0.762)
					(thickness 0.2286)
				)
			)
		)
		(sheetname "09-USBUart_PPSMUX_UARTMUX")
		(sheetfile "09-USBUart_PPSMUX_UARTMUX.kicad_sch")
		(duplicate_pad_numbers_are_jumpers no)
		(pad "1" smd rect
			(at -0.375 0)
			(size 0.45 0.5)
			(layers "F.Cu" "F.Mask" "F.Paste")
			(net "MAC_PPS_IN")
		)
		(pad "2" smd rect
			(at 0.375 0)
			(size 0.45 0.5)
			(layers "F.Cu" "F.Mask" "F.Paste")
			(net "NetR98_2")
		)
	)
	(footprint "Vault:RESC1005X40X25NL05T05"
		(layer "F.Cu")
		(at 157.5216 115.0162 180)
		(property "Reference" "R76"
			(at -2.9286 -0.126921 0)
			(unlocked yes)
			(layer "F.SilkS")
			(effects
				(font
					(size 0.762 0.762)
					(thickness 0.2286)
				)
			)
		)
		(property "Value" "27_1%_0402"
			(at -2.732271 9.53462 90)
			(unlocked yes)
			(layer "F.SilkS")
			(hide yes)
			(effects
				(font
					(size 0.762 0.762)
					(thickness 0.2286)
				)
			)
		)
		(sheetname "08-DIPSwitches_I2C")
		(sheetfile "08-DIPSwitches_I2C.kicad_sch")
		(duplicate_pad_numbers_are_jumpers no)
		(pad "1" smd rect
			(at -0.45 0 270)
			(size 0.55 0.55)
			(layers "F.Cu" "F.Mask" "F.Paste")
			(net "MAC_I2C_SCL")
		)
		(pad "2" smd rect
			(at 0.45 0 270)
			(size 0.55 0.55)
			(layers "F.Cu" "F.Mask" "F.Paste")
			(net "NetR76_2")
		)
	)
	(footprint "Resistors:RESC1005X04N"
		(layer "F.Cu")
		(at 105.8216 144.6162)
		(property "Reference" "R24"
			(at -3.3 0.693345 0)
			(unlocked yes)
			(layer "F.SilkS")
			(effects
				(font
					(size 0.762 0.762)
					(thickness 0.2286)
				)
				(justify left bottom)
			)
		)
		(property "Value" "ERJ-2GE0R00X"
			(at -0.2413 3.331845 0)
			(unlocked yes)
			(layer "F.SilkS")
			(hide yes)
			(effects
				(font
					(size 0.762 0.762)
					(thickness 0.2286)
				)
				(justify left bottom)
			)
		)
		(sheetname "04-PCIe_JTAG")
		(sheetfile "04-PCIe_JTAG.kicad_sch")
		(duplicate_pad_numbers_are_jumpers no)
		(pad "1" smd rect
			(at -0.425 0 90)
			(size 0.6 0.65)
			(layers "F.Cu" "F.Mask" "F.Paste")
			(net "PRSNT")
		)
		(pad "2" smd rect
			(at 0.425 0 90)
			(size 0.6 0.65)
			(layers "F.Cu" "F.Mask" "F.Paste")
			(net "NetP2_B31")
		)
	)
	(footprint "Vault:FP-C1005-050-0_05-IPC_A"
		(layer "F.Cu")
		(at 114.8216 81.0162 -90)
		(property "Reference" "C7"
			(at -0.5 -1.106655 270)
			(unlocked yes)
			(layer "F.SilkS")
			(effects
				(font
					(size 0.762 0.762)
					(thickness 0.2286)
				)
				(justify left bottom)
			)
		)
		(property "Value" "2.2uF_16V_0402"
			(at 12.037845 11.1911 0)
			(unlocked yes)
			(layer "F.SilkS")
			(hide yes)
			(effects
				(font
					(size 0.762 0.762)
					(thickness 0.2286)
				)
				(justify left bottom)
			)
		)
		(sheetname "05-GPS_IMU_SENSORS")
		(sheetfile "05-GPS_IMU_SENSORS.kicad_sch")
		(duplicate_pad_numbers_are_jumpers no)
		(fp_line
			(start 0.83624 0.73624)
			(end -0.83624 0.73624)
			(stroke
				(width 0.2)
				(type solid)
			)
			(layer "F.SilkS")
		)
		(fp_line
			(start 0.83624 -0.73624)
			(end -0.83624 -0.73624)
			(stroke
				(width 0.2)
				(type solid)
			)
			(layer "F.SilkS")
		)
		(fp_line
			(start -1.03624 0.53624)
			(end -1.03624 -0.53624)
			(stroke
				(width 0.2)
				(type solid)
			)
			(layer "F.CrtYd")
		)
		(fp_line
			(start 1.03623 0.53624)
			(end -1.03624 0.53624)
			(stroke
				(width 0.2)
				(type solid)
			)
			(layer "F.CrtYd")
		)
		(fp_line
			(start 1.03623 0.53624)
			(end 1.03623 -0.53624)
			(stroke
				(width 0.2)
				(type solid)
			)
			(layer "F.CrtYd")
		)
		(fp_line
			(start 1.03623 -0.53624)
			(end -1.03624 -0.53624)
			(stroke
				(width 0.2)
				(type solid)
			)
			(layer "F.CrtYd")
		)
		(fp_line
			(start -1.03624 0.53624)
			(end -1.03624 -0.53624)
			(stroke
				(width 0.2)
				(type solid)
			)
			(layer "F.Fab")
		)
		(fp_line
			(start 1.03623 0.53624)
			(end -1.03624 0.53624)
			(stroke
				(width 0.2)
				(type solid)
			)
			(layer "F.Fab")
		)
		(fp_line
			(start 1.03623 0.53624)
			(end 1.03623 -0.53624)
			(stroke
				(width 0.2)
				(type solid)
			)
			(layer "F.Fab")
		)
		(fp_line
			(start 0 0.5)
			(end 0 -0.5)
			(stroke
				(width 0.1)
				(type solid)
			)
			(layer "F.Fab")
		)
		(fp_line
			(start 0.5 0)
			(end -0.5 0)
			(stroke
				(width 0.1)
				(type solid)
			)
			(layer "F.Fab")
		)
		(fp_line
			(start 1.03623 -0.53624)
			(end -1.03624 -0.53624)
			(stroke
				(width 0.2)
				(type solid)
			)
			(layer "F.Fab")
		)
		(fp_text user "${REFERENCE}"
			(at -0.00001 0.09602 270)
			(unlocked yes)
			(layer "F.Fab")
			(effects
				(font
					(face "Arial")
					(size 0.63 0.63)
					(thickness 0.1)
				)
				(justify left bottom)
			)
		)
		(pad "1" smd rect
			(at -0.46658 0 270)
			(size 0.73933 0.67248)
			(layers "F.Cu" "F.Mask" "F.Paste")
			(net "+5.0V")
			(solder_mask_margin 0)
			(solder_paste_margin 0)
		)
		(pad "2" smd rect
			(at 0.46657 0 270)
			(size 0.73933 0.67248)
			(layers "F.Cu" "F.Mask" "F.Paste")
			(net "GND")
			(solder_mask_margin 0)
			(solder_paste_margin 0)
		)
	)
	(footprint "Vault:RESC1005X40X25NL05T05"
		(layer "F.Cu")
		(at 196.9216 133.9162)
		(property "Reference" "R151"
			(at 1.3175 -0.830389 0)
			(unlocked yes)
			(layer "F.SilkS")
			(effects
				(font
					(size 0.762 0.762)
					(thickness 0.2032)
				)
			)
		)
		(property "Value" "DNI_27_1%_0402"
			(at -2.732281 10.270975 270)
			(unlocked yes)
			(layer "F.SilkS")
			(hide yes)
			(effects
				(font
					(size 0.762 0.762)
					(thickness 0.2032)
				)
			)
		)
		(sheetname "11-M2_RCB_MUX")
		(sheetfile "11-M2_RCB_MUX.kicad_sch")
		(duplicate_pad_numbers_are_jumpers no)
		(pad "1" smd rect
			(at -0.45 0 90)
			(size 0.55 0.55)
			(layers "F.Cu" "F.Mask" "F.Paste")
			(net "RCB_GPS2_TP1")
		)
		(pad "2" smd rect
			(at 0.45 0 90)
			(size 0.55 0.55)
			(layers "F.Cu" "F.Mask" "F.Paste")
			(net "GPS2_TP1")
		)
	)
	(footprint "Connectors:PCIE_4LANE_EDGE"
		(layer "F.Cu")
		(at 127.02147 154.3547)
		(property "Reference" "P2"
			(at -12.64987 -0.282755 0)
			(unlocked yes)
			(layer "F.SilkS")
			(hide yes)
			(effects
				(font
					(size 0.762 0.762)
					(thickness 0.2286)
				)
				(justify left bottom)
			)
		)
		(property "Value" "PCIex4"
			(at -5.44907 18.557875 0)
			(unlocked yes)
			(layer "F.SilkS")
			(hide yes)
			(effects
				(font
					(size 0.762 0.762)
					(thickness 0.2286)
				)
				(justify left bottom)
			)
		)
		(sheetname "04-PCIe_JTAG")
		(sheetfile "04-PCIe_JTAG.kicad_sch")
		(duplicate_pad_numbers_are_jumpers no)
		(pad "A1" smd rect
			(at -16.49984 2.2286)
			(size 0.7112 3.2004)
			(layers "B.Cu" "B.Mask" "B.Paste")
			(net "PRSNT")
		)
		(pad "A2" smd rect
			(at -15.49985 2.7239)
			(size 0.7112 4.191)
			(layers "B.Cu" "B.Mask" "B.Paste")
			(net "+12V_PCIE")
		)
		(pad "A3" smd rect
			(at -14.49985 2.7239)
			(size 0.7112 4.191)
			(layers "B.Cu" "B.Mask" "B.Paste")
			(net "+12V_PCIE")
		)
		(pad "A4" smd rect
			(at -13.49985 2.7239)
			(size 0.7112 4.191)
			(layers "B.Cu" "B.Mask" "B.Paste")
			(net "GND")
		)
		(pad "A5" smd rect
			(at -12.49985 2.7239)
			(size 0.7112 4.191)
			(layers "B.Cu" "B.Mask" "B.Paste")
		)
		(pad "A6" smd rect
			(at -11.49985 2.7239)
			(size 0.7112 4.191)
			(layers "B.Cu" "B.Mask" "B.Paste")
		)
		(pad "A7" smd rect
			(at -10.49986 2.7239)
			(size 0.7112 4.191)
			(layers "B.Cu" "B.Mask" "B.Paste")
		)
		(pad "A8" smd rect
			(at -9.49986 2.7239)
			(size 0.7112 4.191)
			(layers "B.Cu" "B.Mask" "B.Paste")
		)
		(pad "A9" smd rect
			(at -8.49986 2.7239)
			(size 0.7112 4.191)
			(layers "B.Cu" "B.Mask" "B.Paste")
			(net "+3.3V_PCIE")
		)
		(pad "A10" smd rect
			(at -7.49986 2.7239)
			(size 0.7112 4.191)
			(layers "B.Cu" "B.Mask" "B.Paste")
			(net "+3.3V_PCIE")
		)
		(pad "A11" smd rect
			(at -6.49986 2.7239)
			(size 0.7112 4.191)
			(layers "B.Cu" "B.Mask" "B.Paste")
			(net "PCIE_PERST")
		)
		(pad "A12" smd rect
			(at -3.49987 2.7239)
			(size 0.7112 4.191)
			(layers "B.Cu" "B.Mask" "B.Paste")
			(net "GND")
		)
		(pad "A13" smd rect
			(at -2.49987 2.7239)
			(size 0.7112 4.191)
			(layers "B.Cu" "B.Mask" "B.Paste")
			(net "NetC44_1")
		)
		(pad "A14" smd rect
			(at -1.49987 2.7239)
			(size 0.7112 4.191)
			(layers "B.Cu" "B.Mask" "B.Paste")
			(net "NetC45_1")
		)
		(pad "A15" smd rect
			(at -0.49988 2.7239)
			(size 0.7112 4.191)
			(layers "B.Cu" "B.Mask" "B.Paste")
			(net "GND")
		)
		(pad "A16" smd rect
			(at 0.50012 2.7239)
			(size 0.7112 4.191)
			(layers "B.Cu" "B.Mask" "B.Paste")
			(net "NetC46_1")
		)
		(pad "A17" smd rect
			(at 1.50012 2.7239)
			(size 0.7112 4.191)
			(layers "B.Cu" "B.Mask" "B.Paste")
			(net "NetC47_1")
		)
		(pad "A18" smd rect
			(at 2.50012 2.7239)
			(size 0.7112 4.191)
			(layers "B.Cu" "B.Mask" "B.Paste")
			(net "GND")
		)
		(pad "A19" smd rect
			(at 3.50012 2.7239)
			(size 0.7112 4.191)
			(layers "B.Cu" "B.Mask" "B.Paste")
		)
		(pad "A20" smd rect
			(at 4.50011 2.7239)
			(size 0.7112 4.191)
			(layers "B.Cu" "B.Mask" "B.Paste")
			(net "GND")
		)
		(pad "A21" smd rect
			(at 5.50011 2.7239)
			(size 0.7112 4.191)
			(layers "B.Cu" "B.Mask" "B.Paste")
			(net "NetC48_1")
		)
		(pad "A22" smd rect
			(at 6.50011 2.7239)
			(size 0.7112 4.191)
			(layers "B.Cu" "B.Mask" "B.Paste")
			(net "NetC49_1")
		)
		(pad "A23" smd rect
			(at 7.50011 2.7239)
			(size 0.7112 4.191)
			(layers "B.Cu" "B.Mask" "B.Paste")
			(net "GND")
		)
		(pad "A24" smd rect
			(at 8.50011 2.7239)
			(size 0.7112 4.191)
			(layers "B.Cu" "B.Mask" "B.Paste")
			(net "GND")
		)
		(pad "A25" smd rect
			(at 9.5001 2.7239)
			(size 0.7112 4.191)
			(layers "B.Cu" "B.Mask" "B.Paste")
			(net "NetC50_1")
		)
		(pad "A26" smd rect
			(at 10.5001 2.7239)
			(size 0.7112 4.191)
			(layers "B.Cu" "B.Mask" "B.Paste")
			(net "NetC51_1")
		)
		(pad "A27" smd rect
			(at 11.5001 2.7239)
			(size 0.7112 4.191)
			(layers "B.Cu" "B.Mask" "B.Paste")
			(net "GND")
		)
		(pad "A28" smd rect
			(at 12.5001 2.7239)
			(size 0.7112 4.191)
			(layers "B.Cu" "B.Mask" "B.Paste")
			(net "GND")
		)
		(pad "A29" smd rect
			(at 13.5001 2.7239)
			(size 0.7112 4.191)
			(layers "B.Cu" "B.Mask" "B.Paste")
			(net "NetC52_1")
		)
		(pad "A30" smd rect
			(at 14.50009 2.7239)
			(size 0.7112 4.191)
			(layers "B.Cu" "B.Mask" "B.Paste")
			(net "NetC53_1")
		)
		(pad "A31" smd rect
			(at 15.50009 2.7239)
			(size 0.7112 4.191)
			(layers "B.Cu" "B.Mask" "B.Paste")
			(net "GND")
		)
		(pad "A32" smd rect
			(at 16.50009 2.7239)
			(size 0.7112 4.191)
			(layers "B.Cu" "B.Mask" "B.Paste")
		)
		(pad "B1" smd rect
			(at -16.49984 2.7239)
			(size 0.7112 4.191)
			(layers "F.Cu" "F.Mask" "F.Paste")
			(net "+12V_PCIE")
		)
		(pad "B2" smd rect
			(at -15.49985 2.7239)
			(size 0.7112 4.191)
			(layers "F.Cu" "F.Mask" "F.Paste")
			(net "+12V_PCIE")
		)
		(pad "B3" smd rect
			(at -14.49985 2.7239)
			(size 0.7112 4.191)
			(layers "F.Cu" "F.Mask" "F.Paste")
			(net "+12V_PCIE")
		)
		(pad "B4" smd rect
			(at -13.49985 2.7239)
			(size 0.7112 4.191)
			(layers "F.Cu" "F.Mask" "F.Paste")
			(net "GND")
		)
		(pad "B5" smd rect
			(at -12.49985 2.7239)
			(size 0.7112 4.191)
			(layers "F.Cu" "F.Mask" "F.Paste")
		)
		(pad "B6" smd rect
			(at -11.49985 2.7239)
			(size 0.7112 4.191)
			(layers "F.Cu" "F.Mask" "F.Paste")
		)
		(pad "B7" smd rect
			(at -10.49986 2.7239)
			(size 0.7112 4.191)
			(layers "F.Cu" "F.Mask" "F.Paste")
			(net "GND")
		)
		(pad "B8" smd rect
			(at -9.49986 2.7239)
			(size 0.7112 4.191)
			(layers "F.Cu" "F.Mask" "F.Paste")
			(net "+3.3V_PCIE")
		)
		(pad "B9" smd rect
			(at -8.49986 2.7239)
			(size 0.7112 4.191)
			(layers "F.Cu" "F.Mask" "F.Paste")
		)
		(pad "B10" smd rect
			(at -7.49986 2.7239)
			(size 0.7112 4.191)
			(layers "F.Cu" "F.Mask" "F.Paste")
		)
		(pad "B11" smd rect
			(at -6.49986 2.7239)
			(size 0.7112 4.191)
			(layers "F.Cu" "F.Mask" "F.Paste")
		)
		(pad "B12" smd rect
			(at -3.49987 2.7239)
			(size 0.7112 4.191)
			(layers "F.Cu" "F.Mask" "F.Paste")
		)
		(pad "B13" smd rect
			(at -2.49987 2.7239)
			(size 0.7112 4.191)
			(layers "F.Cu" "F.Mask" "F.Paste")
			(net "GND")
		)
		(pad "B14" smd rect
			(at -1.49987 2.7239)
			(size 0.7112 4.191)
			(layers "F.Cu" "F.Mask" "F.Paste")
			(net "PCIE_RX0_P")
		)
		(pad "B15" smd rect
			(at -0.49988 2.7239)
			(size 0.7112 4.191)
			(layers "F.Cu" "F.Mask" "F.Paste")
			(net "PCIE_RX0_N")
		)
		(pad "B16" smd rect
			(at 0.50012 2.7239)
			(size 0.7112 4.191)
			(layers "F.Cu" "F.Mask" "F.Paste")
			(net "GND")
		)
		(pad "B17" smd rect
			(at 1.50012 2.7239)
			(size 0.7112 4.191)
			(layers "F.Cu" "F.Mask" "F.Paste")
			(net "NetP2_B17")
		)
		(pad "B18" smd rect
			(at 2.50012 2.7239)
			(size 0.7112 4.191)
			(layers "F.Cu" "F.Mask" "F.Paste")
			(net "GND")
		)
		(pad "B19" smd rect
			(at 3.50012 2.7239)
			(size 0.7112 4.191)
			(layers "F.Cu" "F.Mask" "F.Paste")
			(net "PCIE_RX1_P")
		)
		(pad "B20" smd rect
			(at 4.50011 2.7239)
			(size 0.7112 4.191)
			(layers "F.Cu" "F.Mask" "F.Paste")
			(net "PCIE_RX1_N")
		)
		(pad "B21" smd rect
			(at 5.50011 2.7239)
			(size 0.7112 4.191)
			(layers "F.Cu" "F.Mask" "F.Paste")
			(net "GND")
		)
		(pad "B22" smd rect
			(at 6.50011 2.7239)
			(size 0.7112 4.191)
			(layers "F.Cu" "F.Mask" "F.Paste")
			(net "GND")
		)
		(pad "B23" smd rect
			(at 7.50011 2.7239)
			(size 0.7112 4.191)
			(layers "F.Cu" "F.Mask" "F.Paste")
			(net "PCIE_RX2_P")
		)
		(pad "B24" smd rect
			(at 8.50011 2.7239)
			(size 0.7112 4.191)
			(layers "F.Cu" "F.Mask" "F.Paste")
			(net "PCIE_RX2_N")
		)
		(pad "B25" smd rect
			(at 9.5001 2.7239)
			(size 0.7112 4.191)
			(layers "F.Cu" "F.Mask" "F.Paste")
			(net "GND")
		)
		(pad "B26" smd rect
			(at 10.5001 2.7239)
			(size 0.7112 4.191)
			(layers "F.Cu" "F.Mask" "F.Paste")
			(net "GND")
		)
		(pad "B27" smd rect
			(at 11.5001 2.7239)
			(size 0.7112 4.191)
			(layers "F.Cu" "F.Mask" "F.Paste")
			(net "PCIE_RX3_P")
		)
		(pad "B28" smd rect
			(at 12.5001 2.7239)
			(size 0.7112 4.191)
			(layers "F.Cu" "F.Mask" "F.Paste")
			(net "PCIE_RX3_N")
		)
		(pad "B29" smd rect
			(at 13.5001 2.7239)
			(size 0.7112 4.191)
			(layers "F.Cu" "F.Mask" "F.Paste")
			(net "GND")
		)
		(pad "B30" smd rect
			(at 14.50009 2.7239)
			(size 0.7112 4.191)
			(layers "F.Cu" "F.Mask" "F.Paste")
		)
		(pad "B31" smd rect
			(at 15.50009 2.2286)
			(size 0.7112 3.2004)
			(layers "F.Cu" "F.Mask" "F.Paste")
			(net "NetP2_B31")
		)
		(pad "B32" smd rect
			(at 16.50009 2.7239)
			(size 0.7112 4.191)
			(layers "F.Cu" "F.Mask" "F.Paste")
			(net "GND")
		)
	)
	(footprint "Vault:FP-BLM18-0_15-t0_8-IPC_A"
		(layer "F.Cu")
		(at 225.1216 131.3162)
		(property "Reference" "FB1"
			(at -3.271395 0.126921 0)
			(unlocked yes)
			(layer "F.SilkS")
			(effects
				(font
					(size 0.762 0.762)
					(thickness 0.2286)
				)
			)
		)
		(property "Value" "600ohm_1.3A_0603"
			(at 10.14352 2.744951 0)
			(unlocked yes)
			(layer "F.SilkS")
			(hide yes)
			(effects
				(font
					(size 0.762 0.762)
					(thickness 0.2286)
				)
			)
		)
		(sheetname "09-USBUart_PPSMUX_UARTMUX")
		(sheetfile "09-USBUart_PPSMUX_UARTMUX.kicad_sch")
		(duplicate_pad_numbers_are_jumpers no)
		(fp_line
			(start -1.42911 -0.92911)
			(end 1.42911 -0.92911)
			(stroke
				(width 0.2)
				(type solid)
			)
			(layer "F.SilkS")
		)
		(fp_line
			(start -1.42911 0.92911)
			(end 1.42911 0.92911)
			(stroke
				(width 0.2)
				(type solid)
			)
			(layer "F.SilkS")
		)
		(fp_line
			(start -1.92911 -1.02911)
			(end 1.92911 -1.02911)
			(stroke
				(width 0.2)
				(type solid)
			)
			(layer "F.CrtYd")
		)
		(fp_line
			(start -1.92911 1.02911)
			(end -1.92911 -1.02911)
			(stroke
				(width 0.2)
				(type solid)
			)
			(layer "F.CrtYd")
		)
		(fp_line
			(start -1.92911 1.02911)
			(end 1.92911 1.02911)
			(stroke
				(width 0.2)
				(type solid)
			)
			(layer "F.CrtYd")
		)
		(fp_line
			(start 1.92911 1.02911)
			(end 1.92911 -1.02911)
			(stroke
				(width 0.2)
				(type solid)
			)
			(layer "F.CrtYd")
		)
		(fp_line
			(start -1.92911 -1.02911)
			(end 1.92911 -1.02911)
			(stroke
				(width 0.2)
				(type solid)
			)
			(layer "F.Fab")
		)
		(fp_line
			(start -1.92911 1.02911)
			(end -1.92911 -1.02911)
			(stroke
				(width 0.2)
				(type solid)
			)
			(layer "F.Fab")
		)
		(fp_line
			(start -1.92911 1.02911)
			(end 1.92911 1.02911)
			(stroke
				(width 0.2)
				(type solid)
			)
			(layer "F.Fab")
		)
		(fp_line
			(start -0.5 0)
			(end 0.5 0)
			(stroke
				(width 0.1)
				(type solid)
			)
			(layer "F.Fab")
		)
		(fp_line
			(start 0 0.5)
			(end 0 -0.5)
			(stroke
				(width 0.1)
				(type solid)
			)
			(layer "F.Fab")
		)
		(fp_line
			(start 1.92911 1.02911)
			(end 1.92911 -1.02911)
			(stroke
				(width 0.2)
				(type solid)
			)
			(layer "F.Fab")
		)
		(fp_text user "${REFERENCE}"
			(at -0.00001 0.10711 360)
			(unlocked yes)
			(layer "F.Fab")
			(effects
				(font
					(face "Arial")
					(size 0.63 0.63)
					(thickness 0.1)
				)
				(justify left bottom)
			)
		)
		(pad "1" smd rect
			(at -0.77608 0)
			(size 1.30606 1.05822)
			(layers "F.Cu" "F.Mask" "F.Paste")
			(net "USB_VBUS")
			(solder_mask_margin 0)
			(solder_paste_margin 0)
		)
		(pad "2" smd rect
			(at 0.77608 0)
			(size 1.30606 1.05822)
			(layers "F.Cu" "F.Mask" "F.Paste")
			(net "FTDI_VBUS")
			(solder_mask_margin 0)
			(solder_paste_margin 0)
		)
	)
	(footprint "Vault:RESC1005X40X25LL05T05"
		(layer "F.Cu")
		(at 211.9216 131.5162 180)
		(property "Reference" "R139"
			(at -5.2032 -0.126921 0)
			(unlocked yes)
			(layer "F.SilkS")
			(effects
				(font
					(size 0.762 0.762)
					(thickness 0.2032)
				)
			)
		)
		(property "Value" "0_1%_0402"
			(at -2.579871 6.63996 90)
			(unlocked yes)
			(layer "F.SilkS")
			(hide yes)
			(effects
				(font
					(size 0.762 0.762)
					(thickness 0.2032)
				)
			)
		)
		(sheetname "10-M2_GPS")
		(sheetfile "10-M2_GPS.kicad_sch")
		(duplicate_pad_numbers_are_jumpers no)
		(pad "1" smd rect
			(at -0.4 0 270)
			(size 0.45 0.45)
			(layers "F.Cu" "F.Mask" "F.Paste")
			(net "NetJ45_46")
		)
		(pad "2" smd rect
			(at 0.4 0 270)
			(size 0.45 0.45)
			(layers "F.Cu" "F.Mask" "F.Paste")
			(net "M2_GPS2_TP1")
		)
	)
	(footprint "Vault:RESC1005X40X25NL10T10"
		(layer "F.Cu")
		(at 78.4216 104.0162)
		(property "Reference" "R14"
			(at 0.6286 1.026921 0)
			(unlocked yes)
			(layer "F.SilkS")
			(effects
				(font
					(size 0.762 0.762)
					(thickness 0.2286)
				)
			)
		)
		(property "Value" "4.7K_1%_0402"
			(at 7.110135 5.008471 0)
			(unlocked yes)
			(layer "F.SilkS")
			(hide yes)
			(effects
				(font
					(size 0.762 0.762)
					(thickness 0.2286)
				)
			)
		)
		(sheetname "01-USER_IO")
		(sheetfile "01-USER_IO.kicad_sch")
		(duplicate_pad_numbers_are_jumpers no)
		(pad "1" smd rect
			(at -0.425 0 90)
			(size 0.6 0.65)
			(layers "F.Cu" "F.Mask" "F.Paste")
			(net "+3.3V")
		)
		(pad "2" smd rect
			(at 0.425 0 90)
			(size 0.6 0.65)
			(layers "F.Cu" "F.Mask" "F.Paste")
			(net "ANT1_IO_OUT")
		)
	)
	(footprint "Vault:RESC1005X40X25NL05T05"
		(layer "F.Cu")
		(at 113.4216 58.0162 -90)
		(property "Reference" "R159"
			(at 2.5032 -0.173069 270)
			(unlocked yes)
			(layer "F.SilkS")
			(effects
				(font
					(size 0.762 0.762)
					(thickness 0.2032)
				)
			)
		)
		(property "Value" "DNI_27_1%_0402"
			(at -2.732271 10.270975 180)
			(unlocked yes)
			(layer "F.SilkS")
			(hide yes)
			(effects
				(font
					(size 0.762 0.762)
					(thickness 0.2032)
				)
			)
		)
		(sheetname "11-M2_RCB_MUX")
		(sheetfile "11-M2_RCB_MUX.kicad_sch")
		(duplicate_pad_numbers_are_jumpers no)
		(pad "1" smd rect
			(at -0.45 0)
			(size 0.55 0.55)
			(layers "F.Cu" "F.Mask" "F.Paste")
			(net "RCB_GPS1_TP1")
		)
		(pad "2" smd rect
			(at 0.45 0)
			(size 0.55 0.55)
			(layers "F.Cu" "F.Mask" "F.Paste")
			(net "GPS1_TP1")
		)
	)
	(footprint "Vault:FP-ERJ2RK-IPC_A"
		(layer "F.Cu")
		(at 96.32159 80.4162)
		(property "Reference" "R1"
			(at -3.09999 0.493345 0)
			(unlocked yes)
			(layer "F.SilkS")
			(effects
				(font
					(size 0.762 0.762)
					(thickness 0.2286)
				)
				(justify left bottom)
			)
		)
		(property "Value" "200_1%_0402"
			(at -17.19089 9.390245 0)
			(unlocked yes)
			(layer "F.SilkS")
			(hide yes)
			(effects
				(font
					(size 0.762 0.762)
					(thickness 0.2286)
				)
				(justify left bottom)
			)
		)
		(sheetname "03-POWER")
		(sheetfile "03-POWER.kicad_sch")
		(duplicate_pad_numbers_are_jumpers no)
		(fp_line
			(start -0.83623 -0.73624)
			(end 0.83624 -0.73624)
			(stroke
				(width 0.2)
				(type solid)
			)
			(layer "F.SilkS")
		)
		(fp_line
			(start -0.83623 0.73624)
			(end 0.83624 0.73624)
			(stroke
				(width 0.2)
				(type solid)
			)
			(layer "F.SilkS")
		)
		(fp_line
			(start -1.03623 -0.53624)
			(end 1.03624 -0.53624)
			(stroke
				(width 0.2)
				(type solid)
			)
			(layer "F.CrtYd")
		)
		(fp_line
			(start -1.03623 0.53624)
			(end -1.03623 -0.53624)
			(stroke
				(width 0.2)
				(type solid)
			)
			(layer "F.CrtYd")
		)
		(fp_line
			(start -1.03623 0.53624)
			(end 1.03624 0.53624)
			(stroke
				(width 0.2)
				(type solid)
			)
			(layer "F.CrtYd")
		)
		(fp_line
			(start 1.03624 0.53624)
			(end 1.03624 -0.53624)
			(stroke
				(width 0.2)
				(type solid)
			)
			(layer "F.CrtYd")
		)
		(fp_line
			(start -1.03623 -0.53624)
			(end 1.03624 -0.53624)
			(stroke
				(width 0.2)
				(type solid)
			)
			(layer "F.Fab")
		)
		(fp_line
			(start -1.03623 0.53624)
			(end -1.03623 -0.53624)
			(stroke
				(width 0.2)
				(type solid)
			)
			(layer "F.Fab")
		)
		(fp_line
			(start -1.03623 0.53624)
			(end 1.03624 0.53624)
			(stroke
				(width 0.2)
				(type solid)
			)
			(layer "F.Fab")
		)
		(fp_line
			(start -0.5 0)
			(end 0.5 0)
			(stroke
				(width 0.1)
				(type solid)
			)
			(layer "F.Fab")
		)
		(fp_line
			(start 0 0.5)
			(end 0 -0.5)
			(stroke
				(width 0.1)
				(type solid)
			)
			(layer "F.Fab")
		)
		(fp_line
			(start 1.03624 0.53624)
			(end 1.03624 -0.53624)
			(stroke
				(width 0.2)
				(type solid)
			)
			(layer "F.Fab")
		)
		(fp_text user "${REFERENCE}"
			(at -0.00001 0.10711 360)
			(unlocked yes)
			(layer "F.Fab")
			(effects
				(font
					(face "Arial")
					(size 0.63 0.63)
					(thickness 0.1)
				)
				(justify left bottom)
			)
		)
		(pad "1" smd rect
			(at -0.50214 0)
			(size 0.66818 0.67248)
			(layers "F.Cu" "F.Mask" "F.Paste")
			(net "GND")
			(solder_mask_margin 0)
			(solder_paste_margin 0)
		)
		(pad "2" smd rect
			(at 0.50215 0)
			(size 0.66818 0.67248)
			(layers "F.Cu" "F.Mask" "F.Paste")
			(net "NetD4_1")
			(solder_mask_margin 0)
			(solder_paste_margin 0)
		)
	)
	(footprint "Vault:RESC1005X40X25NL05T05"
		(layer "F.Cu")
		(at 156.7216 127.3162 -90)
		(property "Reference" "R85"
			(at -2.0714 0.026931 270)
			(unlocked yes)
			(layer "F.SilkS")
			(effects
				(font
					(size 0.762 0.762)
					(thickness 0.2286)
				)
			)
		)
		(property "Value" "27_1%_0402"
			(at -2.732271 7.37632 180)
			(unlocked yes)
			(layer "F.SilkS")
			(hide yes)
			(effects
				(font
					(size 0.762 0.762)
					(thickness 0.2286)
				)
			)
		)
		(sheetname "09-USBUart_PPSMUX_UARTMUX")
		(sheetfile "09-USBUart_PPSMUX_UARTMUX.kicad_sch")
		(duplicate_pad_numbers_are_jumpers no)
		(pad "1" smd rect
			(at -0.45 0)
			(size 0.55 0.55)
			(layers "F.Cu" "F.Mask" "F.Paste")
			(net "FTDI_RX")
		)
		(pad "2" smd rect
			(at 0.45 0)
			(size 0.55 0.55)
			(layers "F.Cu" "F.Mask" "F.Paste")
			(net "NetR85_2")
		)
	)
	(footprint "MUN12AD06-SM:MUN12AD06-SM_CYN"
		(layer "F.Cu")
		(at 97.6632 58.6162 -90)
		(property "Reference" "U1"
			(at 2.003195 -4.731469 270)
			(unlocked yes)
			(layer "F.SilkS")
			(effects
				(font
					(size 0.762 0.762)
					(thickness 0.2032)
				)
			)
		)
		(property "Value" "MUN12AD06-SM"
			(at 5.027635 -0.734819 270)
			(unlocked yes)
			(layer "F.SilkS")
			(hide yes)
			(effects
				(font
					(size 0.762 0.762)
					(thickness 0.2032)
				)
			)
		)
		(sheetname "03-POWER")
		(sheetfile "03-POWER.kicad_sch")
		(duplicate_pad_numbers_are_jumpers no)
		(fp_line
			(start -3.1242 3.1242)
			(end -3.1242 2.00688)
			(stroke
				(width 0.1524)
				(type solid)
			)
			(layer "F.SilkS")
		)
		(fp_line
			(start -2.00688 3.1242)
			(end -3.1242 3.1242)
			(stroke
				(width 0.1524)
				(type solid)
			)
			(layer "F.SilkS")
		)
		(fp_line
			(start 3.1242 3.1242)
			(end 2.00688 3.1242)
			(stroke
				(width 0.1524)
				(type solid)
			)
			(layer "F.SilkS")
		)
		(fp_line
			(start 3.1242 3.1242)
			(end 3.1242 2.00688)
			(stroke
				(width 0.1524)
				(type solid)
			)
			(layer "F.SilkS")
		)
		(fp_line
			(start -3.1242 -2.00688)
			(end -3.1242 -3.1242)
			(stroke
				(width 0.1524)
				(type solid)
			)
			(layer "F.SilkS")
		)
		(fp_line
			(start 3.1242 -2.00688)
			(end 3.1242 -3.1242)
			(stroke
				(width 0.1524)
				(type solid)
			)
			(layer "F.SilkS")
		)
		(fp_line
			(start -2.00688 -3.1242)
			(end -3.1242 -3.1242)
			(stroke
				(width 0.1524)
				(type solid)
			)
			(layer "F.SilkS")
		)
		(fp_line
			(start 3.1242 -3.1242)
			(end 2.00688 -3.1242)
			(stroke
				(width 0.1524)
				(type solid)
			)
			(layer "F.SilkS")
		)
		(fp_poly
			(pts
				(xy 1.7905 3.1496) (xy 1.4095 3.1496) (xy 1.4095 3.4036) (xy 1.7905 3.4036)
			)
			(stroke
				(width 0)
				(type default)
			)
			(fill yes)
			(layer "F.SilkS")
		)
		(fp_poly
			(pts
				(xy -1.4095 -3.1496) (xy -1.7905 -3.1496) (xy -1.7905 -3.4036) (xy -1.4095 -3.4036)
			)
			(stroke
				(width 0)
				(type default)
			)
			(fill yes)
			(layer "F.SilkS")
		)
		(fp_text user "*"
			(at 1.2 -1.344425 270)
			(unlocked yes)
			(layer "F.SilkS")
			(effects
				(font
					(size 1.27 1.27)
					(thickness 0.0762)
				)
				(justify left bottom)
			)
		)
		(pad "1" smd rect
			(at -2.6416 -1.6 180)
			(size 0.3302 0.508)
			(layers "F.Cu" "F.Mask" "F.Paste")
			(net "+12V")
			(solder_mask_margin 0)
			(solder_paste_margin 0)
		)
		(pad "2" smd rect
			(at -2.6416 -0.8 180)
			(size 0.3302 0.508)
			(layers "F.Cu" "F.Mask" "F.Paste")
			(net "P5V_MUN_PHASE")
			(solder_mask_margin 0)
			(solder_paste_margin 0)
		)
		(pad "3" smd rect
			(at -2.6416 0 180)
			(size 0.3302 0.508)
			(layers "F.Cu" "F.Mask" "F.Paste")
			(net "P5V_MUN_PHASE")
			(solder_mask_margin 0)
			(solder_paste_margin 0)
		)
		(pad "4" smd rect
			(at -2.6416 0.8 180)
			(size 0.3302 0.508)
			(layers "F.Cu" "F.Mask" "F.Paste")
			(net "P5V_MUN_PHASE")
			(solder_mask_margin 0)
			(solder_paste_margin 0)
		)
		(pad "5" smd rect
			(at -2.6416 1.6 180)
			(size 0.3302 0.508)
			(layers "F.Cu" "F.Mask" "F.Paste")
			(net "GND")
			(solder_mask_margin 0)
			(solder_paste_margin 0)
		)
		(pad "6" smd rect
			(at -1.6 2.6416 90)
			(size 0.3302 0.508)
			(layers "F.Cu" "F.Mask" "F.Paste")
			(net "GND")
			(solder_mask_margin 0)
			(solder_paste_margin 0)
		)
		(pad "7" smd rect
			(at -0.8 2.6416 90)
			(size 0.3302 0.508)
			(layers "F.Cu" "F.Mask" "F.Paste")
			(net "GND")
			(solder_mask_margin 0)
			(solder_paste_margin 0)
		)
		(pad "8" smd rect
			(at 0 2.6416 90)
			(size 0.3302 0.508)
			(layers "F.Cu" "F.Mask" "F.Paste")
			(net "NetR4_2")
			(solder_mask_margin 0)
			(solder_paste_margin 0)
		)
		(pad "9" smd rect
			(at 0.8 2.6416 90)
			(size 0.3302 0.508)
			(layers "F.Cu" "F.Mask" "F.Paste")
			(net "NetR5_1")
			(solder_mask_margin 0)
			(solder_paste_margin 0)
		)
		(pad "10" smd rect
			(at 1.6 2.6416 90)
			(size 0.3302 0.508)
			(layers "F.Cu" "F.Mask" "F.Paste")
			(net "P5V_SENSE")
			(solder_mask_margin 0)
			(solder_paste_margin 0)
		)
		(pad "11" smd rect
			(at 2.6416 1.6 180)
			(size 0.3302 0.508)
			(layers "F.Cu" "F.Mask" "F.Paste")
			(net "P5V_SENSE")
			(solder_mask_margin 0)
			(solder_paste_margin 0)
		)
		(pad "12" smd rect
			(at 2.6416 0.8 180)
			(size 0.3302 0.508)
			(layers "F.Cu" "F.Mask" "F.Paste")
			(net "P5V_SENSE")
			(solder_mask_margin 0)
			(solder_paste_margin 0)
		)
		(pad "13" smd rect
			(at 2.6416 0 180)
			(size 0.3302 0.508)
			(layers "F.Cu" "F.Mask" "F.Paste")
			(net "P5V_SENSE")
			(solder_mask_margin 0)
			(solder_paste_margin 0)
		)
		(pad "14" smd rect
			(at 2.6416 -0.8 180)
			(size 0.3302 0.508)
			(layers "F.Cu" "F.Mask" "F.Paste")
			(net "P5V_SENSE")
			(solder_mask_margin 0)
			(solder_paste_margin 0)
		)
		(pad "15" smd rect
			(at 2.6416 -1.6 180)
			(size 0.3302 0.508)
			(layers "F.Cu" "F.Mask" "F.Paste")
			(net "GND")
			(solder_mask_margin 0)
			(solder_paste_margin 0)
		)
		(pad "16" smd rect
			(at 1.6 -2.6416 90)
			(size 0.3302 0.508)
			(layers "F.Cu" "F.Mask" "F.Paste")
			(net "P5V_MUN_FB")
			(solder_mask_margin 0)
			(solder_paste_margin 0)
		)
		(pad "17" smd rect
			(at 0.8 -2.6416 90)
			(size 0.3302 0.508)
			(layers "F.Cu" "F.Mask" "F.Paste")
			(net "P5V_MUN_VCC")
			(solder_mask_margin 0)
			(solder_paste_margin 0)
		)
		(pad "18" smd rect
			(at 0 -2.6416 90)
			(size 0.3302 0.508)
			(layers "F.Cu" "F.Mask" "F.Paste")
			(solder_mask_margin 0)
			(solder_paste_margin 0)
		)
		(pad "19" smd rect
			(at -0.8 -2.6416 90)
			(size 0.3302 0.508)
			(layers "F.Cu" "F.Mask" "F.Paste")
			(net "+12V")
			(solder_mask_margin 0)
			(solder_paste_margin 0)
		)
		(pad "20" smd rect
			(at -1.6 -2.6416 90)
			(size 0.3302 0.508)
			(layers "F.Cu" "F.Mask" "F.Paste")
			(net "+12V")
			(solder_mask_margin 0)
			(solder_paste_margin 0)
		)
		(pad "21" smd rect
			(at -0.91 -1.67 270)
			(size 1.8796 0.3556)
			(layers "F.Cu" "F.Mask" "F.Paste")
			(net "+12V")
			(solder_mask_margin 0)
			(solder_paste_margin 0)
		)
		(pad "22" smd rect
			(at -0.91 -0.86 270)
			(size 1.8796 0.6604)
			(layers "F.Cu" "F.Mask" "F.Paste")
			(net "P5V_MUN_PHASE")
			(solder_mask_margin 0)
			(solder_paste_margin 0)
		)
		(pad "23" smd rect
			(at -0.91 0.8 270)
			(size 1.8796 2.1082)
			(layers "F.Cu" "F.Mask" "F.Paste")
			(net "GND")
			(solder_mask_margin 0)
			(solder_paste_margin 0)
		)
		(pad "24" smd rect
			(at 1.4 0.8 270)
			(size 0.889 2.1082)
			(layers "F.Cu" "F.Mask" "F.Paste")
			(net "P5V_SENSE")
			(solder_mask_margin 0)
			(solder_paste_margin 0)
		)
		(pad "25" smd rect
			(at 1.4 -1.2 270)
			(size 0.889 1.2954)
			(layers "F.Cu" "F.Mask" "F.Paste")
			(net "GND")
			(solder_mask_margin 0)
			(solder_paste_margin 0)
		)
	)
	(footprint "Vault:RESC1005X40X25NL05T05"
		(layer "F.Cu")
		(at 230.2216 113.1162)
		(property "Reference" "R13"
			(at 0.3286 -0.873069 0)
			(unlocked yes)
			(layer "F.SilkS")
			(effects
				(font
					(size 0.762 0.762)
					(thickness 0.2286)
				)
			)
		)
		(property "Value" "27_1%_0402"
			(at -2.884671 3.18659 270)
			(unlocked yes)
			(layer "F.SilkS")
			(hide yes)
			(effects
				(font
					(size 0.762 0.762)
					(thickness 0.2286)
				)
			)
		)
		(sheetname "09-USBUart_PPSMUX_UARTMUX")
		(sheetfile "09-USBUart_PPSMUX_UARTMUX.kicad_sch")
		(duplicate_pad_numbers_are_jumpers no)
		(pad "1" smd rect
			(at -0.45 0 90)
			(size 0.55 0.55)
			(layers "F.Cu" "F.Mask" "F.Paste")
			(net "NetR13_1")
		)
		(pad "2" smd rect
			(at 0.45 0 90)
			(size 0.55 0.55)
			(layers "F.Cu" "F.Mask" "F.Paste")
			(net "FTDI_TX")
		)
	)
	(footprint "FPGA_CONN:SingleFPGAConn"
		(locked yes)
		(layer "F.Cu")
		(at 151.29899 101.28552 -90)
		(property "Reference" "J35"
			(at -0.39436 -23.455129 270)
			(unlocked yes)
			(layer "F.SilkS")
			(effects
				(font
					(size 0.762 0.762)
					(thickness 0.2286)
				)
			)
		)
		(property "Value" "Single FPGA Conn"
			(at 9.25452 3.621231 270)
			(unlocked yes)
			(layer "F.SilkS")
			(hide yes)
			(effects
				(font
					(size 0.762 0.762)
					(thickness 0.2286)
				)
			)
		)
		(sheetname "07-FPGA")
		(sheetfile "07-FPGA.kicad_sch")
		(duplicate_pad_numbers_are_jumpers no)
		(fp_line
			(start -1.40005 1.24993)
			(end -1.40005 0.70002)
			(stroke
				(width 0.15011)
				(type solid)
			)
			(layer "F.SilkS")
		)
		(fp_line
			(start 1.40005 1.24993)
			(end -1.40005 1.24993)
			(stroke
				(width 0.15011)
				(type solid)
			)
			(layer "F.SilkS")
		)
		(fp_line
			(start 1.40005 1.24993)
			(end 2 0.70002)
			(stroke
				(width 0.15011)
				(type solid)
			)
			(layer "F.SilkS")
		)
		(fp_line
			(start -2 0.70002)
			(end -2 0.03302)
			(stroke
				(width 0.15011)
				(type solid)
			)
			(layer "F.SilkS")
		)
		(fp_line
			(start -1.40005 0.70002)
			(end -2 0.70002)
			(stroke
				(width 0.15011)
				(type solid)
			)
			(layer "F.SilkS")
		)
		(fp_line
			(start 2 0.70002)
			(end 2 0.03302)
			(stroke
				(width 0.15011)
				(type solid)
			)
			(layer "F.SilkS")
		)
		(fp_line
			(start -2 -20.03298)
			(end -2 -20.69998)
			(stroke
				(width 0.15011)
				(type solid)
			)
			(layer "F.SilkS")
		)
		(fp_line
			(start 2 -20.03298)
			(end 2 -20.69998)
			(stroke
				(width 0.15011)
				(type solid)
			)
			(layer "F.SilkS")
		)
		(fp_line
			(start -1.40005 -20.69998)
			(end -2 -20.69998)
			(stroke
				(width 0.15011)
				(type solid)
			)
			(layer "F.SilkS")
		)
		(fp_line
			(start -1.40005 -20.69998)
			(end -1.40005 -21.24989)
			(stroke
				(width 0.15011)
				(type solid)
			)
			(layer "F.SilkS")
		)
		(fp_line
			(start 2 -20.69998)
			(end 1.40005 -21.24989)
			(stroke
				(width 0.15011)
				(type solid)
			)
			(layer "F.SilkS")
		)
		(fp_line
			(start 1.40005 -21.24989)
			(end -1.40005 -21.24989)
			(stroke
				(width 0.15011)
				(type solid)
			)
			(layer "F.SilkS")
		)
		(fp_circle
			(center 3.5052 -0.22454)
			(end 3.30505 -0.22454)
			(stroke
				(width 0.40005)
				(type solid)
			)
			(fill no)
			(layer "F.SilkS")
		)
		(pad "1" smd rect
			(at 2.02489 -0.24994 270)
			(size 1.54991 0.24994)
			(layers "F.Cu" "F.Mask" "F.Paste")
			(net "GPS1_PIN15")
		)
		(pad "2" smd rect
			(at -2.02489 -0.24994 270)
			(size 1.54991 0.24994)
			(layers "F.Cu" "F.Mask" "F.Paste")
			(net "GPS1_PIN13")
		)
		(pad "3" smd rect
			(at 2.02489 -0.75006 270)
			(size 1.54991 0.24994)
			(layers "F.Cu" "F.Mask" "F.Paste")
			(net "GPS1_PIN14")
		)
		(pad "4" smd rect
			(at -2.02489 -0.75006 270)
			(size 1.54991 0.24994)
			(layers "F.Cu" "F.Mask" "F.Paste")
			(net "GPS1_PIN11")
		)
		(pad "5" smd rect
			(at 2.02489 -1.24993 270)
			(size 1.54991 0.24994)
			(layers "F.Cu" "F.Mask" "F.Paste")
			(net "GPS1_PIN12")
		)
		(pad "6" smd rect
			(at -2.02489 -1.24993 270)
			(size 1.54991 0.24994)
			(layers "F.Cu" "F.Mask" "F.Paste")
		)
		(pad "7" smd rect
			(at 2.02489 -1.75006 270)
			(size 1.54991 0.24994)
			(layers "F.Cu" "F.Mask" "F.Paste")
		)
		(pad "8" smd rect
			(at -2.02489 -1.75006 270)
			(size 1.54991 0.24994)
			(layers "F.Cu" "F.Mask" "F.Paste")
			(net "MAC_USB_PWR")
		)
		(pad "9" smd rect
			(at 2.02489 -2.24993 270)
			(size 1.54991 0.24994)
			(layers "F.Cu" "F.Mask" "F.Paste")
			(net "GND")
		)
		(pad "10" smd rect
			(at -2.02489 -2.24993 270)
			(size 1.54991 0.24994)
			(layers "F.Cu" "F.Mask" "F.Paste")
			(net "GND")
		)
		(pad "11" smd rect
			(at 2.02489 -2.75006 270)
			(size 1.54991 0.24994)
			(layers "F.Cu" "F.Mask" "F.Paste")
			(net "MAC_RF_OUT")
		)
		(pad "12" smd rect
			(at -2.02489 -2.75006 270)
			(size 1.54991 0.24994)
			(layers "F.Cu" "F.Mask" "F.Paste")
		)
		(pad "13" smd rect
			(at 2.02489 -3.24993 270)
			(size 1.54991 0.24994)
			(layers "F.Cu" "F.Mask" "F.Paste")
			(net "MAC_RF_OUT")
		)
		(pad "14" smd rect
			(at -2.02489 -3.24993 270)
			(size 1.54991 0.24994)
			(layers "F.Cu" "F.Mask" "F.Paste")
		)
		(pad "15" smd rect
			(at 2.02489 -3.75006 270)
			(size 1.54991 0.24994)
			(layers "F.Cu" "F.Mask" "F.Paste")
			(net "ANT1_OUT")
		)
		(pad "16" smd rect
			(at -2.02489 -3.75006 270)
			(size 1.54991 0.24994)
			(layers "F.Cu" "F.Mask" "F.Paste")
			(net "ANT3_IN")
		)
		(pad "17" smd rect
			(at 2.02489 -4.24993 270)
			(size 1.54991 0.24994)
			(layers "F.Cu" "F.Mask" "F.Paste")
			(net "ANT2_OUT")
		)
		(pad "18" smd rect
			(at -2.02489 -4.24993 270)
			(size 1.54991 0.24994)
			(layers "F.Cu" "F.Mask" "F.Paste")
			(net "ANT4_IN")
		)
		(pad "19" smd rect
			(at 2.02489 -4.75005 270)
			(size 1.54991 0.24994)
			(layers "F.Cu" "F.Mask" "F.Paste")
			(net "GND")
		)
		(pad "20" smd rect
			(at -2.02489 -4.75005 270)
			(size 1.54991 0.24994)
			(layers "F.Cu" "F.Mask" "F.Paste")
			(net "GND")
		)
		(pad "21" smd rect
			(at 2.02489 -5.24993 270)
			(size 1.54991 0.24994)
			(layers "F.Cu" "F.Mask" "F.Paste")
			(net "ANT1_IN")
		)
		(pad "22" smd rect
			(at -2.02489 -5.24993 270)
			(size 1.54991 0.24994)
			(layers "F.Cu" "F.Mask" "F.Paste")
		)
		(pad "23" smd rect
			(at 2.02489 -5.75005 270)
			(size 1.54991 0.24994)
			(layers "F.Cu" "F.Mask" "F.Paste")
			(net "ANT2_IN")
		)
		(pad "24" smd rect
			(at -2.02489 -5.75005 270)
			(size 1.54991 0.24994)
			(layers "F.Cu" "F.Mask" "F.Paste")
		)
		(pad "25" smd rect
			(at 2.02489 -6.24992 270)
			(size 1.54991 0.24994)
			(layers "F.Cu" "F.Mask" "F.Paste")
			(net "ANT3_OUT")
		)
		(pad "26" smd rect
			(at -2.02489 -6.24992 270)
			(size 1.54991 0.24994)
			(layers "F.Cu" "F.Mask" "F.Paste")
			(net "FPGA_MAC_UART_TX")
		)
		(pad "27" smd rect
			(at 2.02489 -6.75005 270)
			(size 1.54991 0.24994)
			(layers "F.Cu" "F.Mask" "F.Paste")
			(net "ANT4_OUT")
		)
		(pad "28" smd rect
			(at -2.02489 -6.75005 270)
			(size 1.54991 0.24994)
			(layers "F.Cu" "F.Mask" "F.Paste")
			(net "MAC_FPGA_UART_RX")
		)
		(pad "29" smd rect
			(at 2.02489 -7.24992 270)
			(size 1.54991 0.24994)
			(layers "F.Cu" "F.Mask" "F.Paste")
			(net "GND")
		)
		(pad "30" smd rect
			(at -2.02489 -7.24992 270)
			(size 1.54991 0.24994)
			(layers "F.Cu" "F.Mask" "F.Paste")
			(net "GND")
		)
		(pad "31" smd rect
			(at 2.02489 -7.75005 270)
			(size 1.54991 0.24994)
			(layers "F.Cu" "F.Mask" "F.Paste")
		)
		(pad "32" smd rect
			(at -2.02489 -7.75005 270)
			(size 1.54991 0.24994)
			(layers "F.Cu" "F.Mask" "F.Paste")
		)
		(pad "33" smd rect
			(at 2.02489 -8.24992 270)
			(size 1.54991 0.24994)
			(layers "F.Cu" "F.Mask" "F.Paste")
		)
		(pad "34" smd rect
			(at -2.02489 -8.24992 270)
			(size 1.54991 0.24994)
			(layers "F.Cu" "F.Mask" "F.Paste")
		)
		(pad "35" smd rect
			(at 2.02489 -8.75005 270)
			(size 1.54991 0.24994)
			(layers "F.Cu" "F.Mask" "F.Paste")
			(net "MAC_ALARM")
		)
		(pad "36" smd rect
			(at -2.02489 -8.75005 270)
			(size 1.54991 0.24994)
			(layers "F.Cu" "F.Mask" "F.Paste")
			(net "FPGA_BNO_XIN32")
		)
		(pad "37" smd rect
			(at 2.02489 -9.24992 270)
			(size 1.54991 0.24994)
			(layers "F.Cu" "F.Mask" "F.Paste")
			(net "MAC_BITE")
		)
		(pad "38" smd rect
			(at -2.02489 -9.24992 270)
			(size 1.54991 0.24994)
			(layers "F.Cu" "F.Mask" "F.Paste")
			(net "FPGA_BNO_XOUT32")
		)
		(pad "39" smd rect
			(at 2.02489 -9.75004 270)
			(size 1.54991 0.24994)
			(layers "F.Cu" "F.Mask" "F.Paste")
			(net "GND")
		)
		(pad "40" smd rect
			(at -2.02489 -9.75004 270)
			(size 1.54991 0.24994)
			(layers "F.Cu" "F.Mask" "F.Paste")
			(net "GND")
		)
		(pad "41" smd rect
			(at 2.02489 -10.24992 270)
			(size 1.54991 0.24994)
			(layers "F.Cu" "F.Mask" "F.Paste")
		)
		(pad "42" smd rect
			(at -2.02489 -10.24992 270)
			(size 1.54991 0.24994)
			(layers "F.Cu" "F.Mask" "F.Paste")
		)
		(pad "43" smd rect
			(at 2.02489 -10.75004 270)
			(size 1.54991 0.24994)
			(layers "F.Cu" "F.Mask" "F.Paste")
			(net "FPGA_MAC_PPS_OUT-")
		)
		(pad "44" smd rect
			(at -2.02489 -10.75004 270)
			(size 1.54991 0.24994)
			(layers "F.Cu" "F.Mask" "F.Paste")
		)
		(pad "45" smd rect
			(at 2.02489 -11.24991 270)
			(size 1.54991 0.24994)
			(layers "F.Cu" "F.Mask" "F.Paste")
		)
		(pad "46" smd rect
			(at -2.02489 -11.24991 270)
			(size 1.54991 0.24994)
			(layers "F.Cu" "F.Mask" "F.Paste")
		)
		(pad "47" smd rect
			(at 2.02489 -11.75004 270)
			(size 1.54991 0.24994)
			(layers "F.Cu" "F.Mask" "F.Paste")
			(net "FPGA_MAC_PPS_IN0-")
		)
		(pad "48" smd rect
			(at -2.02489 -11.75004 270)
			(size 1.54991 0.24994)
			(layers "F.Cu" "F.Mask" "F.Paste")
		)
		(pad "49" smd rect
			(at 2.02489 -12.24991 270)
			(size 1.54991 0.24994)
			(layers "F.Cu" "F.Mask" "F.Paste")
			(net "GND")
		)
		(pad "50" smd rect
			(at -2.02489 -12.24991 270)
			(size 1.54991 0.24994)
			(layers "F.Cu" "F.Mask" "F.Paste")
			(net "GND")
		)
		(pad "51" smd rect
			(at 2.02489 -12.75004 270)
			(size 1.54991 0.24994)
			(layers "F.Cu" "F.Mask" "F.Paste")
		)
		(pad "52" smd rect
			(at -2.02489 -12.75004 270)
			(size 1.54991 0.24994)
			(layers "F.Cu" "F.Mask" "F.Paste")
		)
		(pad "53" smd rect
			(at 2.02489 -13.24991 270)
			(size 1.54991 0.24994)
			(layers "F.Cu" "F.Mask" "F.Paste")
			(net "FPGA_MAC_PPS_IN1-")
		)
		(pad "54" smd rect
			(at -2.02489 -13.24991 270)
			(size 1.54991 0.24994)
			(layers "F.Cu" "F.Mask" "F.Paste")
		)
		(pad "55" smd rect
			(at 2.02489 -13.75004 270)
			(size 1.54991 0.24994)
			(layers "F.Cu" "F.Mask" "F.Paste")
		)
		(pad "56" smd rect
			(at -2.02489 -13.75004 270)
			(size 1.54991 0.24994)
			(layers "F.Cu" "F.Mask" "F.Paste")
		)
		(pad "57" smd rect
			(at 2.02489 -14.24991 270)
			(size 1.54991 0.24994)
			(layers "F.Cu" "F.Mask" "F.Paste")
		)
		(pad "58" smd rect
			(at -2.02489 -14.24991 270)
			(size 1.54991 0.24994)
			(layers "F.Cu" "F.Mask" "F.Paste")
		)
		(pad "59" smd rect
			(at 2.02489 -14.75003 270)
			(size 1.54991 0.24994)
			(layers "F.Cu" "F.Mask" "F.Paste")
			(net "GND")
		)
		(pad "60" smd rect
			(at -2.02489 -14.75003 270)
			(size 1.54991 0.24994)
			(layers "F.Cu" "F.Mask" "F.Paste")
			(net "GND")
		)
		(pad "61" smd rect
			(at 2.02489 -15.24991 270)
			(size 1.54991 0.24994)
			(layers "F.Cu" "F.Mask" "F.Paste")
			(net "SDA")
		)
		(pad "62" smd rect
			(at -2.02489 -15.24991 270)
			(size 1.54991 0.24994)
			(layers "F.Cu" "F.Mask" "F.Paste")
		)
		(pad "63" smd rect
			(at 2.02489 -15.75003 270)
			(size 1.54991 0.24994)
			(layers "F.Cu" "F.Mask" "F.Paste")
			(net "BNO_INT")
		)
		(pad "64" smd rect
			(at -2.02489 -15.75003 270)
			(size 1.54991 0.24994)
			(layers "F.Cu" "F.Mask" "F.Paste")
		)
		(pad "65" smd rect
			(at 2.02489 -16.2499 270)
			(size 1.54991 0.24994)
			(layers "F.Cu" "F.Mask" "F.Paste")
			(net "GPS2_PIN15")
		)
		(pad "66" smd rect
			(at -2.02489 -16.2499 270)
			(size 1.54991 0.24994)
			(layers "F.Cu" "F.Mask" "F.Paste")
		)
		(pad "67" smd rect
			(at 2.02489 -16.75003 270)
			(size 1.54991 0.24994)
			(layers "F.Cu" "F.Mask" "F.Paste")
			(net "SCL")
		)
		(pad "68" smd rect
			(at -2.02489 -16.75003 270)
			(size 1.54991 0.24994)
			(layers "F.Cu" "F.Mask" "F.Paste")
		)
		(pad "69" smd rect
			(at 2.02489 -17.2499 270)
			(size 1.54991 0.24994)
			(layers "F.Cu" "F.Mask" "F.Paste")
			(net "GND")
		)
		(pad "70" smd rect
			(at -2.02489 -17.2499 270)
			(size 1.54991 0.24994)
			(layers "F.Cu" "F.Mask" "F.Paste")
			(net "GND")
		)
		(pad "71" smd rect
			(at 2.02489 -17.75003 270)
			(size 1.54991 0.24994)
			(layers "F.Cu" "F.Mask" "F.Paste")
			(net "UART1_TXD")
		)
		(pad "72" smd rect
			(at -2.02489 -17.75003 270)
			(size 1.54991 0.24994)
			(layers "F.Cu" "F.Mask" "F.Paste")
			(net "MAC_USB+")
		)
		(pad "73" smd rect
			(at 2.02489 -18.2499 270)
			(size 1.54991 0.24994)
			(layers "F.Cu" "F.Mask" "F.Paste")
			(net "GPS2_PIN13")
		)
		(pad "74" smd rect
			(at -2.02489 -18.2499 270)
			(size 1.54991 0.24994)
			(layers "F.Cu" "F.Mask" "F.Paste")
			(net "MAC_USB-")
		)
		(pad "75" smd rect
			(at 2.02489 -18.75003 270)
			(size 1.54991 0.24994)
			(layers "F.Cu" "F.Mask" "F.Paste")
			(net "GPS2_PIN11")
		)
		(pad "76" smd rect
			(at -2.02489 -18.75003 270)
			(size 1.54991 0.24994)
			(layers "F.Cu" "F.Mask" "F.Paste")
			(net "GPS2_PIN12")
		)
		(pad "77" smd rect
			(at 2.02489 -19.2499 270)
			(size 1.54991 0.24994)
			(layers "F.Cu" "F.Mask" "F.Paste")
			(net "UART1_RXD")
		)
		(pad "78" smd rect
			(at -2.02489 -19.2499 270)
			(size 1.54991 0.24994)
			(layers "F.Cu" "F.Mask" "F.Paste")
			(net "GPS2_PIN14")
		)
		(pad "79" smd rect
			(at 2.02489 -19.75002 270)
			(size 1.54991 0.24994)
			(layers "F.Cu" "F.Mask" "F.Paste")
			(net "GPS1_RX")
		)
		(pad "80" smd rect
			(at -2.02489 -19.75002 270)
			(size 1.54991 0.24994)
			(layers "F.Cu" "F.Mask" "F.Paste")
			(net "GPS1_TX")
		)
		(pad "81" smd rect
			(at 0.01135 1.17626 270)
			(size 1.70002 1.35001)
			(layers "F.Cu" "F.Mask" "F.Paste")
		)
		(pad "82" thru_hole circle
			(at 0 0 270)
			(size 0.55016 0.55016)
			(drill 0.55016)
			(layers "*.Cu" "*.Mask")
			(remove_unused_layers no)
			(thermal_bridge_angle 90)
		)
		(pad "83" thru_hole circle
			(at 0 -19.99996 270)
			(size 0.55016 0.55016)
			(drill 0.55016)
			(layers "*.Cu" "*.Mask")
			(remove_unused_layers no)
			(thermal_bridge_angle 90)
		)
		(pad "84" smd rect
			(at 0.01135 -21.17374 270)
			(size 1.70002 1.35001)
			(layers "F.Cu" "F.Mask" "F.Paste")
		)
	)
	(footprint "GNSS:GNSS"
		(locked yes)
		(layer "F.Cu")
		(at 107.2491 70.7286)
		(property "Reference" "U9"
			(at -1.3275 4.294255 180)
			(unlocked yes)
			(layer "F.SilkS")
			(effects
				(font
					(size 0.762 0.762)
					(thickness 0.2286)
				)
				(justify left bottom)
			)
		)
		(property "Value" "RCB-F9T"
			(at -9.8007 23.073645 0)
			(unlocked yes)
			(layer "F.SilkS")
			(hide yes)
			(effects
				(font
					(size 0.762 0.762)
					(thickness 0.2286)
				)
				(justify left bottom)
			)
		)
		(sheetname "05-GPS_IMU_SENSORS")
		(sheetfile "05-GPS_IMU_SENSORS.kicad_sch")
		(duplicate_pad_numbers_are_jumpers no)
		(fp_line
			(start -6.11 -20.47)
			(end 61.07 -20.47)
			(stroke
				(width 0.254)
				(type solid)
			)
			(layer "F.SilkS")
		)
		(fp_line
			(start -6.11 11.28)
			(end -6.11 -20.47)
			(stroke
				(width 0.254)
				(type solid)
			)
			(layer "F.SilkS")
		)
		(fp_line
			(start -6.11 11.28)
			(end 61.07 11.28)
			(stroke
				(width 0.254)
				(type solid)
			)
			(layer "F.SilkS")
		)
		(fp_line
			(start 61.07 11.28)
			(end 61.07 -20.47)
			(stroke
				(width 0.254)
				(type solid)
			)
			(layer "F.SilkS")
		)
		(pad "0" thru_hole circle
			(at 0 -2 270)
			(size 0 0)
			(drill 0.76)
			(layers "*.Cu" "*.Mask")
			(remove_unused_layers no)
			(thermal_bridge_angle 90)
		)
		(pad "0" thru_hole circle
			(at 0 2 270)
			(size 0 0)
			(drill 0.76)
			(layers "*.Cu" "*.Mask")
			(remove_unused_layers no)
			(thermal_bridge_angle 90)
		)
		(pad "1" smd rect
			(at -2.2225 3 270)
			(size 1.12 2.105)
			(layers "F.Cu" "F.Mask" "F.Paste")
			(net "+5.0V")
		)
		(pad "2" smd rect
			(at 2.2225 3 270)
			(size 1.12 2.105)
			(layers "F.Cu" "F.Mask" "F.Paste")
			(net "+3.3V")
		)
		(pad "3" smd rect
			(at -2.2225 1 270)
			(size 1.12 2.105)
			(layers "F.Cu" "F.Mask" "F.Paste")
			(net "RCB_GPS1_TX")
		)
		(pad "4" smd rect
			(at 2.2225 1 270)
			(size 1.12 2.105)
			(layers "F.Cu" "F.Mask" "F.Paste")
			(net "GPS1_RST")
		)
		(pad "5" smd rect
			(at -2.2225 -1 270)
			(size 1.12 2.105)
			(layers "F.Cu" "F.Mask" "F.Paste")
			(net "RCB_GPS1_RX")
		)
		(pad "6" smd rect
			(at 2.2225 -1 270)
			(size 1.12 2.105)
			(layers "F.Cu" "F.Mask" "F.Paste")
			(net "RCB_GPS1_TP1")
		)
		(pad "7" smd rect
			(at -2.2225 -3 270)
			(size 1.12 2.105)
			(layers "F.Cu" "F.Mask" "F.Paste")
			(net "RCB_GPS1_TP2")
		)
		(pad "8" smd rect
			(at 2.2225 -3 270)
			(size 1.12 2.105)
			(layers "F.Cu" "F.Mask" "F.Paste")
			(net "GND")
		)
	)
	(footprint "Vault:FP-0603-L_1_6_0_2-W_0_8_0-MFG"
		(layer "F.Cu")
		(at 169.4716 83.5162 90)
		(property "Reference" "C80"
			(at 2.7286 -0.023069 90)
			(unlocked yes)
			(layer "F.SilkS")
			(effects
				(font
					(size 0.762 0.762)
					(thickness 0.2286)
				)
			)
		)
		(property "Value" "10uF_16V_0603"
			(at -2.871951 8.95046 0)
			(unlocked yes)
			(layer "F.SilkS")
			(hide yes)
			(effects
				(font
					(size 0.762 0.762)
					(thickness 0.2286)
				)
			)
		)
		(sheetname "03-POWER")
		(sheetfile "03-POWER.kicad_sch")
		(duplicate_pad_numbers_are_jumpers no)
		(fp_line
			(start -0.9 -0.825)
			(end 0.9 -0.825)
			(stroke
				(width 0.2)
				(type solid)
			)
			(layer "F.SilkS")
		)
		(fp_line
			(start -0.9 0.82499)
			(end 0.9 0.82499)
			(stroke
				(width 0.2)
				(type solid)
			)
			(layer "F.SilkS")
		)
		(fp_line
			(start 1.15 -0.6)
			(end 1.15 0.59999)
			(stroke
				(width 0.2)
				(type solid)
			)
			(layer "F.CrtYd")
		)
		(fp_line
			(start -1.15 -0.6)
			(end 1.15 -0.6)
			(stroke
				(width 0.2)
				(type solid)
			)
			(layer "F.CrtYd")
		)
		(fp_line
			(start -1.15 -0.6)
			(end -1.15 0.59999)
			(stroke
				(width 0.2)
				(type solid)
			)
			(layer "F.CrtYd")
		)
		(fp_line
			(start -1.15 0.59999)
			(end 1.15 0.59999)
			(stroke
				(width 0.2)
				(type solid)
			)
			(layer "F.CrtYd")
		)
		(fp_line
			(start 1.15 -0.6)
			(end 1.15 0.59999)
			(stroke
				(width 0.2)
				(type solid)
			)
			(layer "F.Fab")
		)
		(fp_line
			(start -1.15 -0.6)
			(end 1.15 -0.6)
			(stroke
				(width 0.2)
				(type solid)
			)
			(layer "F.Fab")
		)
		(fp_line
			(start -1.15 -0.6)
			(end -1.15 0.59999)
			(stroke
				(width 0.2)
				(type solid)
			)
			(layer "F.Fab")
		)
		(fp_line
			(start 0 -0.5)
			(end 0 0.49999)
			(stroke
				(width 0.1)
				(type solid)
			)
			(layer "F.Fab")
		)
		(fp_line
			(start -0.5 0)
			(end 0.5 0)
			(stroke
				(width 0.1)
				(type solid)
			)
			(layer "F.Fab")
		)
		(fp_line
			(start -1.15 0.59999)
			(end 1.15 0.59999)
			(stroke
				(width 0.2)
				(type solid)
			)
			(layer "F.Fab")
		)
		(fp_text user "${REFERENCE}"
			(at -0.00001 0.09601 90)
			(unlocked yes)
			(layer "F.Fab")
			(effects
				(font
					(face "Arial")
					(size 0.63 0.63)
					(thickness 0.1)
				)
				(justify left bottom)
			)
		)
		(pad "1" smd rect
			(at -0.7 0 90)
			(size 0.7 0.7)
			(layers "F.Cu" "F.Mask" "F.Paste")
			(net "+3.3V")
			(solder_mask_margin 0)
			(solder_paste_margin 0)
		)
		(pad "2" smd rect
			(at 0.7 0 90)
			(size 0.7 0.7)
			(layers "F.Cu" "F.Mask" "F.Paste")
			(net "GND")
			(solder_mask_margin 0)
			(solder_paste_margin 0)
		)
	)
	(footprint ""
		(layer "F.Cu")
		(at 208.22161 83.61617)
		(property "Reference" ""
			(at 0 0 0)
			(layer "F.SilkS")
			(effects
				(font
					(size 1.27 1.27)
				)
			)
		)
		(property "Value" ""
			(at 0 0 0)
			(layer "F.Fab")
			(effects
				(font
					(size 1.27 1.27)
				)
			)
		)
		(duplicate_pad_numbers_are_jumpers no)
		(pad "2" thru_hole circle
			(at 0 0)
			(size 6.5 6.5)
			(drill 4.2)
			(layers "*.Cu" "*.Mask")
			(remove_unused_layers no)
			(net "GND")
			(thermal_bridge_angle 90)
		)
	)
	(footprint "Vault:RESC3216X89X64NL25T25"
		(layer "F.Cu")
		(at 172.2466 85.8162 180)
		(property "Reference" "R72"
			(at 3.1964 -0.126921 0)
			(unlocked yes)
			(layer "F.SilkS")
			(effects
				(font
					(size 0.762 0.762)
					(thickness 0.2286)
				)
			)
		)
		(property "Value" "2mOhm_1%_1206"
			(at 7.62962 3.037071 180)
			(unlocked yes)
			(layer "F.SilkS")
			(hide yes)
			(effects
				(font
					(size 0.762 0.762)
					(thickness 0.2286)
				)
			)
		)
		(sheetname "03-POWER")
		(sheetfile "03-POWER.kicad_sch")
		(duplicate_pad_numbers_are_jumpers no)
		(fp_line
			(start 0.2 0.825)
			(end -0.2 0.825)
			(stroke
				(width 0.2)
				(type solid)
			)
			(layer "F.SilkS")
		)
		(fp_line
			(start 0.2 -0.825)
			(end -0.2 -0.825)
			(stroke
				(width 0.2)
				(type solid)
			)
			(layer "F.SilkS")
		)
		(pad "1" smd rect
			(at -1.325 0 270)
			(size 1.85 1.5)
			(layers "F.Cu" "F.Mask" "F.Paste")
			(net "P3V3_SENSE")
		)
		(pad "2" smd rect
			(at 1.325 0 270)
			(size 1.85 1.5)
			(layers "F.Cu" "F.Mask" "F.Paste")
			(net "+3.3V")
		)
	)
	(footprint "Capacitors:CAPC2012X14N"
		(layer "F.Cu")
		(at 138.7854 84.7662 90)
		(property "Reference" "C62"
			(at 1.446695 -1.09139 0)
			(unlocked yes)
			(layer "F.SilkS")
			(effects
				(font
					(size 0.762 0.762)
					(thickness 0.2286)
				)
				(justify left bottom)
			)
		)
		(property "Value" "CAP_0805_10UF_25V"
			(at -2.433445 -1.7875 0)
			(unlocked yes)
			(layer "F.SilkS")
			(hide yes)
			(effects
				(font
					(size 0.762 0.762)
					(thickness 0.2286)
				)
				(justify left bottom)
			)
		)
		(sheetname "06-MAC")
		(sheetfile "06-MAC.kicad_sch")
		(duplicate_pad_numbers_are_jumpers no)
		(fp_line
			(start -0.762 -0.9652)
			(end 0.762 -0.9652)
			(stroke
				(width 0.1524)
				(type solid)
			)
			(layer "F.SilkS")
		)
		(fp_line
			(start -0.762 0.9652)
			(end 0.762 0.9652)
			(stroke
				(width 0.1524)
				(type solid)
			)
			(layer "F.SilkS")
		)
		(pad "1" smd rect
			(at -0.9 0 180)
			(size 1.45 1.15)
			(layers "F.Cu" "F.Mask" "F.Paste")
			(net "MAC_VCC")
		)
		(pad "2" smd rect
			(at 0.9 0 180)
			(size 1.45 1.15)
			(layers "F.Cu" "F.Mask" "F.Paste")
			(net "GND")
		)
	)
	(footprint "Vault:RESC1005X40X25NL05T05"
		(layer "F.Cu")
		(at 193.2216 128.8162 90)
		(property "Reference" "R154"
			(at 0.9032 -2.473079 90)
			(unlocked yes)
			(layer "F.SilkS")
			(effects
				(font
					(size 0.762 0.762)
					(thickness 0.2032)
				)
			)
		)
		(property "Value" "DNI_27_1%_0402"
			(at -2.732271 10.270965 0)
			(unlocked yes)
			(layer "F.SilkS")
			(hide yes)
			(effects
				(font
					(size 0.762 0.762)
					(thickness 0.2032)
				)
			)
		)
		(sheetname "11-M2_RCB_MUX")
		(sheetfile "11-M2_RCB_MUX.kicad_sch")
		(duplicate_pad_numbers_are_jumpers no)
		(pad "1" smd rect
			(at -0.45 0 180)
			(size 0.55 0.55)
			(layers "F.Cu" "F.Mask" "F.Paste")
			(net "M2_GPS2_TX")
		)
		(pad "2" smd rect
			(at 0.45 0 180)
			(size 0.55 0.55)
			(layers "F.Cu" "F.Mask" "F.Paste")
			(net "GPS2_TX")
		)
	)
	(footprint "Vault:RESC1005X40X25NL05T05"
		(layer "F.Cu")
		(at 169.3216 118.1162 90)
		(property "Reference" "R121"
			(at -3.4032 -0.652001 270)
			(unlocked yes)
			(layer "F.SilkS")
			(effects
				(font
					(size 0.762 0.762)
					(thickness 0.2032)
				)
			)
		)
		(property "Value" "27_1%_0402"
			(at -2.732271 7.35092 0)
			(unlocked yes)
			(layer "F.SilkS")
			(hide yes)
			(effects
				(font
					(size 0.762 0.762)
					(thickness 0.2032)
				)
			)
		)
		(sheetname "08-DIPSwitches_I2C")
		(sheetfile "08-DIPSwitches_I2C.kicad_sch")
		(duplicate_pad_numbers_are_jumpers no)
		(pad "1" smd rect
			(at -0.45 0 180)
			(size 0.55 0.55)
			(layers "F.Cu" "F.Mask" "F.Paste")
			(net "PCIE_PERST")
		)
		(pad "2" smd rect
			(at 0.45 0 180)
			(size 0.55 0.55)
			(layers "F.Cu" "F.Mask" "F.Paste")
			(net "NetR121_2")
		)
	)
	(footprint "Vault:FP-LTST-C191KGKT-MFG"
		(layer "F.Cu")
		(at 224.7216 114.3162)
		(property "Reference" "D21"
			(at -3.392175 0.026931 0)
			(unlocked yes)
			(layer "F.SilkS")
			(effects
				(font
					(size 0.762 0.762)
					(thickness 0.2286)
				)
			)
		)
		(property "Value" "LTST-C191KGKT"
			(at 7.09647 2.452871 0)
			(unlocked yes)
			(layer "F.SilkS")
			(hide yes)
			(effects
				(font
					(size 0.762 0.762)
					(thickness 0.2286)
				)
			)
		)
		(sheetname "08-DIPSwitches_I2C")
		(sheetfile "08-DIPSwitches_I2C.kicad_sch")
		(duplicate_pad_numbers_are_jumpers no)
		(fp_line
			(start -0.85 -0.775)
			(end 0.85 -0.775)
			(stroke
				(width 0.2)
				(type solid)
			)
			(layer "F.SilkS")
		)
		(fp_line
			(start -0.85 0.775)
			(end 0.85 0.775)
			(stroke
				(width 0.2)
				(type solid)
			)
			(layer "F.SilkS")
		)
		(fp_circle
			(center -1.7 0)
			(end -1.7 -0.125)
			(stroke
				(width 0.25)
				(type solid)
			)
			(fill no)
			(layer "F.SilkS")
		)
		(fp_line
			(start -1.25 -0.55)
			(end 1.25 -0.55)
			(stroke
				(width 0.2)
				(type solid)
			)
			(layer "F.CrtYd")
		)
		(fp_line
			(start -1.25 0.55)
			(end -1.25 -0.55)
			(stroke
				(width 0.2)
				(type solid)
			)
			(layer "F.CrtYd")
		)
		(fp_line
			(start -1.25 0.55)
			(end 1.25 0.55)
			(stroke
				(width 0.2)
				(type solid)
			)
			(layer "F.CrtYd")
		)
		(fp_line
			(start 1.25 0.55)
			(end 1.25 -0.55)
			(stroke
				(width 0.2)
				(type solid)
			)
			(layer "F.CrtYd")
		)
		(fp_line
			(start -1.25 -0.55)
			(end 1.25 -0.55)
			(stroke
				(width 0.2)
				(type solid)
			)
			(layer "F.Fab")
		)
		(fp_line
			(start -1.25 0.55)
			(end -1.25 -0.55)
			(stroke
				(width 0.2)
				(type solid)
			)
			(layer "F.Fab")
		)
		(fp_line
			(start -1.25 0.55)
			(end 1.25 0.55)
			(stroke
				(width 0.2)
				(type solid)
			)
			(layer "F.Fab")
		)
		(fp_line
			(start -0.5 0)
			(end 0.5 0)
			(stroke
				(width 0.1)
				(type solid)
			)
			(layer "F.Fab")
		)
		(fp_line
			(start 0 0.5)
			(end 0 -0.5)
			(stroke
				(width 0.1)
				(type solid)
			)
			(layer "F.Fab")
		)
		(fp_line
			(start 1.25 0.55)
			(end 1.25 -0.55)
			(stroke
				(width 0.2)
				(type solid)
			)
			(layer "F.Fab")
		)
		(fp_text user "${REFERENCE}"
			(at 0 0.29534 0)
			(unlocked yes)
			(layer "F.Fab")
			(effects
				(font
					(face "Arial")
					(size 0.63 0.63)
					(thickness 0.1)
				)
				(justify left bottom)
			)
		)
		(pad "1" smd rect
			(at -0.75 0)
			(size 0.8 0.8)
			(layers "F.Cu" "F.Mask" "F.Paste")
			(net "NetD21_1")
			(solder_mask_margin 0)
			(solder_paste_margin 0)
		)
		(pad "2" smd rect
			(at 0.75 0)
			(size 0.8 0.8)
			(layers "F.Cu" "F.Mask" "F.Paste")
			(net "+3.3V")
			(solder_mask_margin 0)
			(solder_paste_margin 0)
		)
	)
	(footprint "Passives:SOT65P210X110-3N"
		(layer "F.Cu")
		(at 191.1826 145.69763)
		(property "Reference" "D6"
			(at -3.16026 -1.068085 0)
			(unlocked yes)
			(layer "F.SilkS")
			(effects
				(font
					(size 0.762 0.762)
					(thickness 0.2286)
				)
				(justify left bottom)
			)
		)
		(property "Value" "BAT54SW"
			(at -4.0249 -1.823555 0)
			(unlocked yes)
			(layer "F.SilkS")
			(hide yes)
			(effects
				(font
					(size 0.762 0.762)
					(thickness 0.2286)
				)
				(justify left bottom)
			)
		)
		(sheetname "04-PCIe_JTAG")
		(sheetfile "04-PCIe_JTAG.kicad_sch")
		(duplicate_pad_numbers_are_jumpers no)
		(fp_line
			(start -0.32499 -1.1)
			(end 0.675 -1.1)
			(stroke
				(width 0.2)
				(type solid)
			)
			(layer "F.SilkS")
		)
		(fp_line
			(start -0.32499 1.1)
			(end 0.675 1.1)
			(stroke
				(width 0.2)
				(type solid)
			)
			(layer "F.SilkS")
		)
		(fp_line
			(start 0.675 -0.65)
			(end 0.675 -1.1)
			(stroke
				(width 0.2)
				(type solid)
			)
			(layer "F.SilkS")
		)
		(fp_line
			(start 0.675 1.1)
			(end 0.675 0.65)
			(stroke
				(width 0.2)
				(type solid)
			)
			(layer "F.SilkS")
		)
		(fp_circle
			(center -1.125 -1.45)
			(end -1.125 -1.575)
			(stroke
				(width 0.25)
				(type solid)
			)
			(fill no)
			(layer "F.SilkS")
		)
		(pad "1" smd rect
			(at -1.125 -0.65 90)
			(size 0.5 0.9)
			(layers "F.Cu" "F.Mask" "F.Paste")
			(net "GND")
		)
		(pad "2" smd rect
			(at -1.125 0.65 90)
			(size 0.5 0.9)
			(layers "F.Cu" "F.Mask" "F.Paste")
			(net "+3.3V")
		)
		(pad "3" smd rect
			(at 1.125 0 90)
			(size 0.5 0.9)
			(layers "F.Cu" "F.Mask" "F.Paste")
			(net "FPGA_TDO")
		)
	)
	(footprint "Vault:RESC1005X40X25NL05T05"
		(layer "F.Cu")
		(at 161.1716 128.4162 180)
		(property "Reference" "R84"
			(at -0.4786 1.073069 0)
			(unlocked yes)
			(layer "F.SilkS")
			(effects
				(font
					(size 0.762 0.762)
					(thickness 0.2286)
				)
			)
		)
		(property "Value" "27_1%_0402"
			(at -2.732271 7.37632 90)
			(unlocked yes)
			(layer "F.SilkS")
			(hide yes)
			(effects
				(font
					(size 0.762 0.762)
					(thickness 0.2286)
				)
			)
		)
		(sheetname "09-USBUart_PPSMUX_UARTMUX")
		(sheetfile "09-USBUart_PPSMUX_UARTMUX.kicad_sch")
		(duplicate_pad_numbers_are_jumpers no)
		(pad "1" smd rect
			(at -0.45 0 270)
			(size 0.55 0.55)
			(layers "F.Cu" "F.Mask" "F.Paste")
			(net "GND")
		)
		(pad "2" smd rect
			(at 0.45 0 270)
			(size 0.55 0.55)
			(layers "F.Cu" "F.Mask" "F.Paste")
			(net "NetR84_2")
		)
	)
	(footprint "Vault:RESC1005X40X25LL05T10"
		(layer "F.Cu")
		(at 143.1216 107.4162 90)
		(property "Reference" "R97"
			(at -2.2286 -0.026931 270)
			(unlocked yes)
			(layer "F.SilkS")
			(effects
				(font
					(size 0.762 0.762)
					(thickness 0.2286)
				)
			)
		)
		(property "Value" "49.9_1%_0402"
			(at -2.579871 8.823665 0)
			(unlocked yes)
			(layer "F.SilkS")
			(hide yes)
			(effects
				(font
					(size 0.762 0.762)
					(thickness 0.2286)
				)
			)
		)
		(sheetname "09-USBUart_PPSMUX_UARTMUX")
		(sheetfile "09-USBUart_PPSMUX_UARTMUX.kicad_sch")
		(duplicate_pad_numbers_are_jumpers no)
		(pad "1" smd rect
			(at -0.375 0 180)
			(size 0.45 0.5)
			(layers "F.Cu" "F.Mask" "F.Paste")
			(net "FPGA_MAC_PPSDIFF_OUT")
		)
		(pad "2" smd rect
			(at 0.375 0 180)
			(size 0.45 0.5)
			(layers "F.Cu" "F.Mask" "F.Paste")
			(net "NetR97_2")
		)
	)
	(footprint "Vault:RESC1005X40X25NL05T05"
		(layer "F.Cu")
		(at 158.4216 132.1162)
		(property "Reference" "R101"
			(at 1.13007 0.988851 0)
			(unlocked yes)
			(layer "F.SilkS")
			(effects
				(font
					(size 0.762 0.762)
					(thickness 0.2286)
				)
			)
		)
		(property "Value" "DNI_27_1%_0402"
			(at -2.732281 10.296375 270)
			(unlocked yes)
			(layer "F.SilkS")
			(hide yes)
			(effects
				(font
					(size 0.762 0.762)
					(thickness 0.2286)
				)
			)
		)
		(sheetname "09-USBUart_PPSMUX_UARTMUX")
		(sheetfile "09-USBUart_PPSMUX_UARTMUX.kicad_sch")
		(duplicate_pad_numbers_are_jumpers no)
		(pad "1" smd rect
			(at -0.45 0 90)
			(size 0.55 0.55)
			(layers "F.Cu" "F.Mask" "F.Paste")
			(net "FTDI_TX")
		)
		(pad "2" smd rect
			(at 0.45 0 90)
			(size 0.55 0.55)
			(layers "F.Cu" "F.Mask" "F.Paste")
			(net "UART1_RXD")
		)
	)
	(footprint "Vault:RESC1005X40X25LL05T10"
		(layer "F.Cu")
		(at 144.2216 107.3662 90)
		(property "Reference" "R99"
			(at -2.4786 0.473069 270)
			(unlocked yes)
			(layer "F.SilkS")
			(effects
				(font
					(size 0.762 0.762)
					(thickness 0.2286)
				)
			)
		)
		(property "Value" "49.9_1%_0402"
			(at -2.579871 8.823665 0)
			(unlocked yes)
			(layer "F.SilkS")
			(hide yes)
			(effects
				(font
					(size 0.762 0.762)
					(thickness 0.2286)
				)
			)
		)
		(sheetname "09-USBUart_PPSMUX_UARTMUX")
		(sheetfile "09-USBUart_PPSMUX_UARTMUX.kicad_sch")
		(duplicate_pad_numbers_are_jumpers no)
		(pad "1" smd rect
			(at -0.375 0 180)
			(size 0.45 0.5)
			(layers "F.Cu" "F.Mask" "F.Paste")
			(net "FPGA_MAC_PPS_DIFF_IN0")
		)
		(pad "2" smd rect
			(at 0.375 0 180)
			(size 0.45 0.5)
			(layers "F.Cu" "F.Mask" "F.Paste")
			(net "NetR99_2")
		)
	)
	(footprint "SamacSys:155124M173200"
		(layer "F.Cu")
		(at 67.4466 114.8162 90)
		(property "Reference" "D16"
			(at -0.4286 1.448069 270)
			(unlocked yes)
			(layer "F.SilkS")
			(effects
				(font
					(size 0.762 0.762)
					(thickness 0.2286)
				)
			)
		)
		(property "Value" "155124M173200"
			(at 7.1471 2.605271 90)
			(unlocked yes)
			(layer "F.SilkS")
			(hide yes)
			(effects
				(font
					(size 0.762 0.762)
					(thickness 0.2286)
				)
			)
		)
		(sheetname "02-USER_IO_STATUS")
		(sheetfile "02-USER_IO_STATUS.kicad_sch")
		(duplicate_pad_numbers_are_jumpers no)
		(fp_line
			(start -0.8 0.5)
			(end 0.8 0.5)
			(stroke
				(width 0.1)
				(type solid)
			)
			(layer "F.SilkS")
		)
		(fp_arc
			(start -2 -0.1)
			(mid -1.95 -0.05)
			(end -2 0)
			(stroke
				(width 0.381)
				(type solid)
			)
			(layer "F.SilkS")
		)
		(fp_arc
			(start -2 0)
			(mid -2.05 -0.05)
			(end -2 -0.1)
			(stroke
				(width 0.381)
				(type solid)
			)
			(layer "F.SilkS")
		)
		(pad "1" smd rect
			(at -1.4 0 180)
			(size 0.9 0.6)
			(layers "F.Cu" "F.Mask" "F.Paste")
			(net "+3.3V")
		)
		(pad "2" smd rect
			(at -0.45 -0.325 90)
			(size 0.6 0.55)
			(layers "F.Cu" "F.Mask" "F.Paste")
			(net "NetD16_2")
		)
		(pad "3" smd rect
			(at 0.45 -0.325 90)
			(size 0.6 0.55)
			(layers "F.Cu" "F.Mask" "F.Paste")
			(net "NetD16_3")
		)
		(pad "4" smd rect
			(at 1.4 0 180)
			(size 0.9 0.6)
			(layers "F.Cu" "F.Mask" "F.Paste")
			(net "NetD16_4")
		)
	)
	(footprint "Vault:AMPH-901-143-6RFX_V"
		(layer "F.Cu")
		(at 69.9716 135.5786 180)
		(property "Reference" "AN4"
			(at 0.95 3.669055 0)
			(unlocked yes)
			(layer "F.SilkS")
			(effects
				(font
					(size 0.762 0.762)
					(thickness 0.2286)
				)
				(justify left bottom)
			)
		)
		(property "Value" "RF2-49B-T-00-50-G-HDW"
			(at 4.6101 -12.120245 0)
			(unlocked yes)
			(layer "F.SilkS")
			(hide yes)
			(effects
				(font
					(size 0.762 0.762)
					(thickness 0.2286)
				)
				(justify left bottom)
			)
		)
		(sheetname "01-USER_IO")
		(sheetfile "01-USER_IO.kicad_sch")
		(duplicate_pad_numbers_are_jumpers no)
		(fp_line
			(start 3.5 -1.38)
			(end 3.5 1.38)
			(stroke
				(width 0.2)
				(type solid)
			)
			(layer "F.SilkS")
		)
		(fp_line
			(start 1.38 3.5)
			(end -1.38 3.5)
			(stroke
				(width 0.2)
				(type solid)
			)
			(layer "F.SilkS")
		)
		(fp_line
			(start 1.38 -3.5)
			(end -1.38 -3.5)
			(stroke
				(width 0.2)
				(type solid)
			)
			(layer "F.SilkS")
		)
		(fp_line
			(start -3.5 -1.38)
			(end -3.5 1.38)
			(stroke
				(width 0.2)
				(type solid)
			)
			(layer "F.SilkS")
		)
		(pad "1" thru_hole rect
			(at 0 0 180)
			(size 2 2)
			(drill 1.5)
			(layers "*.Cu" "*.Mask")
			(remove_unused_layers no)
			(net "NetAN4_1")
		)
		(pad "2" thru_hole circle
			(at -2.54 -2.54 180)
			(size 2.2 2.2)
			(drill 1.7)
			(layers "*.Cu" "*.Mask")
			(remove_unused_layers no)
			(net "GND")
			(thermal_bridge_angle 90)
		)
		(pad "3" thru_hole circle
			(at -2.54 2.54 180)
			(size 2.2 2.2)
			(drill 1.7)
			(layers "*.Cu" "*.Mask")
			(remove_unused_layers no)
			(net "GND")
			(thermal_bridge_angle 90)
		)
		(pad "4" thru_hole circle
			(at 2.54 2.54 180)
			(size 2.2 2.2)
			(drill 1.7)
			(layers "*.Cu" "*.Mask")
			(remove_unused_layers no)
			(net "GND")
			(thermal_bridge_angle 90)
		)
		(pad "5" thru_hole circle
			(at 2.54 -2.54 180)
			(size 2.2 2.2)
			(drill 1.7)
			(layers "*.Cu" "*.Mask")
			(remove_unused_layers no)
			(net "GND")
			(thermal_bridge_angle 90)
		)
	)
	(footprint "Vault:FP-RUT0012A-MFG"
		(layer "F.Cu")
		(at 158.3216 129.5162)
		(property "Reference" "U21"
			(at 0.678605 -2.159259 0)
			(unlocked yes)
			(layer "F.SilkS")
			(effects
				(font
					(size 0.762 0.762)
					(thickness 0.2286)
				)
			)
		)
		(property "Value" "TMUX1072RUTR"
			(at 7.426665 3.164071 0)
			(unlocked yes)
			(layer "F.SilkS")
			(hide yes)
			(effects
				(font
					(size 0.762 0.762)
					(thickness 0.2286)
				)
			)
		)
		(sheetname "09-USBUart_PPSMUX_UARTMUX")
		(sheetfile "09-USBUart_PPSMUX_UARTMUX.kicad_sch")
		(duplicate_pad_numbers_are_jumpers no)
		(fp_line
			(start -0.9 -1.525)
			(end 0.9 -1.525)
			(stroke
				(width 0.2)
				(type solid)
			)
			(layer "F.SilkS")
		)
		(fp_line
			(start -0.9 1.525)
			(end 0.9 1.525)
			(stroke
				(width 0.2)
				(type solid)
			)
			(layer "F.SilkS")
		)
		(fp_circle
			(center -1.575 -0.8)
			(end -1.575 -0.925)
			(stroke
				(width 0.25)
				(type solid)
			)
			(fill no)
			(layer "F.SilkS")
		)
		(fp_rect
			(start -0.85 -0.3)
			(end -0.35 -0.5)
			(stroke
				(width 0)
				(type default)
			)
			(fill yes)
			(layer "F.Paste")
		)
		(fp_rect
			(start -0.85 0.1)
			(end -0.35 -0.1)
			(stroke
				(width 0)
				(type default)
			)
			(fill yes)
			(layer "F.Paste")
		)
		(fp_rect
			(start -0.85 0.5)
			(end -0.35 0.3)
			(stroke
				(width 0)
				(type default)
			)
			(fill yes)
			(layer "F.Paste")
		)
		(fp_rect
			(start -0.85 0.9)
			(end -0.35 0.7)
			(stroke
				(width 0)
				(type default)
			)
			(fill yes)
			(layer "F.Paste")
		)
		(fp_rect
			(start -0.1 -0.5)
			(end 0.1 -1)
			(stroke
				(width 0)
				(type default)
			)
			(fill yes)
			(layer "F.Paste")
		)
		(fp_rect
			(start -0.1 1)
			(end 0.1 0.5)
			(stroke
				(width 0)
				(type default)
			)
			(fill yes)
			(layer "F.Paste")
		)
		(fp_rect
			(start 0.35 -0.7)
			(end 0.85 -0.9)
			(stroke
				(width 0)
				(type default)
			)
			(fill yes)
			(layer "F.Paste")
		)
		(fp_rect
			(start 0.35 -0.3)
			(end 0.85 -0.5)
			(stroke
				(width 0)
				(type default)
			)
			(fill yes)
			(layer "F.Paste")
		)
		(fp_rect
			(start 0.35 0.1)
			(end 0.85 -0.1)
			(stroke
				(width 0)
				(type default)
			)
			(fill yes)
			(layer "F.Paste")
		)
		(fp_rect
			(start 0.35 0.5)
			(end 0.85 0.3)
			(stroke
				(width 0)
				(type default)
			)
			(fill yes)
			(layer "F.Paste")
		)
		(fp_rect
			(start 0.35 0.9)
			(end 0.85 0.7)
			(stroke
				(width 0)
				(type default)
			)
			(fill yes)
			(layer "F.Paste")
		)
		(fp_poly
			(pts
				(xy -0.5 -1) (xy -0.35 -1) (xy -0.35 -0.7) (xy -0.85 -0.7) (xy -0.85 -0.9) (xy -0.5 -0.9)
			)
			(stroke
				(width 0)
				(type default)
			)
			(fill yes)
			(layer "F.Paste")
		)
		(fp_line
			(start -1.05 -1.2)
			(end 1.05 -1.2)
			(stroke
				(width 0.2)
				(type solid)
			)
			(layer "F.CrtYd")
		)
		(fp_line
			(start -1.05 1.2)
			(end -1.05 -1.2)
			(stroke
				(width 0.2)
				(type solid)
			)
			(layer "F.CrtYd")
		)
		(fp_line
			(start -1.05 1.2)
			(end 1.05 1.2)
			(stroke
				(width 0.2)
				(type solid)
			)
			(layer "F.CrtYd")
		)
		(fp_line
			(start 1.05 1.2)
			(end 1.05 -1.2)
			(stroke
				(width 0.2)
				(type solid)
			)
			(layer "F.CrtYd")
		)
		(fp_line
			(start -1.05 -1.2)
			(end 1.05 -1.2)
			(stroke
				(width 0.2)
				(type solid)
			)
			(layer "F.Fab")
		)
		(fp_line
			(start -1.05 1.2)
			(end -1.05 -1.2)
			(stroke
				(width 0.2)
				(type solid)
			)
			(layer "F.Fab")
		)
		(fp_line
			(start -1.05 1.2)
			(end 1.05 1.2)
			(stroke
				(width 0.2)
				(type solid)
			)
			(layer "F.Fab")
		)
		(fp_line
			(start -0.5 0)
			(end 0.5 0)
			(stroke
				(width 0.1)
				(type solid)
			)
			(layer "F.Fab")
		)
		(fp_line
			(start 0 0.5)
			(end 0 -0.5)
			(stroke
				(width 0.1)
				(type solid)
			)
			(layer "F.Fab")
		)
		(fp_line
			(start 1.05 1.2)
			(end 1.05 -1.2)
			(stroke
				(width 0.2)
				(type solid)
			)
			(layer "F.Fab")
		)
		(fp_text user "${REFERENCE}"
			(at -0.00001 0.09602 0)
			(unlocked yes)
			(layer "F.Fab")
			(effects
				(font
					(face "Arial")
					(size 0.63 0.63)
					(thickness 0.1)
				)
				(justify left bottom)
			)
		)
		(pad "" smd custom
			(at -0.5 -1.1)
			(size 0.000001 0.000001)
			(layers "F.Cu" "F.Mask")
			(solder_mask_margin 0)
			(thermal_bridge_angle 90)
			(options
				(clearance outline)
				(anchor circle)
			)
			(primitives
				(gr_poly
					(pts
						(xy 0 0) (xy 0.15 0) (xy 0.15 0.4) (xy -0.45 0.4) (xy -0.45 0.2) (xy 0 0.2)
					)
					(width 0)
					(fill yes)
				)
			)
		)
		(pad "1" smd circle
			(at -0.45 -0.8)
			(size 0.18 0.18)
			(layers "F.Cu" "F.Mask" "F.Paste")
			(net "DIP_SW_UART_SEL")
			(solder_mask_margin 0)
			(solder_paste_margin -1000)
			(thermal_bridge_angle 90)
		)
		(pad "2" smd rect
			(at -0.65 -0.4)
			(size 0.6 0.2)
			(layers "F.Cu" "F.Mask" "F.Paste")
			(net "NetR85_2")
			(solder_mask_margin 0)
			(solder_paste_margin -1000)
		)
		(pad "3" smd rect
			(at -0.65 0)
			(size 0.6 0.2)
			(layers "F.Cu" "F.Mask" "F.Paste")
			(net "GND")
			(solder_mask_margin 0)
			(solder_paste_margin -1000)
		)
		(pad "4" smd rect
			(at -0.65 0.4)
			(size 0.6 0.2)
			(layers "F.Cu" "F.Mask" "F.Paste")
			(net "NetR87_2")
			(solder_mask_margin 0)
			(solder_paste_margin -1000)
		)
		(pad "5" smd rect
			(at -0.65 0.8)
			(size 0.6 0.2)
			(layers "F.Cu" "F.Mask" "F.Paste")
			(net "DIP_SW_UART_SEL")
			(solder_mask_margin 0)
			(solder_paste_margin -1000)
		)
		(pad "6" smd rect
			(at 0 0.8)
			(size 0.2 0.6)
			(layers "F.Cu" "F.Mask" "F.Paste")
			(net "GND")
			(solder_mask_margin 0)
			(solder_paste_margin -1000)
		)
		(pad "7" smd rect
			(at 0.65 0.8)
			(size 0.6 0.2)
			(layers "F.Cu" "F.Mask" "F.Paste")
			(net "UART1_RXD")
			(solder_mask_margin 0)
			(solder_paste_margin -1000)
		)
		(pad "8" smd rect
			(at 0.65 0.4)
			(size 0.6 0.2)
			(layers "F.Cu" "F.Mask" "F.Paste")
			(net "NetR86_2")
			(solder_mask_margin 0)
			(solder_paste_margin -1000)
		)
		(pad "9" smd rect
			(at 0.65 0)
			(size 0.6 0.2)
			(layers "F.Cu" "F.Mask" "F.Paste")
			(net "+3.3V")
			(solder_mask_margin 0)
			(solder_paste_margin -1000)
		)
		(pad "10" smd rect
			(at 0.65 -0.4)
			(size 0.6 0.2)
			(layers "F.Cu" "F.Mask" "F.Paste")
			(net "NetR84_2")
			(solder_mask_margin 0)
			(solder_paste_margin -1000)
		)
		(pad "11" smd rect
			(at 0.65 -0.8)
			(size 0.6 0.2)
			(layers "F.Cu" "F.Mask" "F.Paste")
			(net "UART1_TXD")
			(solder_mask_margin 0)
			(solder_paste_margin -1000)
		)
		(pad "12" smd rect
			(at 0 -0.8)
			(size 0.2 0.6)
			(layers "F.Cu" "F.Mask" "F.Paste")
			(net "GND")
			(solder_mask_margin 0)
			(solder_paste_margin -1000)
		)
	)
	(footprint "Vault:RESC1005X40X25NL05T05"
		(layer "F.Cu")
		(at 154.0216 113.2162)
		(property "Reference" "R74"
			(at -2.1714 0.126931 0)
			(unlocked yes)
			(layer "F.SilkS")
			(effects
				(font
					(size 0.762 0.762)
					(thickness 0.2286)
				)
			)
		)
		(property "Value" "DNI_27_1%_0402"
			(at -2.884671 8.544305 270)
			(unlocked yes)
			(layer "F.SilkS")
			(hide yes)
			(effects
				(font
					(size 0.762 0.762)
					(thickness 0.2286)
				)
			)
		)
		(sheetname "08-DIPSwitches_I2C")
		(sheetfile "08-DIPSwitches_I2C.kicad_sch")
		(duplicate_pad_numbers_are_jumpers no)
		(pad "1" smd rect
			(at -0.45 0 90)
			(size 0.55 0.55)
			(layers "F.Cu" "F.Mask" "F.Paste")
			(net "FPGA_MAC_UART_TX")
		)
		(pad "2" smd rect
			(at 0.45 0 90)
			(size 0.55 0.55)
			(layers "F.Cu" "F.Mask" "F.Paste")
			(net "MAC_TX")
		)
	)
	(footprint "Vault:CAPC1608X87X45ML20T05"
		(layer "F.Cu")
		(at 105.45022 83.17365)
		(property "Reference" "C31"
			(at 2.651465 -0.026931 180)
			(unlocked yes)
			(layer "F.SilkS")
			(effects
				(font
					(size 0.762 0.762)
					(thickness 0.2286)
				)
			)
		)
		(property "Value" "0.1uF"
			(at 2.069025 2.630671 0)
			(unlocked yes)
			(layer "F.SilkS")
			(hide yes)
			(effects
				(font
					(size 0.762 0.762)
					(thickness 0.2286)
				)
			)
		)
		(sheetname "05-GPS_IMU_SENSORS")
		(sheetfile "05-GPS_IMU_SENSORS.kicad_sch")
		(duplicate_pad_numbers_are_jumpers no)
		(pad "1" smd rect
			(at -0.7 0 90)
			(size 1.1 1.05)
			(layers "F.Cu" "F.Mask" "F.Paste")
			(net "GND")
		)
		(pad "2" smd rect
			(at 0.7 0 90)
			(size 1.1 1.05)
			(layers "F.Cu" "F.Mask" "F.Paste")
			(net "+3.3V")
		)
	)
	(footprint "GNSS:GNSS Header 16-pin"
		(locked yes)
		(layer "F.Cu")
		(at 215.0592 140.4387 90)
		(property "Reference" "J13"
			(at 5.1939 1.735469 270)
			(unlocked yes)
			(layer "F.SilkS")
			(effects
				(font
					(size 0.762 0.762)
					(thickness 0.2286)
				)
			)
		)
		(property "Value" "GNSS Header 16-pin"
			(at 6.740165 4.840511 90)
			(unlocked yes)
			(layer "F.SilkS")
			(hide yes)
			(effects
				(font
					(size 0.762 0.762)
					(thickness 0.2286)
				)
			)
		)
		(sheetname "05-GPS_IMU_SENSORS")
		(sheetfile "05-GPS_IMU_SENSORS.kicad_sch")
		(duplicate_pad_numbers_are_jumpers no)
		(fp_line
			(start 8.5 -7.5)
			(end 8.5 0.5)
			(stroke
				(width 0.0254)
				(type solid)
			)
			(layer "F.SilkS")
		)
		(fp_line
			(start -0.5 -7.5)
			(end 8.5 -7.5)
			(stroke
				(width 0.0254)
				(type solid)
			)
			(layer "F.SilkS")
		)
		(fp_line
			(start -0.5 -7.5)
			(end -0.5 0.5)
			(stroke
				(width 0.0254)
				(type solid)
			)
			(layer "F.SilkS")
		)
		(fp_line
			(start -0.5 0.5)
			(end 8.5 0.5)
			(stroke
				(width 0.0254)
				(type solid)
			)
			(layer "F.SilkS")
		)
		(fp_circle
			(center 0 -0.5)
			(end 0.0254 -0.5)
			(stroke
				(width 0.508)
				(type solid)
			)
			(fill no)
			(layer "F.SilkS")
		)
		(fp_text user "Orig 2x4"
			(at 7.664175 -6.06619 360)
			(unlocked yes)
			(layer "F.SilkS")
			(effects
				(font
					(size 0.762 0.762)
					(thickness 0.2286)
				)
				(justify left bottom)
			)
		)
		(pad "0" thru_hole circle
			(at 4 -13.49999)
			(size 0 0)
			(drill 0.76)
			(layers "*.Cu" "*.Mask")
			(remove_unused_layers no)
			(thermal_bridge_angle 90)
		)
		(pad "0" thru_hole circle
			(at 4 -1.5)
			(size 0 0)
			(drill 0.76)
			(layers "*.Cu" "*.Mask")
			(remove_unused_layers no)
			(thermal_bridge_angle 90)
		)
		(pad "1" smd rect
			(at 1.7775 -0.5)
			(size 1.12 2.105)
			(layers "F.Cu" "F.Mask" "F.Paste")
			(net "GNSS2_P5V0")
		)
		(pad "2" smd rect
			(at 6.2225 -0.5)
			(size 1.12 2.105)
			(layers "F.Cu" "F.Mask" "F.Paste")
			(net "GNSS2_P3V3")
		)
		(pad "3" smd rect
			(at 1.7775 -2.5)
			(size 1.12 2.105)
			(layers "F.Cu" "F.Mask" "F.Paste")
			(net "RCB_GPS2_TX")
		)
		(pad "4" smd rect
			(at 6.2225 -2.5)
			(size 1.12 2.105)
			(layers "F.Cu" "F.Mask" "F.Paste")
			(net "GPS2_RST")
		)
		(pad "5" smd rect
			(at 1.7775 -4.5)
			(size 1.12 2.105)
			(layers "F.Cu" "F.Mask" "F.Paste")
			(net "RCB_GPS2_RX")
		)
		(pad "6" smd rect
			(at 6.2225 -4.5)
			(size 1.12 2.105)
			(layers "F.Cu" "F.Mask" "F.Paste")
			(net "RCB_GPS2_TP1")
		)
		(pad "7" smd rect
			(at 1.7775 -6.5)
			(size 1.12 2.105)
			(layers "F.Cu" "F.Mask" "F.Paste")
			(net "RCB_GPS2_TP2")
		)
		(pad "8" smd rect
			(at 6.2225 -6.5)
			(size 1.12 2.105)
			(layers "F.Cu" "F.Mask" "F.Paste")
			(net "GND")
		)
		(pad "9" smd rect
			(at 1.7775 -8.50001)
			(size 1.12 2.105)
			(layers "F.Cu" "F.Mask" "F.Paste")
			(net "GNSS2_P5V0")
		)
		(pad "10" smd rect
			(at 6.2225 -8.50001)
			(size 1.12 2.105)
			(layers "F.Cu" "F.Mask" "F.Paste")
			(net "GNSS2_P3V3")
		)
		(pad "11" smd rect
			(at 1.7775 -10.50001)
			(size 1.12 2.105)
			(layers "F.Cu" "F.Mask" "F.Paste")
			(net "RCB_GPS2_PIN11")
		)
		(pad "12" smd rect
			(at 6.2225 -10.50001)
			(size 1.12 2.105)
			(layers "F.Cu" "F.Mask" "F.Paste")
			(net "RCB_GPS2_PIN12")
		)
		(pad "13" smd rect
			(at 1.7775 -12.50001)
			(size 1.12 2.105)
			(layers "F.Cu" "F.Mask" "F.Paste")
			(net "GPS2_PIN13")
		)
		(pad "14" smd rect
			(at 6.2225 -12.50001)
			(size 1.12 2.105)
			(layers "F.Cu" "F.Mask" "F.Paste")
			(net "GPS2_PIN14")
		)
		(pad "15" smd rect
			(at 1.7775 -14.5)
			(size 1.12 2.105)
			(layers "F.Cu" "F.Mask" "F.Paste")
			(net "GPS2_PIN15")
		)
		(pad "16" smd rect
			(at 6.2225 -14.5)
			(size 1.12 2.105)
			(layers "F.Cu" "F.Mask" "F.Paste")
			(net "GND")
		)
	)
	(footprint "Vault:FP-GRM31C-0_2-e0_3_0_8-IPC_C"
		(layer "F.Cu")
		(at 184.7216 84.9162 90)
		(property "Reference" "C76"
			(at 0.46924 -2.601729 90)
			(unlocked yes)
			(layer "F.SilkS")
			(effects
				(font
					(size 0.762 0.762)
					(thickness 0.2286)
				)
			)
		)
		(property "Value" "4.7uF_50V_1206"
			(at 8.594615 2.719551 90)
			(unlocked yes)
			(layer "F.SilkS")
			(hide yes)
			(effects
				(font
					(size 0.762 0.762)
					(thickness 0.2286)
				)
			)
		)
		(sheetname "03-POWER")
		(sheetfile "03-POWER.kicad_sch")
		(duplicate_pad_numbers_are_jumpers no)
		(fp_line
			(start -0.39846 -0.9)
			(end 0.39847 -0.9)
			(stroke
				(width 0.2)
				(type solid)
			)
			(layer "F.SilkS")
		)
		(fp_line
			(start -0.39846 0.9)
			(end 0.39847 0.9)
			(stroke
				(width 0.2)
				(type solid)
			)
			(layer "F.SilkS")
		)
		(fp_line
			(start 1.9531 -1)
			(end 1.9531 1)
			(stroke
				(width 0.2)
				(type solid)
			)
			(layer "F.CrtYd")
		)
		(fp_line
			(start -1.9531 -1)
			(end 1.9531 -1)
			(stroke
				(width 0.2)
				(type solid)
			)
			(layer "F.CrtYd")
		)
		(fp_line
			(start -1.9531 -1)
			(end -1.9531 1)
			(stroke
				(width 0.2)
				(type solid)
			)
			(layer "F.CrtYd")
		)
		(fp_line
			(start -1.9531 1)
			(end 1.9531 1)
			(stroke
				(width 0.2)
				(type solid)
			)
			(layer "F.CrtYd")
		)
		(fp_line
			(start 1.9531 -1)
			(end 1.9531 1)
			(stroke
				(width 0.2)
				(type solid)
			)
			(layer "F.Fab")
		)
		(fp_line
			(start -1.9531 -1)
			(end 1.9531 -1)
			(stroke
				(width 0.2)
				(type solid)
			)
			(layer "F.Fab")
		)
		(fp_line
			(start -1.9531 -1)
			(end -1.9531 1)
			(stroke
				(width 0.2)
				(type solid)
			)
			(layer "F.Fab")
		)
		(fp_line
			(start 0 -0.5)
			(end 0 0.5)
			(stroke
				(width 0.1)
				(type solid)
			)
			(layer "F.Fab")
		)
		(fp_line
			(start -0.5 0)
			(end 0.5 0)
			(stroke
				(width 0.1)
				(type solid)
			)
			(layer "F.Fab")
		)
		(fp_line
			(start -1.9531 1)
			(end 1.9531 1)
			(stroke
				(width 0.2)
				(type solid)
			)
			(layer "F.Fab")
		)
		(fp_text user "${REFERENCE}"
			(at -0.00001 0.09602 90)
			(unlocked yes)
			(layer "F.Fab")
			(effects
				(font
					(face "Arial")
					(size 0.63 0.63)
					(thickness 0.1)
				)
				(justify left bottom)
			)
		)
		(pad "1" smd rect
			(at -1.27578 0 90)
			(size 1.15464 1.7062)
			(layers "F.Cu" "F.Mask" "F.Paste")
			(net "+12V")
			(solder_mask_margin 0)
			(solder_paste_margin 0)
		)
		(pad "2" smd rect
			(at 1.27578 0 90)
			(size 1.15464 1.7062)
			(layers "F.Cu" "F.Mask" "F.Paste")
			(net "GND")
			(solder_mask_margin 0)
			(solder_paste_margin 0)
		)
	)
	(footprint "Vault:RESC1005X40X25NL05T05"
		(layer "F.Cu")
		(at 158.3216 126.5162)
		(property "Reference" "R100"
			(at 0.728869 -1.6714 270)
			(unlocked yes)
			(layer "F.SilkS")
			(effects
				(font
					(size 0.762 0.762)
					(thickness 0.2286)
				)
			)
		)
		(property "Value" "DNI_27_1%_0402"
			(at -2.732271 10.296375 270)
			(unlocked yes)
			(layer "F.SilkS")
			(hide yes)
			(effects
				(font
					(size 0.762 0.762)
					(thickness 0.2286)
				)
			)
		)
		(sheetname "09-USBUart_PPSMUX_UARTMUX")
		(sheetfile "09-USBUart_PPSMUX_UARTMUX.kicad_sch")
		(duplicate_pad_numbers_are_jumpers no)
		(pad "1" smd rect
			(at -0.45 0 90)
			(size 0.55 0.55)
			(layers "F.Cu" "F.Mask" "F.Paste")
			(net "FTDI_RX")
		)
		(pad "2" smd rect
			(at 0.45 0 90)
			(size 0.55 0.55)
			(layers "F.Cu" "F.Mask" "F.Paste")
			(net "UART1_TXD")
		)
	)
	(footprint "Vault:RESC1005X40X25LL05T10"
		(layer "F.Cu")
		(at 117.6216 78.5162 180)
		(property "Reference" "R176"
			(at 2.0968 0.073079 0)
			(unlocked yes)
			(layer "F.SilkS")
			(effects
				(font
					(size 0.762 0.762)
					(thickness 0.2032)
				)
			)
		)
		(property "Value" "49.9_1%_0402"
			(at -2.579871 8.798265 90)
			(unlocked yes)
			(layer "F.SilkS")
			(hide yes)
			(effects
				(font
					(size 0.762 0.762)
					(thickness 0.2032)
				)
			)
		)
		(sheetname "11-M2_RCB_MUX")
		(sheetfile "11-M2_RCB_MUX.kicad_sch")
		(duplicate_pad_numbers_are_jumpers no)
		(pad "1" smd rect
			(at -0.375 0 270)
			(size 0.45 0.5)
			(layers "F.Cu" "F.Mask" "F.Paste")
			(net "NetR176_1")
		)
		(pad "2" smd rect
			(at 0.375 0 270)
			(size 0.45 0.5)
			(layers "F.Cu" "F.Mask" "F.Paste")
			(net "GPS1_PIN11")
		)
	)
	(footprint "FPGA_CONN:SingleFPGAConn"
		(locked yes)
		(layer "F.Cu")
		(at 186.05909 109.97313 180)
		(property "Reference" "J34"
			(at 1.54102 -22.624419 180)
			(unlocked yes)
			(layer "F.SilkS")
			(effects
				(font
					(size 0.762 0.762)
					(thickness 0.2286)
				)
			)
		)
		(property "Value" "Single FPGA Conn"
			(at 9.25453 3.621231 180)
			(unlocked yes)
			(layer "F.SilkS")
			(hide yes)
			(effects
				(font
					(size 0.762 0.762)
					(thickness 0.2286)
				)
			)
		)
		(sheetname "07-FPGA")
		(sheetfile "07-FPGA.kicad_sch")
		(duplicate_pad_numbers_are_jumpers no)
		(fp_line
			(start 2 0.70002)
			(end 1.40005 1.24993)
			(stroke
				(width 0.15011)
				(type solid)
			)
			(layer "F.SilkS")
		)
		(fp_line
			(start 2 0.03302)
			(end 2 0.70002)
			(stroke
				(width 0.15011)
				(type solid)
			)
			(layer "F.SilkS")
		)
		(fp_line
			(start 2 -20.69999)
			(end 2 -20.03298)
			(stroke
				(width 0.15011)
				(type solid)
			)
			(layer "F.SilkS")
		)
		(fp_line
			(start 2 -20.69999)
			(end 1.40005 -21.2499)
			(stroke
				(width 0.15011)
				(type solid)
			)
			(layer "F.SilkS")
		)
		(fp_line
			(start 1.40005 1.24993)
			(end -1.40004 1.24993)
			(stroke
				(width 0.15011)
				(type solid)
			)
			(layer "F.SilkS")
		)
		(fp_line
			(start 1.40005 -21.2499)
			(end -1.40004 -21.2499)
			(stroke
				(width 0.15011)
				(type solid)
			)
			(layer "F.SilkS")
		)
		(fp_line
			(start -1.40004 0.70002)
			(end -1.40004 1.24993)
			(stroke
				(width 0.15011)
				(type solid)
			)
			(layer "F.SilkS")
		)
		(fp_line
			(start -1.40004 0.70002)
			(end -1.99999 0.70002)
			(stroke
				(width 0.15011)
				(type solid)
			)
			(layer "F.SilkS")
		)
		(fp_line
			(start -1.40004 -20.69999)
			(end -1.99999 -20.69999)
			(stroke
				(width 0.15011)
				(type solid)
			)
			(layer "F.SilkS")
		)
		(fp_line
			(start -1.40004 -21.2499)
			(end -1.40004 -20.69999)
			(stroke
				(width 0.15011)
				(type solid)
			)
			(layer "F.SilkS")
		)
		(fp_line
			(start -1.99999 0.03302)
			(end -1.99999 0.70002)
			(stroke
				(width 0.15011)
				(type solid)
			)
			(layer "F.SilkS")
		)
		(fp_line
			(start -1.99999 -20.69999)
			(end -1.99999 -20.03298)
			(stroke
				(width 0.15011)
				(type solid)
			)
			(layer "F.SilkS")
		)
		(fp_circle
			(center 3.5052 -0.22454)
			(end 3.5052 -0.02439)
			(stroke
				(width 0.40005)
				(type solid)
			)
			(fill no)
			(layer "F.SilkS")
		)
		(pad "1" smd rect
			(at 2.02489 -0.24994 180)
			(size 1.54991 0.24994)
			(layers "F.Cu" "F.Mask" "F.Paste")
			(net "+5.0V")
		)
		(pad "2" smd rect
			(at -2.02488 -0.24994 180)
			(size 1.54991 0.24994)
			(layers "F.Cu" "F.Mask" "F.Paste")
			(net "+5.0V")
		)
		(pad "3" smd rect
			(at 2.02489 -0.75007 180)
			(size 1.54991 0.24994)
			(layers "F.Cu" "F.Mask" "F.Paste")
			(net "+5.0V")
		)
		(pad "4" smd rect
			(at -2.02488 -0.75007 180)
			(size 1.54991 0.24994)
			(layers "F.Cu" "F.Mask" "F.Paste")
			(net "+5.0V")
		)
		(pad "5" smd rect
			(at 2.02489 -1.24994 180)
			(size 1.54991 0.24994)
			(layers "F.Cu" "F.Mask" "F.Paste")
			(net "+5.0V")
		)
		(pad "6" smd rect
			(at -2.02488 -1.24994 180)
			(size 1.54991 0.24994)
			(layers "F.Cu" "F.Mask" "F.Paste")
			(net "+5.0V")
		)
		(pad "7" smd rect
			(at 2.02489 -1.75006 180)
			(size 1.54991 0.24994)
			(layers "F.Cu" "F.Mask" "F.Paste")
			(net "+5.0V")
		)
		(pad "8" smd rect
			(at -2.02488 -1.75006 180)
			(size 1.54991 0.24994)
			(layers "F.Cu" "F.Mask" "F.Paste")
			(net "+5.0V")
		)
		(pad "9" smd rect
			(at 2.02489 -2.24994 180)
			(size 1.54991 0.24994)
			(layers "F.Cu" "F.Mask" "F.Paste")
			(net "GND")
		)
		(pad "10" smd rect
			(at -2.02488 -2.24994 180)
			(size 1.54991 0.24994)
			(layers "F.Cu" "F.Mask" "F.Paste")
			(net "GND")
		)
		(pad "11" smd rect
			(at 2.02489 -2.75006 180)
			(size 1.54991 0.24994)
			(layers "F.Cu" "F.Mask" "F.Paste")
		)
		(pad "12" smd rect
			(at -2.02488 -2.75006 180)
			(size 1.54991 0.24994)
			(layers "F.Cu" "F.Mask" "F.Paste")
		)
		(pad "13" smd rect
			(at 2.02489 -3.24993 180)
			(size 1.54991 0.24994)
			(layers "F.Cu" "F.Mask" "F.Paste")
		)
		(pad "14" smd rect
			(at -2.02488 -3.24993 180)
			(size 1.54991 0.24994)
			(layers "F.Cu" "F.Mask" "F.Paste")
		)
		(pad "15" smd rect
			(at 2.02489 -3.75006 180)
			(size 1.54991 0.24994)
			(layers "F.Cu" "F.Mask" "F.Paste")
		)
		(pad "16" smd rect
			(at -2.02488 -3.75006 180)
			(size 1.54991 0.24994)
			(layers "F.Cu" "F.Mask" "F.Paste")
		)
		(pad "17" smd rect
			(at 2.02489 -4.24993 180)
			(size 1.54991 0.24994)
			(layers "F.Cu" "F.Mask" "F.Paste")
		)
		(pad "18" smd rect
			(at -2.02488 -4.24993 180)
			(size 1.54991 0.24994)
			(layers "F.Cu" "F.Mask" "F.Paste")
		)
		(pad "19" smd rect
			(at 2.02489 -4.75006 180)
			(size 1.54991 0.24994)
			(layers "F.Cu" "F.Mask" "F.Paste")
			(net "GND")
		)
		(pad "20" smd rect
			(at -2.02488 -4.75006 180)
			(size 1.54991 0.24994)
			(layers "F.Cu" "F.Mask" "F.Paste")
			(net "GND")
		)
		(pad "21" smd rect
			(at 2.02489 -5.24993 180)
			(size 1.54991 0.24994)
			(layers "F.Cu" "F.Mask" "F.Paste")
		)
		(pad "22" smd rect
			(at -2.02488 -5.24993 180)
			(size 1.54991 0.24994)
			(layers "F.Cu" "F.Mask" "F.Paste")
			(net "GPS1_RST")
		)
		(pad "23" smd rect
			(at 2.02489 -5.75006 180)
			(size 1.54991 0.24994)
			(layers "F.Cu" "F.Mask" "F.Paste")
		)
		(pad "24" smd rect
			(at -2.02488 -5.75006 180)
			(size 1.54991 0.24994)
			(layers "F.Cu" "F.Mask" "F.Paste")
		)
		(pad "25" smd rect
			(at 2.02489 -6.24993 180)
			(size 1.54991 0.24994)
			(layers "F.Cu" "F.Mask" "F.Paste")
		)
		(pad "26" smd rect
			(at -2.02488 -6.24993 180)
			(size 1.54991 0.24994)
			(layers "F.Cu" "F.Mask" "F.Paste")
		)
		(pad "27" smd rect
			(at 2.02489 -6.75005 180)
			(size 1.54991 0.24994)
			(layers "F.Cu" "F.Mask" "F.Paste")
		)
		(pad "28" smd rect
			(at -2.02488 -6.75005 180)
			(size 1.54991 0.24994)
			(layers "F.Cu" "F.Mask" "F.Paste")
		)
		(pad "29" smd rect
			(at 2.02489 -7.24993 180)
			(size 1.54991 0.24994)
			(layers "F.Cu" "F.Mask" "F.Paste")
			(net "GND")
		)
		(pad "30" smd rect
			(at -2.02488 -7.24993 180)
			(size 1.54991 0.24994)
			(layers "F.Cu" "F.Mask" "F.Paste")
			(net "GND")
		)
		(pad "31" smd rect
			(at 2.02489 -7.75005 180)
			(size 1.54991 0.24994)
			(layers "F.Cu" "F.Mask" "F.Paste")
		)
		(pad "32" smd rect
			(at -2.02488 -7.75005 180)
			(size 1.54991 0.24994)
			(layers "F.Cu" "F.Mask" "F.Paste")
			(net "GPS1_TP1")
		)
		(pad "33" smd rect
			(at 2.02489 -8.24992 180)
			(size 1.54991 0.24994)
			(layers "F.Cu" "F.Mask" "F.Paste")
		)
		(pad "34" smd rect
			(at -2.02488 -8.24992 180)
			(size 1.54991 0.24994)
			(layers "F.Cu" "F.Mask" "F.Paste")
			(net "GPS1_TP2")
		)
		(pad "35" smd rect
			(at 2.02489 -8.75005 180)
			(size 1.54991 0.24994)
			(layers "F.Cu" "F.Mask" "F.Paste")
		)
		(pad "36" smd rect
			(at -2.02488 -8.75005 180)
			(size 1.54991 0.24994)
			(layers "F.Cu" "F.Mask" "F.Paste")
		)
		(pad "37" smd rect
			(at 2.02489 -9.24992 180)
			(size 1.54991 0.24994)
			(layers "F.Cu" "F.Mask" "F.Paste")
		)
		(pad "38" smd rect
			(at -2.02488 -9.24992 180)
			(size 1.54991 0.24994)
			(layers "F.Cu" "F.Mask" "F.Paste")
		)
		(pad "39" smd rect
			(at 2.02489 -9.75005 180)
			(size 1.54991 0.24994)
			(layers "F.Cu" "F.Mask" "F.Paste")
			(net "GND")
		)
		(pad "40" smd rect
			(at -2.02488 -9.75005 180)
			(size 1.54991 0.24994)
			(layers "F.Cu" "F.Mask" "F.Paste")
			(net "GND")
		)
		(pad "41" smd rect
			(at 2.02489 -10.24992 180)
			(size 1.54991 0.24994)
			(layers "F.Cu" "F.Mask" "F.Paste")
		)
		(pad "42" smd rect
			(at -2.02488 -10.24992 180)
			(size 1.54991 0.24994)
			(layers "F.Cu" "F.Mask" "F.Paste")
		)
		(pad "43" smd rect
			(at 2.02489 -10.75005 180)
			(size 1.54991 0.24994)
			(layers "F.Cu" "F.Mask" "F.Paste")
		)
		(pad "44" smd rect
			(at -2.02488 -10.75005 180)
			(size 1.54991 0.24994)
			(layers "F.Cu" "F.Mask" "F.Paste")
			(net "EXT_EEPROM_WP")
		)
		(pad "45" smd rect
			(at 2.02489 -11.24992 180)
			(size 1.54991 0.24994)
			(layers "F.Cu" "F.Mask" "F.Paste")
		)
		(pad "46" smd rect
			(at -2.02488 -11.24992 180)
			(size 1.54991 0.24994)
			(layers "F.Cu" "F.Mask" "F.Paste")
		)
		(pad "47" smd rect
			(at 2.02489 -11.75004 180)
			(size 1.54991 0.24994)
			(layers "F.Cu" "F.Mask" "F.Paste")
		)
		(pad "48" smd rect
			(at -2.02488 -11.75004 180)
			(size 1.54991 0.24994)
			(layers "F.Cu" "F.Mask" "F.Paste")
		)
		(pad "49" smd rect
			(at 2.02489 -12.24992 180)
			(size 1.54991 0.24994)
			(layers "F.Cu" "F.Mask" "F.Paste")
			(net "GND")
		)
		(pad "50" smd rect
			(at -2.02488 -12.24992 180)
			(size 1.54991 0.24994)
			(layers "F.Cu" "F.Mask" "F.Paste")
			(net "GND")
		)
		(pad "51" smd rect
			(at 2.02489 -12.75004 180)
			(size 1.54991 0.24994)
			(layers "F.Cu" "F.Mask" "F.Paste")
		)
		(pad "52" smd rect
			(at -2.02488 -12.75004 180)
			(size 1.54991 0.24994)
			(layers "F.Cu" "F.Mask" "F.Paste")
		)
		(pad "53" smd rect
			(at 2.02489 -13.24991 180)
			(size 1.54991 0.24994)
			(layers "F.Cu" "F.Mask" "F.Paste")
		)
		(pad "54" smd rect
			(at -2.02488 -13.24991 180)
			(size 1.54991 0.24994)
			(layers "F.Cu" "F.Mask" "F.Paste")
		)
		(pad "55" smd rect
			(at 2.02489 -13.75004 180)
			(size 1.54991 0.24994)
			(layers "F.Cu" "F.Mask" "F.Paste")
		)
		(pad "56" smd rect
			(at -2.02488 -13.75004 180)
			(size 1.54991 0.24994)
			(layers "F.Cu" "F.Mask" "F.Paste")
		)
		(pad "57" smd rect
			(at 2.02489 -14.24991 180)
			(size 1.54991 0.24994)
			(layers "F.Cu" "F.Mask" "F.Paste")
		)
		(pad "58" smd rect
			(at -2.02488 -14.24991 180)
			(size 1.54991 0.24994)
			(layers "F.Cu" "F.Mask" "F.Paste")
		)
		(pad "59" smd rect
			(at 2.02489 -14.75004 180)
			(size 1.54991 0.24994)
			(layers "F.Cu" "F.Mask" "F.Paste")
			(net "GND")
		)
		(pad "60" smd rect
			(at -2.02488 -14.75004 180)
			(size 1.54991 0.24994)
			(layers "F.Cu" "F.Mask" "F.Paste")
			(net "GND")
		)
		(pad "61" smd rect
			(at 2.02489 -15.24991 180)
			(size 1.54991 0.24994)
			(layers "F.Cu" "F.Mask" "F.Paste")
		)
		(pad "62" smd rect
			(at -2.02488 -15.24991 180)
			(size 1.54991 0.24994)
			(layers "F.Cu" "F.Mask" "F.Paste")
		)
		(pad "63" smd rect
			(at 2.02489 -15.75004 180)
			(size 1.54991 0.24994)
			(layers "F.Cu" "F.Mask" "F.Paste")
		)
		(pad "64" smd rect
			(at -2.02488 -15.75004 180)
			(size 1.54991 0.24994)
			(layers "F.Cu" "F.Mask" "F.Paste")
		)
		(pad "65" smd rect
			(at 2.02489 -16.24991 180)
			(size 1.54991 0.24994)
			(layers "F.Cu" "F.Mask" "F.Paste")
		)
		(pad "66" smd rect
			(at -2.02488 -16.24991 180)
			(size 1.54991 0.24994)
			(layers "F.Cu" "F.Mask" "F.Paste")
		)
		(pad "67" smd rect
			(at 2.02489 -16.75003 180)
			(size 1.54991 0.24994)
			(layers "F.Cu" "F.Mask" "F.Paste")
			(net "KEY2")
		)
		(pad "68" smd rect
			(at -2.02488 -16.75003 180)
			(size 1.54991 0.24994)
			(layers "F.Cu" "F.Mask" "F.Paste")
		)
		(pad "69" smd rect
			(at 2.02489 -17.24991 180)
			(size 1.54991 0.24994)
			(layers "F.Cu" "F.Mask" "F.Paste")
			(net "GND")
		)
		(pad "70" smd rect
			(at -2.02488 -17.24991 180)
			(size 1.54991 0.24994)
			(layers "F.Cu" "F.Mask" "F.Paste")
			(net "GND")
		)
		(pad "71" smd rect
			(at 2.02489 -17.75003 180)
			(size 1.54991 0.24994)
			(layers "F.Cu" "F.Mask" "F.Paste")
			(net "LED4")
		)
		(pad "72" smd rect
			(at -2.02488 -17.75003 180)
			(size 1.54991 0.24994)
			(layers "F.Cu" "F.Mask" "F.Paste")
		)
		(pad "73" smd rect
			(at 2.02489 -18.2499 180)
			(size 1.54991 0.24994)
			(layers "F.Cu" "F.Mask" "F.Paste")
			(net "LED3")
		)
		(pad "74" smd rect
			(at -2.02488 -18.2499 180)
			(size 1.54991 0.24994)
			(layers "F.Cu" "F.Mask" "F.Paste")
		)
		(pad "75" smd rect
			(at 2.02489 -18.75003 180)
			(size 1.54991 0.24994)
			(layers "F.Cu" "F.Mask" "F.Paste")
			(net "LED2")
		)
		(pad "76" smd rect
			(at -2.02488 -18.75003 180)
			(size 1.54991 0.24994)
			(layers "F.Cu" "F.Mask" "F.Paste")
		)
		(pad "77" smd rect
			(at 2.02489 -19.2499 180)
			(size 1.54991 0.24994)
			(layers "F.Cu" "F.Mask" "F.Paste")
			(net "LED1")
		)
		(pad "78" smd rect
			(at -2.02488 -19.2499 180)
			(size 1.54991 0.24994)
			(layers "F.Cu" "F.Mask" "F.Paste")
		)
		(pad "79" smd rect
			(at 2.02489 -19.75003 180)
			(size 1.54991 0.24994)
			(layers "F.Cu" "F.Mask" "F.Paste")
		)
		(pad "80" smd rect
			(at -2.02488 -19.75003 180)
			(size 1.54991 0.24994)
			(layers "F.Cu" "F.Mask" "F.Paste")
		)
		(pad "81" smd rect
			(at 0.01136 1.17626 180)
			(size 1.70002 1.35001)
			(layers "F.Cu" "F.Mask" "F.Paste")
		)
		(pad "82" thru_hole circle
			(at 0 0 180)
			(size 0.55016 0.55016)
			(drill 0.55016)
			(layers "*.Cu" "*.Mask")
			(remove_unused_layers no)
			(thermal_bridge_angle 90)
		)
		(pad "83" thru_hole circle
			(at 0 -19.99996 180)
			(size 0.55016 0.55016)
			(drill 0.55016)
			(layers "*.Cu" "*.Mask")
			(remove_unused_layers no)
			(thermal_bridge_angle 90)
		)
		(pad "84" smd rect
			(at 0.01136 -21.17375 180)
			(size 1.70002 1.35001)
			(layers "F.Cu" "F.Mask" "F.Paste")
		)
	)
	(footprint "Vault:RESC1005X40X25NL10T10"
		(layer "F.Cu")
		(at 78.5216 115.9162)
		(property "Reference" "R29"
			(at -2.5 1.593345 0)
			(unlocked yes)
			(layer "F.SilkS")
			(effects
				(font
					(size 0.762 0.762)
					(thickness 0.2286)
				)
				(justify left bottom)
			)
		)
		(property "Value" "4.7K_1%_0402"
			(at -0.4445 3.636645 0)
			(unlocked yes)
			(layer "F.SilkS")
			(hide yes)
			(effects
				(font
					(size 0.762 0.762)
					(thickness 0.2286)
				)
				(justify left bottom)
			)
		)
		(sheetname "01-USER_IO")
		(sheetfile "01-USER_IO.kicad_sch")
		(duplicate_pad_numbers_are_jumpers no)
		(pad "1" smd rect
			(at -0.425 0 90)
			(size 0.6 0.65)
			(layers "F.Cu" "F.Mask" "F.Paste")
			(net "+3.3V")
		)
		(pad "2" smd rect
			(at 0.425 0 90)
			(size 0.6 0.65)
			(layers "F.Cu" "F.Mask" "F.Paste")
			(net "ANT2_IO_OUT")
		)
	)
	(footprint "Resistors:RESC2012X50N"
		(layer "F.Cu")
		(at 216.8416 145.71545)
		(property "Reference" "R20"
			(at -1.2 -1.506645 0)
			(unlocked yes)
			(layer "F.SilkS")
			(effects
				(font
					(size 0.762 0.762)
					(thickness 0.2286)
				)
				(justify left bottom)
			)
		)
		(property "Value" "CRCW080533R0FKEA"
			(at 4.25585 -6.908405 0)
			(unlocked yes)
			(layer "F.SilkS")
			(hide yes)
			(effects
				(font
					(size 0.762 0.762)
					(thickness 0.2286)
				)
				(justify left bottom)
			)
		)
		(sheetname "04-PCIe_JTAG")
		(sheetfile "04-PCIe_JTAG.kicad_sch")
		(duplicate_pad_numbers_are_jumpers no)
		(fp_line
			(start 0 0.762)
			(end 0 -0.762)
			(stroke
				(width 0.1524)
				(type solid)
			)
			(layer "F.SilkS")
		)
		(pad "1" smd rect
			(at -1 0 90)
			(size 1.45 0.95)
			(layers "F.Cu" "F.Mask" "F.Paste")
			(net "FPGA_TMS")
		)
		(pad "2" smd rect
			(at 1 0 90)
			(size 1.45 0.95)
			(layers "F.Cu" "F.Mask" "F.Paste")
			(net "NetP4_5")
		)
	)
	(footprint "Vault:RESC1005X40X25NL05T05"
		(layer "F.Cu")
		(at 150.6216 130.4162)
		(property "Reference" "R93"
			(at -2.1714 0.226921 0)
			(unlocked yes)
			(layer "F.SilkS")
			(effects
				(font
					(size 0.762 0.762)
					(thickness 0.2286)
				)
			)
		)
		(property "Value" "27_1%_0402"
			(at -2.732271 7.37632 270)
			(unlocked yes)
			(layer "F.SilkS")
			(hide yes)
			(effects
				(font
					(size 0.762 0.762)
					(thickness 0.2286)
				)
			)
		)
		(sheetname "09-USBUart_PPSMUX_UARTMUX")
		(sheetfile "09-USBUart_PPSMUX_UARTMUX.kicad_sch")
		(duplicate_pad_numbers_are_jumpers no)
		(pad "1" smd rect
			(at -0.45 0 90)
			(size 0.55 0.55)
			(layers "F.Cu" "F.Mask" "F.Paste")
			(net "GPS2_RX_FPGA")
		)
		(pad "2" smd rect
			(at 0.45 0 90)
			(size 0.55 0.55)
			(layers "F.Cu" "F.Mask" "F.Paste")
			(net "NetR93_2")
		)
	)
	(footprint "Vault:RESC1005X40X25NL05T05"
		(layer "F.Cu")
		(at 166.7216 115.2162)
		(property "Reference" "R128"
			(at -2.5968 0.126921 0)
			(unlocked yes)
			(layer "F.SilkS")
			(effects
				(font
					(size 0.762 0.762)
					(thickness 0.2032)
				)
			)
		)
		(property "Value" "27_1%_0402"
			(at -2.732271 7.35092 270)
			(unlocked yes)
			(layer "F.SilkS")
			(hide yes)
			(effects
				(font
					(size 0.762 0.762)
					(thickness 0.2032)
				)
			)
		)
		(sheetname "08-DIPSwitches_I2C")
		(sheetfile "08-DIPSwitches_I2C.kicad_sch")
		(duplicate_pad_numbers_are_jumpers no)
		(pad "1" smd rect
			(at -0.45 0 90)
			(size 0.55 0.55)
			(layers "F.Cu" "F.Mask" "F.Paste")
			(net "GND")
		)
		(pad "2" smd rect
			(at 0.45 0 90)
			(size 0.55 0.55)
			(layers "F.Cu" "F.Mask" "F.Paste")
			(net "NetR128_2")
		)
	)
	(footprint "Vault:RESC1608X55X25NL10T15"
		(layer "F.Cu")
		(at 75.0216 111.8162 90)
		(property "Reference" "R33"
			(at -0.3286 1.073069 270)
			(unlocked yes)
			(layer "F.SilkS")
			(effects
				(font
					(size 0.762 0.762)
					(thickness 0.2286)
				)
			)
		)
		(property "Value" "49.9R"
			(at -2.884671 3.186585 0)
			(unlocked yes)
			(layer "F.SilkS")
			(hide yes)
			(effects
				(font
					(size 0.762 0.762)
					(thickness 0.2286)
				)
			)
		)
		(sheetname "01-USER_IO")
		(sheetfile "01-USER_IO.kicad_sch")
		(duplicate_pad_numbers_are_jumpers no)
		(pad "1" smd rect
			(at -0.7 0 180)
			(size 0.9 0.7)
			(layers "F.Cu" "F.Mask" "F.Paste")
			(net "NetR33_1")
		)
		(pad "2" smd rect
			(at 0.7 0 180)
			(size 0.9 0.7)
			(layers "F.Cu" "F.Mask" "F.Paste")
			(net "NetAN2_1")
		)
	)
	(footprint "Vault:CAPC1608X87X45ML20T05"
		(layer "F.Cu")
		(at 105.46635 84.61749)
		(property "Reference" "C30"
			(at -0.5786 2.235469 180)
			(unlocked yes)
			(layer "F.SilkS")
			(effects
				(font
					(size 0.762 0.762)
					(thickness 0.2286)
				)
			)
		)
		(property "Value" "0.1uF"
			(at 2.069035 2.630671 0)
			(unlocked yes)
			(layer "F.SilkS")
			(hide yes)
			(effects
				(font
					(size 0.762 0.762)
					(thickness 0.2286)
				)
			)
		)
		(sheetname "05-GPS_IMU_SENSORS")
		(sheetfile "05-GPS_IMU_SENSORS.kicad_sch")
		(duplicate_pad_numbers_are_jumpers no)
		(pad "1" smd rect
			(at -0.7 0 90)
			(size 1.1 1.05)
			(layers "F.Cu" "F.Mask" "F.Paste")
			(net "GND")
		)
		(pad "2" smd rect
			(at 0.7 0 90)
			(size 1.1 1.05)
			(layers "F.Cu" "F.Mask" "F.Paste")
			(net "+3.3V")
		)
	)
	(footprint "Vault:MOLX-47589-0001_V"
		(layer "F.Cu")
		(at 228.1216 126.2412 90)
		(property "Reference" "J43"
			(at 15.123929 -0.16576 0)
			(unlocked yes)
			(layer "F.SilkS")
			(effects
				(font
					(size 0.762 0.762)
					(thickness 0.2032)
				)
			)
		)
		(property "Value" "47589-0001"
			(at -7.101071 4.9126 0)
			(unlocked yes)
			(layer "F.SilkS")
			(hide yes)
			(effects
				(font
					(size 0.762 0.762)
					(thickness 0.2032)
				)
			)
		)
		(sheetname "09-USBUart_PPSMUX_UARTMUX")
		(sheetfile "09-USBUart_PPSMUX_UARTMUX.kicad_sch")
		(duplicate_pad_numbers_are_jumpers no)
		(fp_line
			(start 3.75 -1.35)
			(end 3.75 0.15)
			(stroke
				(width 0.2)
				(type solid)
			)
			(layer "F.SilkS")
		)
		(fp_line
			(start 3.2 -1.35)
			(end 3.75 -1.35)
			(stroke
				(width 0.2)
				(type solid)
			)
			(layer "F.SilkS")
		)
		(fp_line
			(start -3.75 -1.35)
			(end -3.2 -1.35)
			(stroke
				(width 0.2)
				(type solid)
			)
			(layer "F.SilkS")
		)
		(fp_line
			(start -3.75 -1.35)
			(end -3.75 0.15)
			(stroke
				(width 0.2)
				(type solid)
			)
			(layer "F.SilkS")
		)
		(fp_line
			(start 3.75 2.85)
			(end 3.75 4.25)
			(stroke
				(width 0.2)
				(type solid)
			)
			(layer "F.SilkS")
		)
		(fp_line
			(start -3.75 2.85)
			(end -3.75 4.25)
			(stroke
				(width 0.2)
				(type solid)
			)
			(layer "F.SilkS")
		)
		(fp_line
			(start -3.75 4.25)
			(end 3.75 4.25)
			(stroke
				(width 0.2)
				(type solid)
			)
			(layer "F.SilkS")
		)
		(fp_circle
			(center -1.3 -2.4)
			(end -1.175 -2.4)
			(stroke
				(width 0.25)
				(type solid)
			)
			(fill no)
			(layer "F.SilkS")
		)
		(pad "1" smd rect
			(at -1.3 -1.175 270)
			(size 0.4 1.35)
			(layers "F.Cu" "F.Mask" "F.Paste")
			(net "USB_VBUS")
		)
		(pad "2" smd rect
			(at -0.65 -1.175 270)
			(size 0.4 1.35)
			(layers "F.Cu" "F.Mask" "F.Paste")
			(net "FTDI_USB_R_N")
		)
		(pad "3" smd rect
			(at 0 -1.175 90)
			(size 0.4 1.35)
			(layers "F.Cu" "F.Mask" "F.Paste")
			(net "FTDI_USB_R_P")
		)
		(pad "4" smd rect
			(at 0.65 -1.175 90)
			(size 0.4 1.35)
			(layers "F.Cu" "F.Mask" "F.Paste")
		)
		(pad "5" smd rect
			(at 1.3 -1.175 90)
			(size 0.4 1.35)
			(layers "F.Cu" "F.Mask" "F.Paste")
			(net "GND")
		)
		(pad "6" thru_hole oval
			(at -2.225 -1.5 180)
			(size 1.25 1.05)
			(drill oval 0.85 0.65)
			(layers "*.Cu" "*.Mask")
			(remove_unused_layers no)
			(net "GND")
		)
		(pad "7" thru_hole oval
			(at 2.225 -1.5 180)
			(size 1.25 1.05)
			(drill oval 0.85 0.65)
			(layers "*.Cu" "*.Mask")
			(remove_unused_layers no)
			(net "GND")
		)
		(pad "8" thru_hole oval
			(at -4.175 1.5 180)
			(size 1.9 1.2)
			(drill oval 1.3 0.6)
			(layers "*.Cu" "*.Mask")
			(remove_unused_layers no)
			(net "GND")
		)
		(pad "9" smd rect
			(at -1.15 1.5 90)
			(size 1.8 1.9)
			(layers "F.Cu" "F.Mask" "F.Paste")
			(net "GND")
		)
		(pad "10" smd rect
			(at 1.15 1.5 270)
			(size 1.8 1.9)
			(layers "F.Cu" "F.Mask" "F.Paste")
			(net "GND")
		)
		(pad "11" thru_hole oval
			(at 4.175 1.5 180)
			(size 1.9 1.2)
			(drill oval 1.3 0.6)
			(layers "*.Cu" "*.Mask")
			(remove_unused_layers no)
			(net "GND")
		)
	)
	(footprint "Passives:SOT65P210X110-3N"
		(layer "F.Cu")
		(at 212.3666 145.56546)
		(property "Reference" "D7"
			(at -0.345 -1.355915 0)
			(unlocked yes)
			(layer "F.SilkS")
			(effects
				(font
					(size 0.762 0.762)
					(thickness 0.2286)
				)
				(justify left bottom)
			)
		)
		(property "Value" "BAT54SW"
			(at 5.35585 -2.652805 0)
			(unlocked yes)
			(layer "F.SilkS")
			(hide yes)
			(effects
				(font
					(size 0.762 0.762)
					(thickness 0.2286)
				)
				(justify left bottom)
			)
		)
		(sheetname "04-PCIe_JTAG")
		(sheetfile "04-PCIe_JTAG.kicad_sch")
		(duplicate_pad_numbers_are_jumpers no)
		(fp_line
			(start -0.325 -1.1)
			(end 0.675 -1.1)
			(stroke
				(width 0.2)
				(type solid)
			)
			(layer "F.SilkS")
		)
		(fp_line
			(start -0.325 1.1)
			(end 0.675 1.1)
			(stroke
				(width 0.2)
				(type solid)
			)
			(layer "F.SilkS")
		)
		(fp_line
			(start 0.675 -0.65)
			(end 0.675 -1.1)
			(stroke
				(width 0.2)
				(type solid)
			)
			(layer "F.SilkS")
		)
		(fp_line
			(start 0.675 1.1)
			(end 0.675 0.65)
			(stroke
				(width 0.2)
				(type solid)
			)
			(layer "F.SilkS")
		)
		(fp_circle
			(center -1.125 -1.45)
			(end -1.125 -1.575)
			(stroke
				(width 0.25)
				(type solid)
			)
			(fill no)
			(layer "F.SilkS")
		)
		(pad "1" smd rect
			(at -1.125 -0.65 90)
			(size 0.5 0.9)
			(layers "F.Cu" "F.Mask" "F.Paste")
			(net "GND")
		)
		(pad "2" smd rect
			(at -1.125 0.65 90)
			(size 0.5 0.9)
			(layers "F.Cu" "F.Mask" "F.Paste")
			(net "+3.3V")
		)
		(pad "3" smd rect
			(at 1.125 0 90)
			(size 0.5 0.9)
			(layers "F.Cu" "F.Mask" "F.Paste")
			(net "FPGA_TMS")
		)
	)
	(footprint "Vault:FP-CC0402-MFG"
		(layer "F.Cu")
		(at 224.0216 129.3162 180)
		(property "Reference" "C86"
			(at 2.3714 -0.026921 0)
			(unlocked yes)
			(layer "F.SilkS")
			(effects
				(font
					(size 0.762 0.762)
					(thickness 0.2286)
				)
			)
		)
		(property "Value" "10nF_50V_0402"
			(at -2.592551 9.22982 90)
			(unlocked yes)
			(layer "F.SilkS")
			(hide yes)
			(effects
				(font
					(size 0.762 0.762)
					(thickness 0.2286)
				)
			)
		)
		(sheetname "09-USBUart_PPSMUX_UARTMUX")
		(sheetfile "09-USBUart_PPSMUX_UARTMUX.kicad_sch")
		(duplicate_pad_numbers_are_jumpers no)
		(fp_line
			(start 0.525 -0.675)
			(end -0.525 -0.675)
			(stroke
				(width 0.2)
				(type solid)
			)
			(layer "F.SilkS")
		)
		(fp_line
			(start 0.51967 0.68067)
			(end -0.53033 0.68067)
			(stroke
				(width 0.2)
				(type solid)
			)
			(layer "F.SilkS")
		)
		(fp_line
			(start 0.875 0.475)
			(end -0.875 0.475)
			(stroke
				(width 0.2)
				(type solid)
			)
			(layer "F.CrtYd")
		)
		(fp_line
			(start 0.875 -0.475)
			(end 0.875 0.475)
			(stroke
				(width 0.2)
				(type solid)
			)
			(layer "F.CrtYd")
		)
		(fp_line
			(start 0.875 -0.475)
			(end -0.875 -0.475)
			(stroke
				(width 0.2)
				(type solid)
			)
			(layer "F.CrtYd")
		)
		(fp_line
			(start -0.875 -0.475)
			(end -0.875 0.475)
			(stroke
				(width 0.2)
				(type solid)
			)
			(layer "F.CrtYd")
		)
		(fp_line
			(start 0.875 0.475)
			(end -0.875 0.475)
			(stroke
				(width 0.2)
				(type solid)
			)
			(layer "F.Fab")
		)
		(fp_line
			(start 0.875 -0.475)
			(end 0.875 0.475)
			(stroke
				(width 0.2)
				(type solid)
			)
			(layer "F.Fab")
		)
		(fp_line
			(start 0.875 -0.475)
			(end -0.875 -0.475)
			(stroke
				(width 0.2)
				(type solid)
			)
			(layer "F.Fab")
		)
		(fp_line
			(start 0.5 0)
			(end -0.5 0)
			(stroke
				(width 0.1)
				(type solid)
			)
			(layer "F.Fab")
		)
		(fp_line
			(start 0 -0.5)
			(end 0 0.5)
			(stroke
				(width 0.1)
				(type solid)
			)
			(layer "F.Fab")
		)
		(fp_line
			(start -0.875 -0.475)
			(end -0.875 0.475)
			(stroke
				(width 0.2)
				(type solid)
			)
			(layer "F.Fab")
		)
		(fp_text user "${REFERENCE}"
			(at -0.00001 0.09601 180)
			(unlocked yes)
			(layer "F.Fab")
			(effects
				(font
					(face "Arial")
					(size 0.63 0.63)
					(thickness 0.1)
				)
				(justify left bottom)
			)
		)
		(pad "1" smd rect
			(at -0.5 0 180)
			(size 0.5 0.5)
			(layers "F.Cu" "F.Mask" "F.Paste")
			(net "USB_VBUS")
			(solder_mask_margin 0)
			(solder_paste_margin 0)
		)
		(pad "2" smd rect
			(at 0.5 0 180)
			(size 0.5 0.5)
			(layers "F.Cu" "F.Mask" "F.Paste")
			(net "GND")
			(solder_mask_margin 0)
			(solder_paste_margin 0)
		)
	)
	(footprint "Vault:RESC1005X40X25NL05T05"
		(layer "F.Cu")
		(at 225.1466 116.8162)
		(property "Reference" "R43"
			(at -3.4964 0.226931 0)
			(unlocked yes)
			(layer "F.SilkS")
			(effects
				(font
					(size 0.762 0.762)
					(thickness 0.2286)
				)
			)
		)
		(property "Value" "27_1%_0402"
			(at -3.011631 6.10665 270)
			(unlocked yes)
			(layer "F.SilkS")
			(hide yes)
			(effects
				(font
					(size 0.762 0.762)
					(thickness 0.2286)
				)
			)
		)
		(sheetname "09-USBUart_PPSMUX_UARTMUX")
		(sheetfile "09-USBUart_PPSMUX_UARTMUX.kicad_sch")
		(duplicate_pad_numbers_are_jumpers no)
		(pad "1" smd rect
			(at -0.45 0 90)
			(size 0.55 0.55)
			(layers "F.Cu" "F.Mask" "F.Paste")
			(net "FTDI_USB_R_N")
		)
		(pad "2" smd rect
			(at 0.45 0 90)
			(size 0.55 0.55)
			(layers "F.Cu" "F.Mask" "F.Paste")
			(net "FTDI_USB_N")
		)
	)
	(footprint "Vault:FP-LTST-C191KGKT-MFG"
		(layer "F.Cu")
		(at 224.7216 111.1162)
		(property "Reference" "D24"
			(at -3.4714 -0.073079 0)
			(unlocked yes)
			(layer "F.SilkS")
			(effects
				(font
					(size 0.762 0.762)
					(thickness 0.2286)
				)
			)
		)
		(property "Value" "LTST-C191KGKT"
			(at -3.519671 10.67713 270)
			(unlocked yes)
			(layer "F.SilkS")
			(hide yes)
			(effects
				(font
					(size 0.762 0.762)
					(thickness 0.2286)
				)
			)
		)
		(sheetname "08-DIPSwitches_I2C")
		(sheetfile "08-DIPSwitches_I2C.kicad_sch")
		(duplicate_pad_numbers_are_jumpers no)
		(fp_line
			(start -0.85 -0.775)
			(end 0.85 -0.775)
			(stroke
				(width 0.2)
				(type solid)
			)
			(layer "F.SilkS")
		)
		(fp_line
			(start -0.85 0.775)
			(end 0.85 0.775)
			(stroke
				(width 0.2)
				(type solid)
			)
			(layer "F.SilkS")
		)
		(fp_circle
			(center -1.7 0)
			(end -1.7 -0.125)
			(stroke
				(width 0.25)
				(type solid)
			)
			(fill no)
			(layer "F.SilkS")
		)
		(fp_line
			(start -1.25 -0.55)
			(end 1.25 -0.55)
			(stroke
				(width 0.2)
				(type solid)
			)
			(layer "F.CrtYd")
		)
		(fp_line
			(start -1.25 0.55)
			(end -1.25 -0.55)
			(stroke
				(width 0.2)
				(type solid)
			)
			(layer "F.CrtYd")
		)
		(fp_line
			(start -1.25 0.55)
			(end 1.25 0.55)
			(stroke
				(width 0.2)
				(type solid)
			)
			(layer "F.CrtYd")
		)
		(fp_line
			(start 1.25 0.55)
			(end 1.25 -0.55)
			(stroke
				(width 0.2)
				(type solid)
			)
			(layer "F.CrtYd")
		)
		(fp_line
			(start -1.25 -0.55)
			(end 1.25 -0.55)
			(stroke
				(width 0.2)
				(type solid)
			)
			(layer "F.Fab")
		)
		(fp_line
			(start -1.25 0.55)
			(end -1.25 -0.55)
			(stroke
				(width 0.2)
				(type solid)
			)
			(layer "F.Fab")
		)
		(fp_line
			(start -1.25 0.55)
			(end 1.25 0.55)
			(stroke
				(width 0.2)
				(type solid)
			)
			(layer "F.Fab")
		)
		(fp_line
			(start -0.5 0)
			(end 0.5 0)
			(stroke
				(width 0.1)
				(type solid)
			)
			(layer "F.Fab")
		)
		(fp_line
			(start 0 0.5)
			(end 0 -0.5)
			(stroke
				(width 0.1)
				(type solid)
			)
			(layer "F.Fab")
		)
		(fp_line
			(start 1.25 0.55)
			(end 1.25 -0.55)
			(stroke
				(width 0.2)
				(type solid)
			)
			(layer "F.Fab")
		)
		(fp_text user "${REFERENCE}"
			(at 0 0.29534 360)
			(unlocked yes)
			(layer "F.Fab")
			(effects
				(font
					(face "Arial")
					(size 0.63 0.63)
					(thickness 0.1)
				)
				(justify left bottom)
			)
		)
		(pad "1" smd rect
			(at -0.75 0)
			(size 0.8 0.8)
			(layers "F.Cu" "F.Mask" "F.Paste")
			(net "NetD24_1")
			(solder_mask_margin 0)
			(solder_paste_margin 0)
		)
		(pad "2" smd rect
			(at 0.75 0)
			(size 0.8 0.8)
			(layers "F.Cu" "F.Mask" "F.Paste")
			(net "+3.3V")
			(solder_mask_margin 0)
			(solder_paste_margin 0)
		)
	)
	(footprint ""
		(layer "F.Cu")
		(at 162.04661 65.0162)
		(property "Reference" ""
			(at 0 0 0)
			(layer "F.SilkS")
			(effects
				(font
					(size 1.27 1.27)
				)
			)
		)
		(property "Value" ""
			(at 0 0 0)
			(layer "F.Fab")
			(effects
				(font
					(size 1.27 1.27)
				)
			)
		)
		(duplicate_pad_numbers_are_jumpers no)
		(pad "2" thru_hole circle
			(at 0 0)
			(size 6.5 6.5)
			(drill 4.2)
			(layers "*.Cu" "*.Mask")
			(remove_unused_layers no)
			(net "GND")
			(thermal_bridge_angle 90)
		)
	)
	(footprint "Vault:RESC1005X40X25NL05T05"
		(layer "F.Cu")
		(at 197.6216 132.2162)
		(property "Reference" "R160"
			(at 0.3032 -0.873069 0)
			(unlocked yes)
			(layer "F.SilkS")
			(effects
				(font
					(size 0.762 0.762)
					(thickness 0.2032)
				)
			)
		)
		(property "Value" "DNI_27_1%_0402"
			(at -2.732271 10.270975 270)
			(unlocked yes)
			(layer "F.SilkS")
			(hide yes)
			(effects
				(font
					(size 0.762 0.762)
					(thickness 0.2032)
				)
			)
		)
		(sheetname "11-M2_RCB_MUX")
		(sheetfile "11-M2_RCB_MUX.kicad_sch")
		(duplicate_pad_numbers_are_jumpers no)
		(pad "1" smd rect
			(at -0.45 0 90)
			(size 0.55 0.55)
			(layers "F.Cu" "F.Mask" "F.Paste")
			(net "M2_GPS2_TP2")
		)
		(pad "2" smd rect
			(at 0.45 0 90)
			(size 0.55 0.55)
			(layers "F.Cu" "F.Mask" "F.Paste")
			(net "GPS2_TP2")
		)
	)
	(footprint "Vault:FP-T495D107K016ATE125-MFG"
		(layer "F.Cu")
		(at 188.3216 81.0162 -90)
		(property "Reference" "C75"
			(at 0.9286 -3.273069 270)
			(unlocked yes)
			(layer "F.SilkS")
			(effects
				(font
					(size 0.762 0.762)
					(thickness 0.2286)
				)
			)
		)
		(property "Value" "100uF_16V_2917"
			(at -5.818351 8.010455 180)
			(unlocked yes)
			(layer "F.SilkS")
			(hide yes)
			(effects
				(font
					(size 0.762 0.762)
					(thickness 0.2286)
				)
			)
		)
		(sheetname "03-POWER")
		(sheetfile "03-POWER.kicad_sch")
		(duplicate_pad_numbers_are_jumpers no)
		(fp_line
			(start -3.8 2.3)
			(end -3.8 1.54)
			(stroke
				(width 0.2)
				(type solid)
			)
			(layer "F.SilkS")
		)
		(fp_line
			(start 3.8 2.3)
			(end -3.8 2.3)
			(stroke
				(width 0.2)
				(type solid)
			)
			(layer "F.SilkS")
		)
		(fp_line
			(start 3.8 2.3)
			(end 3.8 1.54)
			(stroke
				(width 0.2)
				(type solid)
			)
			(layer "F.SilkS")
		)
		(fp_line
			(start 4.7 0.3)
			(end 4.7 -0.3)
			(stroke
				(width 0.2)
				(type solid)
			)
			(layer "F.SilkS")
		)
		(fp_line
			(start 5 0)
			(end 4.4 0)
			(stroke
				(width 0.2)
				(type solid)
			)
			(layer "F.SilkS")
		)
		(fp_line
			(start -3.8 -1.54)
			(end -3.8 -2.3)
			(stroke
				(width 0.2)
				(type solid)
			)
			(layer "F.SilkS")
		)
		(fp_line
			(start 3.8 -1.54)
			(end 3.8 -2.3)
			(stroke
				(width 0.2)
				(type solid)
			)
			(layer "F.SilkS")
		)
		(fp_line
			(start 3.8 -2.3)
			(end -3.8 -2.3)
			(stroke
				(width 0.2)
				(type solid)
			)
			(layer "F.SilkS")
		)
		(fp_line
			(start -4.105 2.4)
			(end -4.105 -2.4)
			(stroke
				(width 0.2)
				(type solid)
			)
			(layer "F.CrtYd")
		)
		(fp_line
			(start 4.105 2.4)
			(end -4.105 2.4)
			(stroke
				(width 0.2)
				(type solid)
			)
			(layer "F.CrtYd")
		)
		(fp_line
			(start 4.105 2.4)
			(end 4.105 -2.4)
			(stroke
				(width 0.2)
				(type solid)
			)
			(layer "F.CrtYd")
		)
		(fp_line
			(start 4.105 -2.4)
			(end -4.105 -2.4)
			(stroke
				(width 0.2)
				(type solid)
			)
			(layer "F.CrtYd")
		)
		(fp_line
			(start -4.105 2.4)
			(end -4.105 -2.4)
			(stroke
				(width 0.2)
				(type solid)
			)
			(layer "F.Fab")
		)
		(fp_line
			(start 4.105 2.4)
			(end -4.105 2.4)
			(stroke
				(width 0.2)
				(type solid)
			)
			(layer "F.Fab")
		)
		(fp_line
			(start 4.105 2.4)
			(end 4.105 -2.4)
			(stroke
				(width 0.2)
				(type solid)
			)
			(layer "F.Fab")
		)
		(fp_line
			(start 0 0.5)
			(end 0 -0.5)
			(stroke
				(width 0.1)
				(type solid)
			)
			(layer "F.Fab")
		)
		(fp_line
			(start 0.5 0)
			(end -0.5 0)
			(stroke
				(width 0.1)
				(type solid)
			)
			(layer "F.Fab")
		)
		(fp_line
			(start 4.105 -2.4)
			(end -4.105 -2.4)
			(stroke
				(width 0.2)
				(type solid)
			)
			(layer "F.Fab")
		)
		(fp_text user "${REFERENCE}"
			(at 0 0.28425 270)
			(unlocked yes)
			(layer "F.Fab")
			(effects
				(font
					(face "Arial")
					(size 0.63 0.63)
					(thickness 0.1)
				)
				(justify left bottom)
			)
		)
		(pad "1" smd rect
			(at -3.01 0 270)
			(size 1.99 2.33)
			(layers "F.Cu" "F.Mask" "F.Paste")
			(net "GND")
			(solder_mask_margin 0)
			(solder_paste_margin 0)
		)
		(pad "2" smd rect
			(at 3.01 0 270)
			(size 1.99 2.33)
			(layers "F.Cu" "F.Mask" "F.Paste")
			(net "+12V")
			(solder_mask_margin 0)
			(solder_paste_margin 0)
		)
	)
	(footprint "Vault:RESC1005X40X25LL05T10"
		(layer "F.Cu")
		(at 193.2216 120.0162 -90)
		(property "Reference" "R167"
			(at -2.60321 -0.126921 90)
			(unlocked yes)
			(layer "F.SilkS")
			(effects
				(font
					(size 0.762 0.762)
					(thickness 0.2032)
				)
			)
		)
		(property "Value" "DNI_49.9_1%_0402"
			(at -2.579871 11.71832 180)
			(unlocked yes)
			(layer "F.SilkS")
			(hide yes)
			(effects
				(font
					(size 0.762 0.762)
					(thickness 0.2032)
				)
			)
		)
		(sheetname "11-M2_RCB_MUX")
		(sheetfile "11-M2_RCB_MUX.kicad_sch")
		(duplicate_pad_numbers_are_jumpers no)
		(pad "1" smd rect
			(at -0.375 0)
			(size 0.45 0.5)
			(layers "F.Cu" "F.Mask" "F.Paste")
			(net "GPS2_PIN11")
		)
		(pad "2" smd rect
			(at 0.375 0)
			(size 0.45 0.5)
			(layers "F.Cu" "F.Mask" "F.Paste")
			(net "M2_GPS2_PIN11")
		)
	)
	(footprint "Vault:FP-0402-L_1_0_1-W_0_5_0_1-IPC_C"
		(layer "F.Cu")
		(at 75.1216 104.2162 180)
		(property "Reference" "C26"
			(at 2.4714 -0.026931 0)
			(unlocked yes)
			(layer "F.SilkS")
			(effects
				(font
					(size 0.762 0.762)
					(thickness 0.2286)
				)
			)
		)
		(property "Value" "0.1uF_25V_0402"
			(at 2.069035 2.567191 180)
			(unlocked yes)
			(layer "F.SilkS")
			(hide yes)
			(effects
				(font
					(size 0.762 0.762)
					(thickness 0.2286)
				)
			)
		)
		(sheetname "01-USER_IO")
		(sheetfile "01-USER_IO.kicad_sch")
		(duplicate_pad_numbers_are_jumpers no)
		(fp_line
			(start 0.65607 0.7)
			(end -0.65607 0.7)
			(stroke
				(width 0.2)
				(type solid)
			)
			(layer "F.SilkS")
		)
		(fp_line
			(start 0.65607 -0.7)
			(end -0.65607 -0.7)
			(stroke
				(width 0.2)
				(type solid)
			)
			(layer "F.SilkS")
		)
		(fp_line
			(start 0.75607 0.4)
			(end -0.75606 0.4)
			(stroke
				(width 0.2)
				(type solid)
			)
			(layer "F.CrtYd")
		)
		(fp_line
			(start 0.75607 -0.4)
			(end 0.75607 0.4)
			(stroke
				(width 0.2)
				(type solid)
			)
			(layer "F.CrtYd")
		)
		(fp_line
			(start 0.75607 -0.4)
			(end -0.75606 -0.4)
			(stroke
				(width 0.2)
				(type solid)
			)
			(layer "F.CrtYd")
		)
		(fp_line
			(start -0.75606 -0.4)
			(end -0.75606 0.4)
			(stroke
				(width 0.2)
				(type solid)
			)
			(layer "F.CrtYd")
		)
		(fp_line
			(start 0.75607 0.4)
			(end -0.75606 0.4)
			(stroke
				(width 0.2)
				(type solid)
			)
			(layer "F.Fab")
		)
		(fp_line
			(start 0.75607 -0.4)
			(end 0.75607 0.4)
			(stroke
				(width 0.2)
				(type solid)
			)
			(layer "F.Fab")
		)
		(fp_line
			(start 0.75607 -0.4)
			(end -0.75606 -0.4)
			(stroke
				(width 0.2)
				(type solid)
			)
			(layer "F.Fab")
		)
		(fp_line
			(start 0.5 0)
			(end -0.5 0)
			(stroke
				(width 0.1)
				(type solid)
			)
			(layer "F.Fab")
		)
		(fp_line
			(start 0 -0.5)
			(end 0 0.5)
			(stroke
				(width 0.1)
				(type solid)
			)
			(layer "F.Fab")
		)
		(fp_line
			(start -0.75606 -0.4)
			(end -0.75606 0.4)
			(stroke
				(width 0.2)
				(type solid)
			)
			(layer "F.Fab")
		)
		(fp_text user "${REFERENCE}"
			(at -0.00001 0.09602 180)
			(unlocked yes)
			(layer "F.Fab")
			(effects
				(font
					(face "Arial")
					(size 0.63 0.63)
					(thickness 0.1)
				)
				(justify left bottom)
			)
		)
		(pad "1" smd rect
			(at -0.36553 0 180)
			(size 0.58106 0.51213)
			(layers "F.Cu" "F.Mask" "F.Paste")
			(net "+3.3V")
			(solder_mask_margin 0)
			(solder_paste_margin 0)
		)
		(pad "2" smd rect
			(at 0.36554 0 180)
			(size 0.58106 0.51213)
			(layers "F.Cu" "F.Mask" "F.Paste")
			(net "GND")
			(solder_mask_margin 0)
			(solder_paste_margin 0)
		)
	)
	(footprint "Vault:RESC1005X40X25NL05T05"
		(layer "F.Cu")
		(at 156.7216 131.5162 90)
		(property "Reference" "R87"
			(at -1.6714 0.326931 90)
			(unlocked yes)
			(layer "F.SilkS")
			(effects
				(font
					(size 0.762 0.762)
					(thickness 0.2286)
				)
			)
		)
		(property "Value" "27_1%_0402"
			(at -2.732271 7.37632 0)
			(unlocked yes)
			(layer "F.SilkS")
			(hide yes)
			(effects
				(font
					(size 0.762 0.762)
					(thickness 0.2286)
				)
			)
		)
		(sheetname "09-USBUart_PPSMUX_UARTMUX")
		(sheetfile "09-USBUart_PPSMUX_UARTMUX.kicad_sch")
		(duplicate_pad_numbers_are_jumpers no)
		(pad "1" smd rect
			(at -0.45 0 180)
			(size 0.55 0.55)
			(layers "F.Cu" "F.Mask" "F.Paste")
			(net "FTDI_TX")
		)
		(pad "2" smd rect
			(at 0.45 0 180)
			(size 0.55 0.55)
			(layers "F.Cu" "F.Mask" "F.Paste")
			(net "NetR87_2")
		)
	)
	(footprint "Vault:FP-ABS07-MFG"
		(layer "F.Cu")
		(at 118.48072 86.4662 90)
		(property "Reference" "Y1"
			(at 0.153195 -1.776719 90)
			(unlocked yes)
			(layer "F.SilkS")
			(effects
				(font
					(size 0.762 0.762)
					(thickness 0.2032)
				)
			)
		)
		(property "Value" "ABS07-32.768KHZ-T"
			(at 11.032235 2.706871 90)
			(unlocked yes)
			(layer "F.SilkS")
			(hide yes)
			(effects
				(font
					(size 0.762 0.762)
					(thickness 0.2032)
				)
			)
		)
		(sheetname "05-GPS_IMU_SENSORS")
		(sheetfile "05-GPS_IMU_SENSORS.kicad_sch")
		(duplicate_pad_numbers_are_jumpers no)
		(fp_line
			(start -0.325 -0.8)
			(end 0.325 -0.8)
			(stroke
				(width 0.2)
				(type solid)
			)
			(layer "F.SilkS")
		)
		(fp_line
			(start -0.325 0.8)
			(end 0.325 0.8)
			(stroke
				(width 0.2)
				(type solid)
			)
			(layer "F.SilkS")
		)
		(fp_line
			(start 1.9 -1.05)
			(end 1.9 1.05)
			(stroke
				(width 0.2)
				(type solid)
			)
			(layer "F.CrtYd")
		)
		(fp_line
			(start -1.9 -1.05)
			(end 1.9 -1.05)
			(stroke
				(width 0.2)
				(type solid)
			)
			(layer "F.CrtYd")
		)
		(fp_line
			(start -1.9 -1.05)
			(end -1.9 1.05)
			(stroke
				(width 0.2)
				(type solid)
			)
			(layer "F.CrtYd")
		)
		(fp_line
			(start -1.9 1.05)
			(end 1.9 1.05)
			(stroke
				(width 0.2)
				(type solid)
			)
			(layer "F.CrtYd")
		)
		(fp_line
			(start 1.9 -1.05)
			(end 1.9 1.05)
			(stroke
				(width 0.2)
				(type solid)
			)
			(layer "F.Fab")
		)
		(fp_line
			(start -1.9 -1.05)
			(end 1.9 -1.05)
			(stroke
				(width 0.2)
				(type solid)
			)
			(layer "F.Fab")
		)
		(fp_line
			(start -1.9 -1.05)
			(end -1.9 1.05)
			(stroke
				(width 0.2)
				(type solid)
			)
			(layer "F.Fab")
		)
		(fp_line
			(start 0 -0.5)
			(end 0 0.5)
			(stroke
				(width 0.1)
				(type solid)
			)
			(layer "F.Fab")
		)
		(fp_line
			(start -0.5 0)
			(end 0.5 0)
			(stroke
				(width 0.1)
				(type solid)
			)
			(layer "F.Fab")
		)
		(fp_line
			(start -1.9 1.05)
			(end 1.9 1.05)
			(stroke
				(width 0.2)
				(type solid)
			)
			(layer "F.Fab")
		)
		(fp_text user "${REFERENCE}"
			(at 0.00091 0.10711 90)
			(unlocked yes)
			(layer "F.Fab")
			(effects
				(font
					(face "Arial")
					(size 0.63 0.63)
					(thickness 0.1)
				)
				(justify left bottom)
			)
		)
		(pad "1" smd rect
			(at -1.25 0 90)
			(size 1.1 1.9)
			(layers "F.Cu" "F.Mask" "F.Paste")
			(net "BNO_XOUT32")
			(solder_mask_margin 0)
			(solder_paste_margin 0)
		)
		(pad "2" smd rect
			(at 1.25 0 90)
			(size 1.1 1.9)
			(layers "F.Cu" "F.Mask" "F.Paste")
			(net "BNO_XIN32")
			(solder_mask_margin 0)
			(solder_paste_margin 0)
		)
	)
	(footprint "Capacitors:CAPC2012X14N"
		(layer "F.Cu")
		(at 229.8216 65.1162 90)
		(property "Reference" "C1"
			(at 1.9 0.393345 90)
			(unlocked yes)
			(layer "F.SilkS")
			(effects
				(font
					(size 0.762 0.762)
					(thickness 0.2286)
				)
				(justify left bottom)
			)
		)
		(property "Value" "CAP_0805_10UF_25V"
			(at -0.433445 1.2125 0)
			(unlocked yes)
			(layer "F.SilkS")
			(hide yes)
			(effects
				(font
					(size 0.762 0.762)
					(thickness 0.2286)
				)
				(justify left bottom)
			)
		)
		(sheetname "03-POWER")
		(sheetfile "03-POWER.kicad_sch")
		(duplicate_pad_numbers_are_jumpers no)
		(fp_line
			(start -0.762 -0.9652)
			(end 0.762 -0.9652)
			(stroke
				(width 0.1524)
				(type solid)
			)
			(layer "F.SilkS")
		)
		(fp_line
			(start -0.762 0.9652)
			(end 0.762 0.9652)
			(stroke
				(width 0.1524)
				(type solid)
			)
			(layer "F.SilkS")
		)
		(pad "1" smd rect
			(at -0.9 0 180)
			(size 1.45 1.15)
			(layers "F.Cu" "F.Mask" "F.Paste")
			(net "+12V")
		)
		(pad "2" smd rect
			(at 0.9 0 180)
			(size 1.45 1.15)
			(layers "F.Cu" "F.Mask" "F.Paste")
			(net "GND")
		)
	)
	(footprint "Vault:FP-2199119-3-MFG"
		(locked yes)
		(layer "F.Cu")
		(at 120.2466 65.0162 90)
		(property "Reference" "J44"
			(at -7.0032 6.448069 270)
			(unlocked yes)
			(layer "F.SilkS")
			(effects
				(font
					(size 0.762 0.762)
					(thickness 0.2032)
				)
			)
		)
		(property "Value" "2199119-3"
			(at -12.739871 1.153685 0)
			(unlocked yes)
			(layer "F.SilkS")
			(hide yes)
			(effects
				(font
					(size 0.762 0.762)
					(thickness 0.2032)
				)
			)
		)
		(sheetname "10-M2_GPS")
		(sheetfile "10-M2_GPS.kicad_sch")
		(duplicate_pad_numbers_are_jumpers no)
		(fp_line
			(start -6.225 -3.975)
			(end -4.775 -3.975)
			(stroke
				(width 0.2)
				(type solid)
			)
			(layer "F.SilkS")
		)
		(fp_line
			(start 11 -1.375)
			(end 11 0.2)
			(stroke
				(width 0.2)
				(type solid)
			)
			(layer "F.SilkS")
		)
		(fp_line
			(start -11 -1.375)
			(end -11 3.975)
			(stroke
				(width 0.2)
				(type solid)
			)
			(layer "F.SilkS")
		)
		(fp_line
			(start 11 2.55)
			(end 11 3.975)
			(stroke
				(width 0.2)
				(type solid)
			)
			(layer "F.SilkS")
		)
		(fp_line
			(start 9.525 3.975)
			(end 11 3.975)
			(stroke
				(width 0.2)
				(type solid)
			)
			(layer "F.SilkS")
		)
		(fp_line
			(start -6.475 3.975)
			(end -5.025 3.975)
			(stroke
				(width 0.2)
				(type solid)
			)
			(layer "F.SilkS")
		)
		(fp_line
			(start -11 3.975)
			(end -9.525 3.975)
			(stroke
				(width 0.2)
				(type solid)
			)
			(layer "F.SilkS")
		)
		(fp_circle
			(center -9.275 -5.275)
			(end -9.15 -5.275)
			(stroke
				(width 0.25)
				(type solid)
			)
			(fill no)
			(layer "F.SilkS")
		)
		(fp_line
			(start 11.1 -4.775)
			(end 11.1 4.525)
			(stroke
				(width 0.2)
				(type solid)
			)
			(layer "F.CrtYd")
		)
		(fp_line
			(start -11.1 -4.775)
			(end 11.1 -4.775)
			(stroke
				(width 0.2)
				(type solid)
			)
			(layer "F.CrtYd")
		)
		(fp_line
			(start -11.1 -4.775)
			(end -11.1 4.525)
			(stroke
				(width 0.2)
				(type solid)
			)
			(layer "F.CrtYd")
		)
		(fp_line
			(start -11.1 4.525)
			(end 11.1 4.525)
			(stroke
				(width 0.2)
				(type solid)
			)
			(layer "F.CrtYd")
		)
		(fp_line
			(start 11.1 -4.775)
			(end 11.1 4.525)
			(stroke
				(width 0.2)
				(type solid)
			)
			(layer "F.Fab")
		)
		(fp_line
			(start -11.1 -4.775)
			(end 11.1 -4.775)
			(stroke
				(width 0.2)
				(type solid)
			)
			(layer "F.Fab")
		)
		(fp_line
			(start -11.1 -4.775)
			(end -11.1 4.525)
			(stroke
				(width 0.2)
				(type solid)
			)
			(layer "F.Fab")
		)
		(fp_line
			(start 0 -0.5)
			(end 0 0.5)
			(stroke
				(width 0.1)
				(type solid)
			)
			(layer "F.Fab")
		)
		(fp_line
			(start -0.5 0)
			(end 0.5 0)
			(stroke
				(width 0.1)
				(type solid)
			)
			(layer "F.Fab")
		)
		(fp_line
			(start -11.1 4.525)
			(end 11.1 4.525)
			(stroke
				(width 0.2)
				(type solid)
			)
			(layer "F.Fab")
		)
		(fp_text user "${REFERENCE}"
			(at -0.00185 0.15925 90)
			(unlocked yes)
			(layer "F.Fab")
			(effects
				(font
					(face "Arial")
					(size 0.63 0.63)
					(thickness 0.1)
				)
				(justify left bottom)
			)
		)
		(pad "" np_thru_hole circle
			(at -10 1.375 90)
			(size 1.1 1.1)
			(drill 1.1)
			(layers "*.Cu" "*.Mask")
			(solder_mask_margin 0)
			(solder_paste_margin -1000)
			(thermal_bridge_angle 90)
		)
		(pad "" np_thru_hole circle
			(at 10 1.375 90)
			(size 1.6 1.6)
			(drill 1.6)
			(layers "*.Cu" "*.Mask")
			(solder_mask_margin 0)
			(solder_paste_margin -1000)
			(thermal_bridge_angle 90)
		)
		(pad "1" smd rect
			(at -9.25 -3.9 90)
			(size 0.3 1.55)
			(layers "F.Cu" "F.Mask" "F.Paste")
			(solder_mask_margin 0)
			(solder_paste_margin 0)
		)
		(pad "2" smd rect
			(at -9 3.65 90)
			(size 0.3 1.55)
			(layers "F.Cu" "F.Mask" "F.Paste")
			(net "+3.3V")
			(solder_mask_margin 0)
			(solder_paste_margin 0)
		)
		(pad "3" smd rect
			(at -8.75 -3.9 90)
			(size 0.3 1.55)
			(layers "F.Cu" "F.Mask" "F.Paste")
			(net "GND")
			(solder_mask_margin 0)
			(solder_paste_margin 0)
		)
		(pad "4" smd rect
			(at -8.5 3.65 90)
			(size 0.3 1.55)
			(layers "F.Cu" "F.Mask" "F.Paste")
			(net "+3.3V")
			(solder_mask_margin 0)
			(solder_paste_margin 0)
		)
		(pad "5" smd rect
			(at -8.25 -3.9 90)
			(size 0.3 1.55)
			(layers "F.Cu" "F.Mask" "F.Paste")
			(net "GND")
			(solder_mask_margin 0)
			(solder_paste_margin 0)
		)
		(pad "6" smd rect
			(at -8 3.65 90)
			(size 0.3 1.55)
			(layers "F.Cu" "F.Mask" "F.Paste")
			(solder_mask_margin 0)
			(solder_paste_margin 0)
		)
		(pad "7" smd rect
			(at -7.75 -3.9 90)
			(size 0.3 1.55)
			(layers "F.Cu" "F.Mask" "F.Paste")
			(solder_mask_margin 0)
			(solder_paste_margin 0)
		)
		(pad "8" smd rect
			(at -7.5 3.65 90)
			(size 0.3 1.55)
			(layers "F.Cu" "F.Mask" "F.Paste")
			(solder_mask_margin 0)
			(solder_paste_margin 0)
		)
		(pad "9" smd rect
			(at -7.25 -3.9 90)
			(size 0.3 1.55)
			(layers "F.Cu" "F.Mask" "F.Paste")
			(solder_mask_margin 0)
			(solder_paste_margin 0)
		)
		(pad "10" smd rect
			(at -7 3.65 90)
			(size 0.3 1.55)
			(layers "F.Cu" "F.Mask" "F.Paste")
			(solder_mask_margin 0)
			(solder_paste_margin 0)
		)
		(pad "11" smd rect
			(at -6.75 -3.9 90)
			(size 0.3 1.55)
			(layers "F.Cu" "F.Mask" "F.Paste")
			(net "GND")
			(solder_mask_margin 0)
			(solder_paste_margin 0)
		)
		(pad "20" smd rect
			(at -4.5 3.65 90)
			(size 0.3 1.55)
			(layers "F.Cu" "F.Mask" "F.Paste")
			(net "M2_GPS1_PIN11")
			(solder_mask_margin 0)
			(solder_paste_margin 0)
		)
		(pad "21" smd rect
			(at -4.25 -3.9 90)
			(size 0.3 1.55)
			(layers "F.Cu" "F.Mask" "F.Paste")
			(solder_mask_margin 0)
			(solder_paste_margin 0)
		)
		(pad "22" smd rect
			(at -4 3.65 90)
			(size 0.3 1.55)
			(layers "F.Cu" "F.Mask" "F.Paste")
			(net "M2_GPS1_PIN12")
			(solder_mask_margin 0)
			(solder_paste_margin 0)
		)
		(pad "23" smd rect
			(at -3.75 -3.9 90)
			(size 0.3 1.55)
			(layers "F.Cu" "F.Mask" "F.Paste")
			(solder_mask_margin 0)
			(solder_paste_margin 0)
		)
		(pad "24" smd rect
			(at -3.5 3.65 90)
			(size 0.3 1.55)
			(layers "F.Cu" "F.Mask" "F.Paste")
			(solder_mask_margin 0)
			(solder_paste_margin 0)
		)
		(pad "25" smd rect
			(at -3.25 -3.9 90)
			(size 0.3 1.55)
			(layers "F.Cu" "F.Mask" "F.Paste")
			(solder_mask_margin 0)
			(solder_paste_margin 0)
		)
		(pad "26" smd rect
			(at -3 3.65 90)
			(size 0.3 1.55)
			(layers "F.Cu" "F.Mask" "F.Paste")
			(solder_mask_margin 0)
			(solder_paste_margin 0)
		)
		(pad "27" smd rect
			(at -2.75 -3.9 90)
			(size 0.3 1.55)
			(layers "F.Cu" "F.Mask" "F.Paste")
			(net "GND")
			(solder_mask_margin 0)
			(solder_paste_margin 0)
		)
		(pad "28" smd rect
			(at -2.5 3.65 90)
			(size 0.3 1.55)
			(layers "F.Cu" "F.Mask" "F.Paste")
			(solder_mask_margin 0)
			(solder_paste_margin 0)
		)
		(pad "29" smd rect
			(at -2.25 -3.9 90)
			(size 0.3 1.55)
			(layers "F.Cu" "F.Mask" "F.Paste")
			(solder_mask_margin 0)
			(solder_paste_margin 0)
		)
		(pad "30" smd rect
			(at -2 3.65 90)
			(size 0.3 1.55)
			(layers "F.Cu" "F.Mask" "F.Paste")
			(solder_mask_margin 0)
			(solder_paste_margin 0)
		)
		(pad "31" smd rect
			(at -1.75 -3.9 90)
			(size 0.3 1.55)
			(layers "F.Cu" "F.Mask" "F.Paste")
			(solder_mask_margin 0)
			(solder_paste_margin 0)
		)
		(pad "32" smd rect
			(at -1.5 3.65 90)
			(size 0.3 1.55)
			(layers "F.Cu" "F.Mask" "F.Paste")
			(solder_mask_margin 0)
			(solder_paste_margin 0)
		)
		(pad "33" smd rect
			(at -1.25 -3.9 90)
			(size 0.3 1.55)
			(layers "F.Cu" "F.Mask" "F.Paste")
			(net "GND")
			(solder_mask_margin 0)
			(solder_paste_margin 0)
		)
		(pad "34" smd rect
			(at -1 3.65 90)
			(size 0.3 1.55)
			(layers "F.Cu" "F.Mask" "F.Paste")
			(solder_mask_margin 0)
			(solder_paste_margin 0)
		)
		(pad "35" smd rect
			(at -0.75 -3.9 90)
			(size 0.3 1.55)
			(layers "F.Cu" "F.Mask" "F.Paste")
			(net "NetJ44_35")
			(solder_mask_margin 0)
			(solder_paste_margin 0)
		)
		(pad "36" smd rect
			(at -0.5 3.65 90)
			(size 0.3 1.55)
			(layers "F.Cu" "F.Mask" "F.Paste")
			(solder_mask_margin 0)
			(solder_paste_margin 0)
		)
		(pad "37" smd rect
			(at -0.25 -3.9 90)
			(size 0.3 1.55)
			(layers "F.Cu" "F.Mask" "F.Paste")
			(solder_mask_margin 0)
			(solder_paste_margin 0)
		)
		(pad "38" smd rect
			(at 0 3.65 90)
			(size 0.3 1.55)
			(layers "F.Cu" "F.Mask" "F.Paste")
			(solder_mask_margin 0)
			(solder_paste_margin 0)
		)
		(pad "39" smd rect
			(at 0.25 -3.9 90)
			(size 0.3 1.55)
			(layers "F.Cu" "F.Mask" "F.Paste")
			(net "GND")
			(solder_mask_margin 0)
			(solder_paste_margin 0)
		)
		(pad "40" smd rect
			(at 0.5 3.65 90)
			(size 0.3 1.55)
			(layers "F.Cu" "F.Mask" "F.Paste")
			(net "GPS1_PIN13")
			(solder_mask_margin 0)
			(solder_paste_margin 0)
		)
		(pad "41" smd rect
			(at 0.75 -3.9 90)
			(size 0.3 1.55)
			(layers "F.Cu" "F.Mask" "F.Paste")
			(solder_mask_margin 0)
			(solder_paste_margin 0)
		)
		(pad "42" smd rect
			(at 1 3.65 90)
			(size 0.3 1.55)
			(layers "F.Cu" "F.Mask" "F.Paste")
			(net "GPS1_PIN14")
			(solder_mask_margin 0)
			(solder_paste_margin 0)
		)
		(pad "43" smd rect
			(at 1.25 -3.9 90)
			(size 0.3 1.55)
			(layers "F.Cu" "F.Mask" "F.Paste")
			(solder_mask_margin 0)
			(solder_paste_margin 0)
		)
		(pad "44" smd rect
			(at 1.5 3.65 90)
			(size 0.3 1.55)
			(layers "F.Cu" "F.Mask" "F.Paste")
			(net "GPS1_PIN15")
			(solder_mask_margin 0)
			(solder_paste_margin 0)
		)
		(pad "45" smd rect
			(at 1.75 -3.9 90)
			(size 0.3 1.55)
			(layers "F.Cu" "F.Mask" "F.Paste")
			(net "GND")
			(solder_mask_margin 0)
			(solder_paste_margin 0)
		)
		(pad "46" smd rect
			(at 2 3.65 90)
			(size 0.3 1.55)
			(layers "F.Cu" "F.Mask" "F.Paste")
			(net "NetJ44_46")
			(solder_mask_margin 0)
			(solder_paste_margin 0)
		)
		(pad "47" smd rect
			(at 2.25 -3.9 90)
			(size 0.3 1.55)
			(layers "F.Cu" "F.Mask" "F.Paste")
			(solder_mask_margin 0)
			(solder_paste_margin 0)
		)
		(pad "48" smd rect
			(at 2.5 3.65 90)
			(size 0.3 1.55)
			(layers "F.Cu" "F.Mask" "F.Paste")
			(net "M2_GPS1_TP2")
			(solder_mask_margin 0)
			(solder_paste_margin 0)
		)
		(pad "49" smd rect
			(at 2.75 -3.9 90)
			(size 0.3 1.55)
			(layers "F.Cu" "F.Mask" "F.Paste")
			(solder_mask_margin 0)
			(solder_paste_margin 0)
		)
		(pad "50" smd rect
			(at 3 3.65 90)
			(size 0.3 1.55)
			(layers "F.Cu" "F.Mask" "F.Paste")
			(net "GPS1_RST")
			(solder_mask_margin 0)
			(solder_paste_margin 0)
		)
		(pad "51" smd rect
			(at 3.25 -3.9 90)
			(size 0.3 1.55)
			(layers "F.Cu" "F.Mask" "F.Paste")
			(net "GND")
			(solder_mask_margin 0)
			(solder_paste_margin 0)
		)
		(pad "52" smd rect
			(at 3.5 3.65 90)
			(size 0.3 1.55)
			(layers "F.Cu" "F.Mask" "F.Paste")
			(solder_mask_margin 0)
			(solder_paste_margin 0)
		)
		(pad "53" smd rect
			(at 3.75 -3.9 90)
			(size 0.3 1.55)
			(layers "F.Cu" "F.Mask" "F.Paste")
			(solder_mask_margin 0)
			(solder_paste_margin 0)
		)
		(pad "54" smd rect
			(at 4 3.65 90)
			(size 0.3 1.55)
			(layers "F.Cu" "F.Mask" "F.Paste")
			(solder_mask_margin 0)
			(solder_paste_margin 0)
		)
		(pad "55" smd rect
			(at 4.25 -3.9 90)
			(size 0.3 1.55)
			(layers "F.Cu" "F.Mask" "F.Paste")
			(solder_mask_margin 0)
			(solder_paste_margin 0)
		)
		(pad "56" smd rect
			(at 4.5 3.65 90)
			(size 0.3 1.55)
			(layers "F.Cu" "F.Mask" "F.Paste")
			(solder_mask_margin 0)
			(solder_paste_margin 0)
		)
		(pad "57" smd rect
			(at 4.75 -3.9 90)
			(size 0.3 1.55)
			(layers "F.Cu" "F.Mask" "F.Paste")
			(net "GND")
			(solder_mask_margin 0)
			(solder_paste_margin 0)
		)
		(pad "58" smd rect
			(at 5 3.65 90)
			(size 0.3 1.55)
			(layers "F.Cu" "F.Mask" "F.Paste")
			(solder_mask_margin 0)
			(solder_paste_margin 0)
		)
		(pad "59" smd rect
			(at 5.25 -3.9 90)
			(size 0.3 1.55)
			(layers "F.Cu" "F.Mask" "F.Paste")
			(solder_mask_margin 0)
			(solder_paste_margin 0)
		)
		(pad "60" smd rect
			(at 5.5 3.65 90)
			(size 0.3 1.55)
			(layers "F.Cu" "F.Mask" "F.Paste")
			(solder_mask_margin 0)
			(solder_paste_margin 0)
		)
		(pad "61" smd rect
			(at 5.75 -3.9 90)
			(size 0.3 1.55)
			(layers "F.Cu" "F.Mask" "F.Paste")
			(solder_mask_margin 0)
			(solder_paste_margin 0)
		)
		(pad "62" smd rect
			(at 6 3.65 90)
			(size 0.3 1.55)
			(layers "F.Cu" "F.Mask" "F.Paste")
			(net "M2_GPS1_RX")
			(solder_mask_margin 0)
			(solder_paste_margin 0)
		)
		(pad "63" smd rect
			(at 6.25 -3.9 90)
			(size 0.3 1.55)
			(layers "F.Cu" "F.Mask" "F.Paste")
			(solder_mask_margin 0)
			(solder_paste_margin 0)
		)
		(pad "64" smd rect
			(at 6.5 3.65 90)
			(size 0.3 1.55)
			(layers "F.Cu" "F.Mask" "F.Paste")
			(net "M2_GPS1_TX")
			(solder_mask_margin 0)
			(solder_paste_margin 0)
		)
		(pad "65" smd rect
			(at 6.75 -3.9 90)
			(size 0.3 1.55)
			(layers "F.Cu" "F.Mask" "F.Paste")
			(solder_mask_margin 0)
			(solder_paste_margin 0)
		)
		(pad "66" smd rect
			(at 7 3.65 90)
			(size 0.3 1.55)
			(layers "F.Cu" "F.Mask" "F.Paste")
			(solder_mask_margin 0)
			(solder_paste_margin 0)
		)
		(pad "67" smd rect
			(at 7.25 -3.9 90)
			(size 0.3 1.55)
			(layers "F.Cu" "F.Mask" "F.Paste")
			(net "GPS1_RST")
			(solder_mask_margin 0)
			(solder_paste_margin 0)
		)
		(pad "68" smd rect
			(at 7.5 3.65 90)
			(size 0.3 1.55)
			(layers "F.Cu" "F.Mask" "F.Paste")
			(solder_mask_margin 0)
			(solder_paste_margin 0)
		)
		(pad "69" smd rect
			(at 7.75 -3.9 90)
			(size 0.3 1.55)
			(layers "F.Cu" "F.Mask" "F.Paste")
			(solder_mask_margin 0)
			(solder_paste_margin 0)
		)
		(pad "70" smd rect
			(at 8 3.65 90)
			(size 0.3 1.55)
			(layers "F.Cu" "F.Mask" "F.Paste")
			(net "+3.3V")
			(solder_mask_margin 0)
			(solder_paste_margin 0)
		)
		(pad "71" smd rect
			(at 8.25 -3.9 90)
			(size 0.3 1.55)
			(layers "F.Cu" "F.Mask" "F.Paste")
			(net "GND")
			(solder_mask_margin 0)
			(solder_paste_margin 0)
		)
		(pad "72" smd rect
			(at 8.5 3.65 90)
			(size 0.3 1.55)
			(layers "F.Cu" "F.Mask" "F.Paste")
			(net "+3.3V")
			(solder_mask_margin 0)
			(solder_paste_margin 0)
		)
		(pad "73" smd rect
			(at 8.75 -3.9 90)
			(size 0.3 1.55)
			(layers "F.Cu" "F.Mask" "F.Paste")
			(net "GND")
			(solder_mask_margin 0)
			(solder_paste_margin 0)
		)
		(pad "74" smd rect
			(at 9 3.65 90)
			(size 0.3 1.55)
			(layers "F.Cu" "F.Mask" "F.Paste")
			(net "+3.3V")
			(solder_mask_margin 0)
			(solder_paste_margin 0)
		)
		(pad "75" smd rect
			(at 9.25 -3.9 90)
			(size 0.3 1.55)
			(layers "F.Cu" "F.Mask" "F.Paste")
			(solder_mask_margin 0)
			(solder_paste_margin 0)
		)
		(pad "76" smd rect
			(at -10.35 -3.125 90)
			(size 1.2 2.75)
			(layers "F.Cu" "F.Mask" "F.Paste")
			(net "GND")
			(solder_mask_margin 0)
			(solder_paste_margin 0)
		)
		(pad "77" smd rect
			(at 10.35 -3.125 90)
			(size 1.2 2.75)
			(layers "F.Cu" "F.Mask" "F.Paste")
			(net "GND")
			(solder_mask_margin 0)
			(solder_paste_margin 0)
		)
	)
	(footprint "Vault:RESC1005X40X25LL05T10"
		(layer "F.Cu")
		(at 194.0216 125.7162 90)
		(property "Reference" "R169"
			(at -0.2968 -2.373079 90)
			(unlocked yes)
			(layer "F.SilkS")
			(effects
				(font
					(size 0.762 0.762)
					(thickness 0.2032)
				)
			)
		)
		(property "Value" "DNI_49.9_1%_0402"
			(at -2.579871 11.71832 0)
			(unlocked yes)
			(layer "F.SilkS")
			(hide yes)
			(effects
				(font
					(size 0.762 0.762)
					(thickness 0.2032)
				)
			)
		)
		(sheetname "11-M2_RCB_MUX")
		(sheetfile "11-M2_RCB_MUX.kicad_sch")
		(duplicate_pad_numbers_are_jumpers no)
		(pad "1" smd rect
			(at -0.375 0 180)
			(size 0.45 0.5)
			(layers "F.Cu" "F.Mask" "F.Paste")
			(net "GPS2_PIN12")
		)
		(pad "2" smd rect
			(at 0.375 0 180)
			(size 0.45 0.5)
			(layers "F.Cu" "F.Mask" "F.Paste")
			(net "M2_GPS2_PIN12")
		)
	)
	(footprint "Vault:TECO-1909763-1_V"
		(layer "F.Cu")
		(at 77.19563 121.8662 -90)
		(property "Reference" "J3"
			(at -3.123079 0.245425 0)
			(unlocked yes)
			(layer "F.SilkS")
			(effects
				(font
					(size 0.762 0.762)
					(thickness 0.2286)
				)
			)
		)
		(property "Value" "1909763-1"
			(at 4.582685 3.722871 270)
			(unlocked yes)
			(layer "F.SilkS")
			(hide yes)
			(effects
				(font
					(size 0.762 0.762)
					(thickness 0.2286)
				)
			)
		)
		(sheetname "01-USER_IO")
		(sheetfile "01-USER_IO.kicad_sch")
		(duplicate_pad_numbers_are_jumpers no)
		(fp_line
			(start 0.55 -1.3)
			(end -0.55 -1.3)
			(stroke
				(width 0.2)
				(type solid)
			)
			(layer "F.SilkS")
		)
		(fp_circle
			(center -1.778 1.65)
			(end -1.903 1.65)
			(stroke
				(width 0.25)
				(type solid)
			)
			(fill no)
			(layer "F.SilkS")
		)
		(pad "1" smd rect
			(at -1.475 0 270)
			(size 1.05 2.2)
			(layers "F.Cu" "F.Mask" "F.Paste")
			(net "GND")
		)
		(pad "2" smd rect
			(at 0 1.525 270)
			(size 1 1.05)
			(layers "F.Cu" "F.Mask" "F.Paste")
			(net "NetAN3_1")
		)
		(pad "3" smd rect
			(at 1.475 0 270)
			(size 1.05 2.2)
			(layers "F.Cu" "F.Mask" "F.Paste")
			(net "GND")
		)
	)
	(footprint "Vault:RESC1005X40X25LL05T10"
		(layer "F.Cu")
		(at 122.6216 81.2162 180)
		(property "Reference" "R174"
			(at -2.85558 0.075489 0)
			(unlocked yes)
			(layer "F.SilkS")
			(effects
				(font
					(size 0.762 0.762)
					(thickness 0.2032)
				)
			)
		)
		(property "Value" "DNI_49.9_1%_0402"
			(at -2.579871 11.71832 90)
			(unlocked yes)
			(layer "F.SilkS")
			(hide yes)
			(effects
				(font
					(size 0.762 0.762)
					(thickness 0.2032)
				)
			)
		)
		(sheetname "11-M2_RCB_MUX")
		(sheetfile "11-M2_RCB_MUX.kicad_sch")
		(duplicate_pad_numbers_are_jumpers no)
		(pad "1" smd rect
			(at -0.375 0 270)
			(size 0.45 0.5)
			(layers "F.Cu" "F.Mask" "F.Paste")
			(net "GPS1_PIN12")
		)
		(pad "2" smd rect
			(at 0.375 0 270)
			(size 0.45 0.5)
			(layers "F.Cu" "F.Mask" "F.Paste")
			(net "M2_GPS1_PIN12")
		)
	)
	(footprint "Vault:RESC1005X40X25LL05T10"
		(layer "F.Cu")
		(at 141.0216 105.0162 180)
		(property "Reference" "R105"
			(at 1.87471 -0.026921 0)
			(unlocked yes)
			(layer "F.SilkS")
			(effects
				(font
					(size 0.762 0.762)
					(thickness 0.2286)
				)
			)
		)
		(property "Value" "DNI_49.9_1%_0402"
			(at -2.579871 11.74372 90)
			(unlocked yes)
			(layer "F.SilkS")
			(hide yes)
			(effects
				(font
					(size 0.762 0.762)
					(thickness 0.2286)
				)
			)
		)
		(sheetname "09-USBUart_PPSMUX_UARTMUX")
		(sheetfile "09-USBUart_PPSMUX_UARTMUX.kicad_sch")
		(duplicate_pad_numbers_are_jumpers no)
		(pad "1" smd rect
			(at -0.375 0 270)
			(size 0.45 0.5)
			(layers "F.Cu" "F.Mask" "F.Paste")
			(net "FPGA_MAC_PPS_OUT-")
		)
		(pad "2" smd rect
			(at 0.375 0 270)
			(size 0.45 0.5)
			(layers "F.Cu" "F.Mask" "F.Paste")
			(net "FPGA_MAC_PPSDIFF_OUT")
		)
	)
	(footprint "Vault:RESC1005X40X25NL05T05"
		(layer "F.Cu")
		(at 115.1216 52.2162 90)
		(property "Reference" "R165"
			(at 0.0032 7.526931 90)
			(unlocked yes)
			(layer "F.SilkS")
			(effects
				(font
					(size 0.762 0.762)
					(thickness 0.2032)
				)
			)
		)
		(property "Value" "DNI_27_1%_0402"
			(at -2.732271 10.270975 0)
			(unlocked yes)
			(layer "F.SilkS")
			(hide yes)
			(effects
				(font
					(size 0.762 0.762)
					(thickness 0.2032)
				)
			)
		)
		(sheetname "11-M2_RCB_MUX")
		(sheetfile "11-M2_RCB_MUX.kicad_sch")
		(duplicate_pad_numbers_are_jumpers no)
		(pad "1" smd rect
			(at -0.45 0 180)
			(size 0.55 0.55)
			(layers "F.Cu" "F.Mask" "F.Paste")
			(net "M2_GPS1_TP2")
		)
		(pad "2" smd rect
			(at 0.45 0 180)
			(size 0.55 0.55)
			(layers "F.Cu" "F.Mask" "F.Paste")
			(net "GPS1_TP2")
		)
	)
	(footprint "Vault:FP-0402-L_1_0_0_05-W_0_5-IPC_A"
		(layer "F.Cu")
		(at 111.0216 80.9162 -90)
		(property "Reference" "C32"
			(at -1.9714 0.126931 270)
			(unlocked yes)
			(layer "F.SilkS")
			(effects
				(font
					(size 0.762 0.762)
					(thickness 0.2286)
				)
			)
		)
		(property "Value" "1uF_16V_0402"
			(at 2.069035 2.567191 270)
			(unlocked yes)
			(layer "F.SilkS")
			(hide yes)
			(effects
				(font
					(size 0.762 0.762)
					(thickness 0.2286)
				)
			)
		)
		(sheetname "05-GPS_IMU_SENSORS")
		(sheetfile "05-GPS_IMU_SENSORS.kicad_sch")
		(duplicate_pad_numbers_are_jumpers no)
		(fp_line
			(start 0.83624 0.73624)
			(end -0.83624 0.73624)
			(stroke
				(width 0.2)
				(type solid)
			)
			(layer "F.SilkS")
		)
		(fp_line
			(start 0.83624 -0.73624)
			(end -0.83624 -0.73624)
			(stroke
				(width 0.2)
				(type solid)
			)
			(layer "F.SilkS")
		)
		(fp_line
			(start -1.03624 0.53624)
			(end -1.03624 -0.53624)
			(stroke
				(width 0.2)
				(type solid)
			)
			(layer "F.CrtYd")
		)
		(fp_line
			(start 1.03623 0.53624)
			(end -1.03624 0.53624)
			(stroke
				(width 0.2)
				(type solid)
			)
			(layer "F.CrtYd")
		)
		(fp_line
			(start 1.03623 0.53624)
			(end 1.03623 -0.53624)
			(stroke
				(width 0.2)
				(type solid)
			)
			(layer "F.CrtYd")
		)
		(fp_line
			(start 1.03623 -0.53624)
			(end -1.03624 -0.53624)
			(stroke
				(width 0.2)
				(type solid)
			)
			(layer "F.CrtYd")
		)
		(fp_line
			(start -1.03624 0.53624)
			(end -1.03624 -0.53624)
			(stroke
				(width 0.2)
				(type solid)
			)
			(layer "F.Fab")
		)
		(fp_line
			(start 1.03623 0.53624)
			(end -1.03624 0.53624)
			(stroke
				(width 0.2)
				(type solid)
			)
			(layer "F.Fab")
		)
		(fp_line
			(start 1.03623 0.53624)
			(end 1.03623 -0.53624)
			(stroke
				(width 0.2)
				(type solid)
			)
			(layer "F.Fab")
		)
		(fp_line
			(start 0 0.5)
			(end 0 -0.5)
			(stroke
				(width 0.1)
				(type solid)
			)
			(layer "F.Fab")
		)
		(fp_line
			(start 0.5 0)
			(end -0.5 0)
			(stroke
				(width 0.1)
				(type solid)
			)
			(layer "F.Fab")
		)
		(fp_line
			(start 1.03623 -0.53624)
			(end -1.03624 -0.53624)
			(stroke
				(width 0.2)
				(type solid)
			)
			(layer "F.Fab")
		)
		(fp_text user "${REFERENCE}"
			(at -0.00001 0.09602 270)
			(unlocked yes)
			(layer "F.Fab")
			(effects
				(font
					(face "Arial")
					(size 0.63 0.63)
					(thickness 0.1)
				)
				(justify left bottom)
			)
		)
		(pad "1" smd rect
			(at -0.47856 0 270)
			(size 0.71535 0.67248)
			(layers "F.Cu" "F.Mask" "F.Paste")
			(net "BNO_P3V3")
			(solder_mask_margin 0)
			(solder_paste_margin 0)
		)
		(pad "2" smd rect
			(at 0.47856 0 270)
			(size 0.71535 0.67248)
			(layers "F.Cu" "F.Mask" "F.Paste")
			(net "GND")
			(solder_mask_margin 0)
			(solder_paste_margin 0)
		)
	)
	(footprint "Vault:RESC1005X40X25NL10T10"
		(layer "F.Cu")
		(at 77.3216 144.0162)
		(property "Reference" "R31"
			(at -0.128605 1.273069 180)
			(unlocked yes)
			(layer "F.SilkS")
			(effects
				(font
					(size 0.762 0.762)
					(thickness 0.2286)
				)
			)
		)
		(property "Value" "4.7K_1%_0402"
			(at 1.612035 2.325871 0)
			(unlocked yes)
			(layer "F.SilkS")
			(hide yes)
			(effects
				(font
					(size 0.762 0.762)
					(thickness 0.2286)
				)
			)
		)
		(sheetname "01-USER_IO")
		(sheetfile "01-USER_IO.kicad_sch")
		(duplicate_pad_numbers_are_jumpers no)
		(pad "1" smd rect
			(at -0.425 0 90)
			(size 0.6 0.65)
			(layers "F.Cu" "F.Mask" "F.Paste")
			(net "+3.3V")
		)
		(pad "2" smd rect
			(at 0.425 0 90)
			(size 0.6 0.65)
			(layers "F.Cu" "F.Mask" "F.Paste")
			(net "ANT4_IO_OUT")
		)
	)
	(footprint "Vault:RESC1005X40X25LL05T10"
		(layer "F.Cu")
		(at 195.5216 125.7162 90)
		(property "Reference" "R168"
			(at 2.4032 0.426921 90)
			(unlocked yes)
			(layer "F.SilkS")
			(effects
				(font
					(size 0.762 0.762)
					(thickness 0.2032)
				)
			)
		)
		(property "Value" "DNI_49.9_1%_0402"
			(at -2.579871 11.71832 0)
			(unlocked yes)
			(layer "F.SilkS")
			(hide yes)
			(effects
				(font
					(size 0.762 0.762)
					(thickness 0.2032)
				)
			)
		)
		(sheetname "11-M2_RCB_MUX")
		(sheetfile "11-M2_RCB_MUX.kicad_sch")
		(duplicate_pad_numbers_are_jumpers no)
		(pad "1" smd rect
			(at -0.375 0 180)
			(size 0.45 0.5)
			(layers "F.Cu" "F.Mask" "F.Paste")
			(net "GPS2_PIN12")
		)
		(pad "2" smd rect
			(at 0.375 0 180)
			(size 0.45 0.5)
			(layers "F.Cu" "F.Mask" "F.Paste")
			(net "RCB_GPS2_PIN12")
		)
	)
	(footprint "SA53:SA53"
		(locked yes)
		(layer "F.Cu")
		(at 108.08908 118.3662 180)
		(property "Reference" "U10"
			(at -22.46112 27.623079 0)
			(unlocked yes)
			(layer "F.SilkS")
			(effects
				(font
					(size 0.762 0.762)
					(thickness 0.2286)
				)
			)
		)
		(property "Value" "MAC-SA5X"
			(at -18.327995 28.437071 180)
			(unlocked yes)
			(layer "F.SilkS")
			(hide yes)
			(effects
				(font
					(size 0.762 0.762)
					(thickness 0.2286)
				)
			)
		)
		(sheetname "06-MAC")
		(sheetfile "06-MAC.kicad_sch")
		(duplicate_pad_numbers_are_jumpers no)
		(fp_line
			(start 26.26748 26.75)
			(end -24.53252 26.75)
			(stroke
				(width 0.254)
				(type solid)
			)
			(layer "F.SilkS")
		)
		(fp_line
			(start 26.26748 -24.05)
			(end 26.26748 26.75)
			(stroke
				(width 0.254)
				(type solid)
			)
			(layer "F.SilkS")
		)
		(fp_line
			(start 26.26748 -24.05)
			(end -24.53252 -24.05)
			(stroke
				(width 0.254)
				(type solid)
			)
			(layer "F.SilkS")
		)
		(fp_line
			(start -24.53252 -24.05)
			(end -24.53252 26.75)
			(stroke
				(width 0.254)
				(type solid)
			)
			(layer "F.SilkS")
		)
		(fp_circle
			(center -15.74749 3.64129)
			(end -15.74749 3.76829)
			(stroke
				(width 0.254)
				(type solid)
			)
			(fill no)
			(layer "F.SilkS")
		)
		(pad "" np_thru_hole circle
			(at -15.05499 -16.94261 180)
			(size 6.096 6.096)
			(drill 2.54)
			(layers "*.Cu" "*.Mask")
			(thermal_bridge_angle 90)
			(padstack
				(mode front_inner_back)
				(layer "Inner"
					(shape circle)
					(size 3.048 3.048)
				)
				(layer "B.Cu"
					(shape circle)
					(size 6.096 6.096)
				)
			)
		)
		(pad "" np_thru_hole circle
			(at -14.98753 19.5926 180)
			(size 6.096 6.096)
			(drill 2.54)
			(layers "*.Cu" "*.Mask")
			(thermal_bridge_angle 90)
			(padstack
				(mode front_inner_back)
				(layer "Inner"
					(shape circle)
					(size 3.048 3.048)
				)
				(layer "B.Cu"
					(shape circle)
					(size 6.096 6.096)
				)
			)
		)
		(pad "" np_thru_hole circle
			(at 16.08749 22.666 180)
			(size 6.096 6.096)
			(drill 2.54)
			(layers "*.Cu" "*.Mask")
			(thermal_bridge_angle 90)
			(padstack
				(mode front_inner_back)
				(layer "Inner"
					(shape circle)
					(size 3.048 3.048)
				)
				(layer "B.Cu"
					(shape circle)
					(size 6.096 6.096)
				)
			)
		)
		(pad "" np_thru_hole circle
			(at 16.72249 -18.442 180)
			(size 6.096 6.096)
			(drill 2.54)
			(layers "*.Cu" "*.Mask")
			(thermal_bridge_angle 90)
			(padstack
				(mode front_inner_back)
				(layer "Inner"
					(shape circle)
					(size 3.048 3.048)
				)
				(layer "B.Cu"
					(shape circle)
					(size 6.096 6.096)
				)
			)
		)
		(pad "1" smd rect
			(at -17.16749 3.64129 270)
			(size 0.25 1.8)
			(layers "F.Cu" "F.Mask" "F.Paste")
			(net "MAC_PPS_IN1+")
		)
		(pad "2" smd rect
			(at -21.16749 3.64129 270)
			(size 0.25 1.8)
			(layers "F.Cu" "F.Mask" "F.Paste")
			(net "MAC_USB+")
		)
		(pad "3" smd rect
			(at -17.16749 3.13329 270)
			(size 0.25 1.8)
			(layers "F.Cu" "F.Mask" "F.Paste")
			(net "MAC_PPS_IN1-")
		)
		(pad "4" smd rect
			(at -21.16749 3.13329 270)
			(size 0.25 1.8)
			(layers "F.Cu" "F.Mask" "F.Paste")
			(net "MAC_USB-")
		)
		(pad "5" smd rect
			(at -17.16749 2.62529 270)
			(size 0.25 1.8)
			(layers "F.Cu" "F.Mask" "F.Paste")
			(net "MAC_PPS_IN0+")
		)
		(pad "6" smd rect
			(at -21.16749 2.62529 270)
			(size 0.25 1.8)
			(layers "F.Cu" "F.Mask" "F.Paste")
			(net "MAC_USB_PWR")
		)
		(pad "7" smd rect
			(at -17.16749 2.11729 270)
			(size 0.25 1.8)
			(layers "F.Cu" "F.Mask" "F.Paste")
			(net "MAC_PPS_IN0-")
		)
		(pad "8" smd rect
			(at -21.16749 2.11729 270)
			(size 0.25 1.8)
			(layers "F.Cu" "F.Mask" "F.Paste")
			(net "GND")
		)
		(pad "9" smd rect
			(at -17.16749 1.60929 270)
			(size 0.25 1.8)
			(layers "F.Cu" "F.Mask" "F.Paste")
			(net "GND")
		)
		(pad "10" smd rect
			(at -21.16749 1.60929 270)
			(size 0.25 1.8)
			(layers "F.Cu" "F.Mask" "F.Paste")
		)
		(pad "11" smd rect
			(at -17.16749 1.10129 270)
			(size 0.25 1.8)
			(layers "F.Cu" "F.Mask" "F.Paste")
		)
		(pad "12" smd rect
			(at -21.16749 1.10129 270)
			(size 0.25 1.8)
			(layers "F.Cu" "F.Mask" "F.Paste")
		)
		(pad "13" smd rect
			(at -17.16749 0.59329 270)
			(size 0.25 1.8)
			(layers "F.Cu" "F.Mask" "F.Paste")
		)
		(pad "14" smd rect
			(at -21.16749 0.59329 270)
			(size 0.25 1.8)
			(layers "F.Cu" "F.Mask" "F.Paste")
		)
		(pad "15" smd rect
			(at -17.16749 0.08529 270)
			(size 0.25 1.8)
			(layers "F.Cu" "F.Mask" "F.Paste")
			(net "GND")
		)
		(pad "16" smd rect
			(at -21.16749 0.08529 270)
			(size 0.25 1.8)
			(layers "F.Cu" "F.Mask" "F.Paste")
		)
		(pad "17" smd rect
			(at -17.16749 -0.42271 270)
			(size 0.25 1.8)
			(layers "F.Cu" "F.Mask" "F.Paste")
			(net "MAC_PPS_OUT+")
		)
		(pad "18" smd rect
			(at -21.16749 -0.42271 270)
			(size 0.25 1.8)
			(layers "F.Cu" "F.Mask" "F.Paste")
		)
		(pad "19" smd rect
			(at -17.16749 -0.93071 270)
			(size 0.25 1.8)
			(layers "F.Cu" "F.Mask" "F.Paste")
			(net "MAC_PPS_OUT-")
		)
		(pad "20" smd rect
			(at -21.16749 -0.93071 270)
			(size 0.25 1.8)
			(layers "F.Cu" "F.Mask" "F.Paste")
			(net "MAC_ALARM")
		)
		(pad "P1" thru_hole circle
			(at 21.16748 21.65 90)
			(size 2.54 2.54)
			(drill 2.0066)
			(layers "*.Cu" "*.Mask")
			(remove_unused_layers no)
			(net "MAC_FREQ_CTRL")
			(thermal_bridge_angle 90)
		)
		(pad "P2" thru_hole circle
			(at 21.16748 1.35 90)
			(size 2.54 2.54)
			(drill 2.0066)
			(layers "*.Cu" "*.Mask")
			(remove_unused_layers no)
			(net "GND")
			(thermal_bridge_angle 90)
		)
		(pad "P3" thru_hole circle
			(at 21.16748 -18.95 90)
			(size 2.54 2.54)
			(drill 2.0066)
			(layers "*.Cu" "*.Mask")
			(remove_unused_layers no)
			(net "MAC_RF_OUT")
			(thermal_bridge_angle 90)
		)
		(pad "P4" thru_hole circle
			(at -19.43252 -18.95 90)
			(size 2.54 2.54)
			(drill 2.0066)
			(layers "*.Cu" "*.Mask")
			(remove_unused_layers no)
			(net "GND")
			(thermal_bridge_angle 90)
		)
		(pad "P5" thru_hole circle
			(at -19.43252 21.65 90)
			(size 2.54 2.54)
			(drill 2.0066)
			(layers "*.Cu" "*.Mask")
			(remove_unused_layers no)
			(net "MAC_VCC")
			(thermal_bridge_angle 90)
		)
		(pad "P6" thru_hole circle
			(at -17.33252 -21.65 90)
			(size 2.54 2.54)
			(drill 2.0066)
			(layers "*.Cu" "*.Mask")
			(remove_unused_layers no)
			(net "MAC_BITE")
			(thermal_bridge_angle 90)
		)
		(pad "P7" thru_hole circle
			(at -14.33252 -21.65 90)
			(size 2.54 2.54)
			(drill 2.0066)
			(layers "*.Cu" "*.Mask")
			(remove_unused_layers no)
			(net "MAC_RX")
			(thermal_bridge_angle 90)
		)
		(pad "P8" thru_hole circle
			(at -11.33252 -21.65 90)
			(size 2.54 2.54)
			(drill 2.0066)
			(layers "*.Cu" "*.Mask")
			(remove_unused_layers no)
			(net "MAC_TX")
			(thermal_bridge_angle 90)
		)
		(pad "P9" thru_hole circle
			(at -8.28452 -21.65 90)
			(size 2.54 2.54)
			(drill 2.0066)
			(layers "*.Cu" "*.Mask")
			(remove_unused_layers no)
			(net "MAC_PPS_IN")
			(thermal_bridge_angle 90)
		)
		(pad "P10" thru_hole circle
			(at -5.23652 -21.65 90)
			(size 2.54 2.54)
			(drill 2.0066)
			(layers "*.Cu" "*.Mask")
			(remove_unused_layers no)
			(net "MAC_PPS_OUT")
			(thermal_bridge_angle 90)
		)
		(zone
			(layer "F.Cu")
			(hatch edge 0.5)
			(connect_pads
				(clearance 0)
			)
			(min_thickness 0.25)
			(keepout
				(tracks allowed)
				(vias allowed)
				(pads allowed)
				(copperpour not_allowed)
				(footprints allowed)
			)
			(placement
				(enabled no)
				(sheetname "")
			)
			(fill
				(thermal_gap 0.5)
				(thermal_bridge_width 0.5)
				(island_removal_mode 0)
			)
			(polygon
				(pts
					(xy 123.58908 121.8662) (xy 123.58909 111.8662) (xy 131.08909 111.8662) (xy 131.08908 121.8662)
				)
			)
		)
		(zone
			(layer "F.Cu")
			(hatch edge 0.5)
			(connect_pads
				(clearance 0)
			)
			(min_thickness 0.25)
			(keepout
				(tracks allowed)
				(vias allowed)
				(pads allowed)
				(copperpour not_allowed)
				(footprints allowed)
			)
			(placement
				(enabled no)
				(sheetname "")
			)
			(fill
				(thermal_gap 0.5)
				(thermal_bridge_width 0.5)
				(island_removal_mode 0)
			)
			(polygon
				(pts
					(xy 132.58908 123.3662) (xy 121.08908 123.3662) (xy 121.08908 110.8662) (xy 132.58908 110.8662)
				)
			)
		)
	)
	(footprint "Vault:CAPC1005X55X25ML05T05"
		(layer "F.Cu")
		(at 120.18072 85.4662 -90)
		(property "Reference" "C39"
			(at -2.3532 0.032189 90)
			(unlocked yes)
			(layer "F.SilkS")
			(effects
				(font
					(size 0.762 0.762)
					(thickness 0.2032)
				)
			)
		)
		(property "Value" "22pF_50V_0402"
			(at -2.808431 9.48378 180)
			(unlocked yes)
			(layer "F.SilkS")
			(hide yes)
			(effects
				(font
					(size 0.762 0.762)
					(thickness 0.2032)
				)
			)
		)
		(sheetname "05-GPS_IMU_SENSORS")
		(sheetfile "05-GPS_IMU_SENSORS.kicad_sch")
		(duplicate_pad_numbers_are_jumpers no)
		(pad "1" smd rect
			(at -0.51 0)
			(size 0.72 0.72)
			(layers "F.Cu" "F.Mask" "F.Paste")
			(net "GND")
		)
		(pad "2" smd rect
			(at 0.51 0)
			(size 0.72 0.72)
			(layers "F.Cu" "F.Mask" "F.Paste")
			(net "BNO_XIN32")
		)
	)
	(footprint "Vault:FP-LTST-C191KGKT-MFG"
		(layer "F.Cu")
		(at 79.4216 55.6162)
		(property "Reference" "D11"
			(at -3.7 1.193345 0)
			(unlocked yes)
			(layer "F.SilkS")
			(effects
				(font
					(size 0.762 0.762)
					(thickness 0.2286)
				)
				(justify left bottom)
			)
		)
		(property "Value" "LTST-C191KGKT"
			(at 2.0903 -0.371355 0)
			(unlocked yes)
			(layer "F.SilkS")
			(hide yes)
			(effects
				(font
					(size 0.762 0.762)
					(thickness 0.2286)
				)
				(justify left bottom)
			)
		)
		(sheetname "02-USER_IO_STATUS")
		(sheetfile "02-USER_IO_STATUS.kicad_sch")
		(duplicate_pad_numbers_are_jumpers no)
		(fp_line
			(start -0.85 -0.775)
			(end 0.85 -0.775)
			(stroke
				(width 0.2)
				(type solid)
			)
			(layer "F.SilkS")
		)
		(fp_line
			(start -0.85 0.775)
			(end 0.85 0.775)
			(stroke
				(width 0.2)
				(type solid)
			)
			(layer "F.SilkS")
		)
		(fp_circle
			(center -1.7 0)
			(end -1.7 -0.125)
			(stroke
				(width 0.25)
				(type solid)
			)
			(fill no)
			(layer "F.SilkS")
		)
		(fp_line
			(start -1.25 -0.55)
			(end 1.25 -0.55)
			(stroke
				(width 0.2)
				(type solid)
			)
			(layer "F.CrtYd")
		)
		(fp_line
			(start -1.25 0.55)
			(end -1.25 -0.55)
			(stroke
				(width 0.2)
				(type solid)
			)
			(layer "F.CrtYd")
		)
		(fp_line
			(start -1.25 0.55)
			(end 1.25 0.55)
			(stroke
				(width 0.2)
				(type solid)
			)
			(layer "F.CrtYd")
		)
		(fp_line
			(start 1.25 0.55)
			(end 1.25 -0.55)
			(stroke
				(width 0.2)
				(type solid)
			)
			(layer "F.CrtYd")
		)
		(fp_line
			(start -1.25 -0.55)
			(end 1.25 -0.55)
			(stroke
				(width 0.2)
				(type solid)
			)
			(layer "F.Fab")
		)
		(fp_line
			(start -1.25 0.55)
			(end -1.25 -0.55)
			(stroke
				(width 0.2)
				(type solid)
			)
			(layer "F.Fab")
		)
		(fp_line
			(start -1.25 0.55)
			(end 1.25 0.55)
			(stroke
				(width 0.2)
				(type solid)
			)
			(layer "F.Fab")
		)
		(fp_line
			(start -0.5 0)
			(end 0.5 0)
			(stroke
				(width 0.1)
				(type solid)
			)
			(layer "F.Fab")
		)
		(fp_line
			(start 0 0.5)
			(end 0 -0.5)
			(stroke
				(width 0.1)
				(type solid)
			)
			(layer "F.Fab")
		)
		(fp_line
			(start 1.25 0.55)
			(end 1.25 -0.55)
			(stroke
				(width 0.2)
				(type solid)
			)
			(layer "F.Fab")
		)
		(fp_text user "${REFERENCE}"
			(at 0 0.29534 360)
			(unlocked yes)
			(layer "F.Fab")
			(effects
				(font
					(face "Arial")
					(size 0.63 0.63)
					(thickness 0.1)
				)
				(justify left bottom)
			)
		)
		(pad "1" smd rect
			(at -0.75 0)
			(size 0.8 0.8)
			(layers "F.Cu" "F.Mask" "F.Paste")
			(net "NetD11_1")
			(solder_mask_margin 0)
			(solder_paste_margin 0)
		)
		(pad "2" smd rect
			(at 0.75 0)
			(size 0.8 0.8)
			(layers "F.Cu" "F.Mask" "F.Paste")
			(net "+3.3V")
			(solder_mask_margin 0)
			(solder_paste_margin 0)
		)
	)
	(footprint "Vault:FP-T521X476M035ATE030-MFG"
		(layer "F.Cu")
		(at 187.4216 92.7162 90)
		(property "Reference" "C73"
			(at 1.4968 3.073069 270)
			(unlocked yes)
			(layer "F.SilkS")
			(effects
				(font
					(size 0.762 0.762)
					(thickness 0.2032)
				)
			)
		)
		(property "Value" "47uF_35V_2917"
			(at -5.843751 7.45182 0)
			(unlocked yes)
			(layer "F.SilkS")
			(hide yes)
			(effects
				(font
					(size 0.762 0.762)
					(thickness 0.2032)
				)
			)
		)
		(sheetname "03-POWER")
		(sheetfile "03-POWER.kicad_sch")
		(duplicate_pad_numbers_are_jumpers no)
		(fp_line
			(start 3.8 -2.3)
			(end 3.8 -1.54)
			(stroke
				(width 0.2)
				(type solid)
			)
			(layer "F.SilkS")
		)
		(fp_line
			(start -3.8 -2.3)
			(end 3.8 -2.3)
			(stroke
				(width 0.2)
				(type solid)
			)
			(layer "F.SilkS")
		)
		(fp_line
			(start -3.8 -2.3)
			(end -3.8 -1.54)
			(stroke
				(width 0.2)
				(type solid)
			)
			(layer "F.SilkS")
		)
		(fp_line
			(start 4.7 -0.3)
			(end 4.7 0.3)
			(stroke
				(width 0.2)
				(type solid)
			)
			(layer "F.SilkS")
		)
		(fp_line
			(start 4.4 0)
			(end 5 0)
			(stroke
				(width 0.2)
				(type solid)
			)
			(layer "F.SilkS")
		)
		(fp_line
			(start 3.8 1.54)
			(end 3.8 2.3)
			(stroke
				(width 0.2)
				(type solid)
			)
			(layer "F.SilkS")
		)
		(fp_line
			(start -3.8 1.54)
			(end -3.8 2.3)
			(stroke
				(width 0.2)
				(type solid)
			)
			(layer "F.SilkS")
		)
		(fp_line
			(start -3.8 2.3)
			(end 3.8 2.3)
			(stroke
				(width 0.2)
				(type solid)
			)
			(layer "F.SilkS")
		)
		(fp_line
			(start 4.13 -2.42)
			(end 4.13 2.42)
			(stroke
				(width 0.2)
				(type solid)
			)
			(layer "F.CrtYd")
		)
		(fp_line
			(start -4.13 -2.42)
			(end 4.13 -2.42)
			(stroke
				(width 0.2)
				(type solid)
			)
			(layer "F.CrtYd")
		)
		(fp_line
			(start -4.13 -2.42)
			(end -4.13 2.42)
			(stroke
				(width 0.2)
				(type solid)
			)
			(layer "F.CrtYd")
		)
		(fp_line
			(start -4.13 2.42)
			(end 4.13 2.42)
			(stroke
				(width 0.2)
				(type solid)
			)
			(layer "F.CrtYd")
		)
		(fp_line
			(start 4.13 -2.42)
			(end 4.13 2.42)
			(stroke
				(width 0.2)
				(type solid)
			)
			(layer "F.Fab")
		)
		(fp_line
			(start -4.13 -2.42)
			(end 4.13 -2.42)
			(stroke
				(width 0.2)
				(type solid)
			)
			(layer "F.Fab")
		)
		(fp_line
			(start -4.13 -2.42)
			(end -4.13 2.42)
			(stroke
				(width 0.2)
				(type solid)
			)
			(layer "F.Fab")
		)
		(fp_line
			(start 0 -0.5)
			(end 0 0.5)
			(stroke
				(width 0.1)
				(type solid)
			)
			(layer "F.Fab")
		)
		(fp_line
			(start -0.5 0)
			(end 0.5 0)
			(stroke
				(width 0.1)
				(type solid)
			)
			(layer "F.Fab")
		)
		(fp_line
			(start -4.13 2.42)
			(end 4.13 2.42)
			(stroke
				(width 0.2)
				(type solid)
			)
			(layer "F.Fab")
		)
		(fp_text user "${REFERENCE}"
			(at 0 0.28425 90)
			(unlocked yes)
			(layer "F.Fab")
			(effects
				(font
					(face "Arial")
					(size 0.63 0.63)
					(thickness 0.1)
				)
				(justify left bottom)
			)
		)
		(pad "1" smd rect
			(at -3.01 0 90)
			(size 1.99 2.33)
			(layers "F.Cu" "F.Mask" "F.Paste")
			(net "GND")
			(solder_mask_margin 0)
			(solder_paste_margin 0)
		)
		(pad "2" smd rect
			(at 3.01 0 90)
			(size 1.99 2.33)
			(layers "F.Cu" "F.Mask" "F.Paste")
			(net "+12V")
			(solder_mask_margin 0)
			(solder_paste_margin 0)
		)
	)
	(footprint "Vault:FP-C0603C105K3PACTU-MFG"
		(layer "F.Cu")
		(at 86.70687 86.4137 -90)
		(property "Reference" "C38"
			(at -0.32859 2.973079 90)
			(unlocked yes)
			(layer "F.SilkS")
			(effects
				(font
					(size 0.762 0.762)
					(thickness 0.2286)
				)
			)
		)
		(property "Value" "1uF"
			(at -2.859271 1.45989 180)
			(unlocked yes)
			(layer "F.SilkS")
			(hide yes)
			(effects
				(font
					(size 0.762 0.762)
					(thickness 0.2286)
				)
			)
		)
		(sheetname "02-USER_IO_STATUS")
		(sheetfile "02-USER_IO_STATUS.kicad_sch")
		(duplicate_pad_numbers_are_jumpers no)
		(fp_line
			(start 0.875 0.825)
			(end -0.875 0.825)
			(stroke
				(width 0.2)
				(type solid)
			)
			(layer "F.SilkS")
		)
		(fp_line
			(start 0.875 -0.825)
			(end -0.875 -0.825)
			(stroke
				(width 0.2)
				(type solid)
			)
			(layer "F.SilkS")
		)
		(fp_line
			(start -1.2 0.6)
			(end -1.2 -0.59999)
			(stroke
				(width 0.2)
				(type solid)
			)
			(layer "F.CrtYd")
		)
		(fp_line
			(start 1.2 0.6)
			(end -1.2 0.6)
			(stroke
				(width 0.2)
				(type solid)
			)
			(layer "F.CrtYd")
		)
		(fp_line
			(start 1.2 0.6)
			(end 1.2 -0.59999)
			(stroke
				(width 0.2)
				(type solid)
			)
			(layer "F.CrtYd")
		)
		(fp_line
			(start 1.2 -0.59999)
			(end -1.2 -0.59999)
			(stroke
				(width 0.2)
				(type solid)
			)
			(layer "F.CrtYd")
		)
		(fp_line
			(start -1.2 0.6)
			(end -1.2 -0.59999)
			(stroke
				(width 0.2)
				(type solid)
			)
			(layer "F.Fab")
		)
		(fp_line
			(start 1.2 0.6)
			(end -1.2 0.6)
			(stroke
				(width 0.2)
				(type solid)
			)
			(layer "F.Fab")
		)
		(fp_line
			(start 1.2 0.6)
			(end 1.2 -0.59999)
			(stroke
				(width 0.2)
				(type solid)
			)
			(layer "F.Fab")
		)
		(fp_line
			(start 0 0.5)
			(end 0 -0.49999)
			(stroke
				(width 0.1)
				(type solid)
			)
			(layer "F.Fab")
		)
		(fp_line
			(start 0.5 0)
			(end -0.5 0)
			(stroke
				(width 0.1)
				(type solid)
			)
			(layer "F.Fab")
		)
		(fp_line
			(start 1.2 -0.59999)
			(end -1.2 -0.59999)
			(stroke
				(width 0.2)
				(type solid)
			)
			(layer "F.Fab")
		)
		(pad "1" smd rect
			(at -0.6 0 270)
			(size 0.75 0.9)
			(layers "F.Cu" "F.Mask" "F.Paste")
			(net "+3.3V")
			(solder_mask_margin 0)
			(solder_paste_margin 0)
		)
		(pad "2" smd rect
			(at 0.6 0 270)
			(size 0.75 0.9)
			(layers "F.Cu" "F.Mask" "F.Paste")
			(net "GND")
			(solder_mask_margin 0)
			(solder_paste_margin 0)
		)
	)
	(footprint "Vault:RESC1005X40X25LL05T10"
		(layer "F.Cu")
		(at 196.2216 129.7162 90)
		(property "Reference" "R143"
			(at 2.5032 0.226931 90)
			(unlocked yes)
			(layer "F.SilkS")
			(effects
				(font
					(size 0.762 0.762)
					(thickness 0.2032)
				)
			)
		)
		(property "Value" "49.9_1%_0402"
			(at -2.579871 8.798265 0)
			(unlocked yes)
			(layer "F.SilkS")
			(hide yes)
			(effects
				(font
					(size 0.762 0.762)
					(thickness 0.2032)
				)
			)
		)
		(sheetname "11-M2_RCB_MUX")
		(sheetfile "11-M2_RCB_MUX.kicad_sch")
		(duplicate_pad_numbers_are_jumpers no)
		(pad "1" smd rect
			(at -0.375 0 180)
			(size 0.45 0.5)
			(layers "F.Cu" "F.Mask" "F.Paste")
			(net "NetR143_1")
		)
		(pad "2" smd rect
			(at 0.375 0 180)
			(size 0.45 0.5)
			(layers "F.Cu" "F.Mask" "F.Paste")
			(net "GPS2_TP2")
		)
	)
	(footprint "Vault:RESC1005X40X25LL05T10"
		(layer "F.Cu")
		(at 194.8216 120.0162 90)
		(property "Reference" "R171"
			(at 2.5032 0.026931 90)
			(unlocked yes)
			(layer "F.SilkS")
			(effects
				(font
					(size 0.762 0.762)
					(thickness 0.2032)
				)
			)
		)
		(property "Value" "49.9_1%_0402"
			(at -2.579871 8.798265 0)
			(unlocked yes)
			(layer "F.SilkS")
			(hide yes)
			(effects
				(font
					(size 0.762 0.762)
					(thickness 0.2032)
				)
			)
		)
		(sheetname "11-M2_RCB_MUX")
		(sheetfile "11-M2_RCB_MUX.kicad_sch")
		(duplicate_pad_numbers_are_jumpers no)
		(pad "1" smd rect
			(at -0.375 0 180)
			(size 0.45 0.5)
			(layers "F.Cu" "F.Mask" "F.Paste")
			(net "NetR171_1")
		)
		(pad "2" smd rect
			(at 0.375 0 180)
			(size 0.45 0.5)
			(layers "F.Cu" "F.Mask" "F.Paste")
			(net "GPS2_PIN11")
		)
	)
	(footprint "Vault:RESC1005X40X25NL10T10"
		(layer "F.Cu")
		(at 175.3216 110.9162)
		(property "Reference" "R114"
			(at 0.8032 -1.273069 0)
			(unlocked yes)
			(layer "F.SilkS")
			(effects
				(font
					(size 0.762 0.762)
					(thickness 0.2032)
				)
			)
		)
		(property "Value" "4.7K_1%_0402"
			(at -2.732281 8.747465 270)
			(unlocked yes)
			(layer "F.SilkS")
			(hide yes)
			(effects
				(font
					(size 0.762 0.762)
					(thickness 0.2032)
				)
			)
		)
		(sheetname "08-DIPSwitches_I2C")
		(sheetfile "08-DIPSwitches_I2C.kicad_sch")
		(duplicate_pad_numbers_are_jumpers no)
		(pad "1" smd rect
			(at -0.425 0 90)
			(size 0.6 0.65)
			(layers "F.Cu" "F.Mask" "F.Paste")
			(net "DC_I2C_SCL")
		)
		(pad "2" smd rect
			(at 0.425 0 90)
			(size 0.6 0.65)
			(layers "F.Cu" "F.Mask" "F.Paste")
			(net "+3.3V")
		)
	)
	(footprint "Vault:RESC1608X55X25NL10T15"
		(layer "F.Cu")
		(at 72.4216 141.0162 90)
		(property "Reference" "R34"
			(at 0.1286 -1.673069 90)
			(unlocked yes)
			(layer "F.SilkS")
			(effects
				(font
					(size 0.762 0.762)
					(thickness 0.2286)
				)
			)
		)
		(property "Value" "49.9R"
			(at -2.884671 3.186585 0)
			(unlocked yes)
			(layer "F.SilkS")
			(hide yes)
			(effects
				(font
					(size 0.762 0.762)
					(thickness 0.2286)
				)
			)
		)
		(sheetname "01-USER_IO")
		(sheetfile "01-USER_IO.kicad_sch")
		(duplicate_pad_numbers_are_jumpers no)
		(pad "1" smd rect
			(at -0.7 0 180)
			(size 0.9 0.7)
			(layers "F.Cu" "F.Mask" "F.Paste")
			(net "NetR34_1")
		)
		(pad "2" smd rect
			(at 0.7 0 180)
			(size 0.9 0.7)
			(layers "F.Cu" "F.Mask" "F.Paste")
			(net "NetAN4_1")
		)
	)
	(footprint "Vault:SOT143-4L"
		(layer "F.Cu")
		(at 71.87161 128.1162 90)
		(property "Reference" "D2"
			(at -0.328605 2.323059 270)
			(unlocked yes)
			(layer "F.SilkS")
			(effects
				(font
					(size 0.762 0.762)
					(thickness 0.2286)
				)
			)
		)
		(property "Value" "8240136"
			(at 2.6781 3.341871 90)
			(unlocked yes)
			(layer "F.SilkS")
			(hide yes)
			(effects
				(font
					(size 0.762 0.762)
					(thickness 0.2286)
				)
			)
		)
		(sheetname "01-USER_IO")
		(sheetfile "01-USER_IO.kicad_sch")
		(duplicate_pad_numbers_are_jumpers no)
		(fp_line
			(start 2.05 -1.7)
			(end 2.05 1.7)
			(stroke
				(width 0.2)
				(type solid)
			)
			(layer "F.SilkS")
		)
		(fp_line
			(start -2.05 -1.7)
			(end 2.05 -1.7)
			(stroke
				(width 0.2)
				(type solid)
			)
			(layer "F.SilkS")
		)
		(fp_line
			(start -2.05 -1.7)
			(end -2.05 1.675)
			(stroke
				(width 0.2)
				(type solid)
			)
			(layer "F.SilkS")
		)
		(fp_line
			(start -2.05 1.7)
			(end 2.05 1.7)
			(stroke
				(width 0.2)
				(type solid)
			)
			(layer "F.SilkS")
		)
		(fp_circle
			(center -2.404 -1.075)
			(end -2.15 -1.075)
			(stroke
				(width 0.2)
				(type solid)
			)
			(fill no)
			(layer "F.SilkS")
		)
		(pad "1" smd rect
			(at -1.1 -0.75 180)
			(size 1.4 1.4)
			(layers "F.Cu" "F.Mask" "F.Paste")
			(net "GND")
		)
		(pad "2" smd rect
			(at -1.1 0.95 180)
			(size 1 1.4)
			(layers "F.Cu" "F.Mask" "F.Paste")
			(net "NetAN4_1")
		)
		(pad "3" smd rect
			(at 1.1 0.95 180)
			(size 1 1.4)
			(layers "F.Cu" "F.Mask" "F.Paste")
			(net "NetAN3_1")
		)
		(pad "4" smd rect
			(at 1.1 -0.95 180)
			(size 1 1.4)
			(layers "F.Cu" "F.Mask" "F.Paste")
			(net "+3.3V")
		)
	)
	(footprint "Vault:FP-T495D107K016ATE125-MFG"
		(layer "F.Cu")
		(at 160.1116 89.1162)
		(property "Reference" "C79"
			(at -2.3614 -2.973079 0)
			(unlocked yes)
			(layer "F.SilkS")
			(effects
				(font
					(size 0.762 0.762)
					(thickness 0.2286)
				)
			)
		)
		(property "Value" "100uF_16V_2917"
			(at -5.818351 8.010455 270)
			(unlocked yes)
			(layer "F.SilkS")
			(hide yes)
			(effects
				(font
					(size 0.762 0.762)
					(thickness 0.2286)
				)
			)
		)
		(sheetname "03-POWER")
		(sheetfile "03-POWER.kicad_sch")
		(duplicate_pad_numbers_are_jumpers no)
		(fp_line
			(start -3.8 -2.3)
			(end 3.8 -2.3)
			(stroke
				(width 0.2)
				(type solid)
			)
			(layer "F.SilkS")
		)
		(fp_line
			(start -3.8 -1.54)
			(end -3.8 -2.3)
			(stroke
				(width 0.2)
				(type solid)
			)
			(layer "F.SilkS")
		)
		(fp_line
			(start -3.8 2.3)
			(end -3.8 1.54)
			(stroke
				(width 0.2)
				(type solid)
			)
			(layer "F.SilkS")
		)
		(fp_line
			(start -3.8 2.3)
			(end 3.8 2.3)
			(stroke
				(width 0.2)
				(type solid)
			)
			(layer "F.SilkS")
		)
		(fp_line
			(start 3.8 -1.54)
			(end 3.8 -2.3)
			(stroke
				(width 0.2)
				(type solid)
			)
			(layer "F.SilkS")
		)
		(fp_line
			(start 3.8 2.3)
			(end 3.8 1.54)
			(stroke
				(width 0.2)
				(type solid)
			)
			(layer "F.SilkS")
		)
		(fp_line
			(start 4.4 0)
			(end 5 0)
			(stroke
				(width 0.2)
				(type solid)
			)
			(layer "F.SilkS")
		)
		(fp_line
			(start 4.7 0.3)
			(end 4.7 -0.3)
			(stroke
				(width 0.2)
				(type solid)
			)
			(layer "F.SilkS")
		)
		(fp_line
			(start -4.105 -2.4)
			(end 4.105 -2.4)
			(stroke
				(width 0.2)
				(type solid)
			)
			(layer "F.CrtYd")
		)
		(fp_line
			(start -4.105 2.4)
			(end -4.105 -2.4)
			(stroke
				(width 0.2)
				(type solid)
			)
			(layer "F.CrtYd")
		)
		(fp_line
			(start -4.105 2.4)
			(end 4.105 2.4)
			(stroke
				(width 0.2)
				(type solid)
			)
			(layer "F.CrtYd")
		)
		(fp_line
			(start 4.105 2.4)
			(end 4.105 -2.4)
			(stroke
				(width 0.2)
				(type solid)
			)
			(layer "F.CrtYd")
		)
		(fp_line
			(start -4.105 -2.4)
			(end 4.105 -2.4)
			(stroke
				(width 0.2)
				(type solid)
			)
			(layer "F.Fab")
		)
		(fp_line
			(start -4.105 2.4)
			(end -4.105 -2.4)
			(stroke
				(width 0.2)
				(type solid)
			)
			(layer "F.Fab")
		)
		(fp_line
			(start -4.105 2.4)
			(end 4.105 2.4)
			(stroke
				(width 0.2)
				(type solid)
			)
			(layer "F.Fab")
		)
		(fp_line
			(start -0.5 0)
			(end 0.5 0)
			(stroke
				(width 0.1)
				(type solid)
			)
			(layer "F.Fab")
		)
		(fp_line
			(start 0 0.5)
			(end 0 -0.5)
			(stroke
				(width 0.1)
				(type solid)
			)
			(layer "F.Fab")
		)
		(fp_line
			(start 4.105 2.4)
			(end 4.105 -2.4)
			(stroke
				(width 0.2)
				(type solid)
			)
			(layer "F.Fab")
		)
		(fp_text user "${REFERENCE}"
			(at 0 0.28425 360)
			(unlocked yes)
			(layer "F.Fab")
			(effects
				(font
					(face "Arial")
					(size 0.63 0.63)
					(thickness 0.1)
				)
				(justify left bottom)
			)
		)
		(pad "1" smd rect
			(at -3.01 0)
			(size 1.99 2.33)
			(layers "F.Cu" "F.Mask" "F.Paste")
			(net "GND")
			(solder_mask_margin 0)
			(solder_paste_margin 0)
		)
		(pad "2" smd rect
			(at 3.01 0)
			(size 1.99 2.33)
			(layers "F.Cu" "F.Mask" "F.Paste")
			(net "+3.3V")
			(solder_mask_margin 0)
			(solder_paste_margin 0)
		)
	)
	(footprint "Vault:FP-D0008A-MFG"
		(layer "F.Cu")
		(at 86.2116 68.03347)
		(property "Reference" "U17"
			(at -3.2614 -3.290339 0)
			(unlocked yes)
			(layer "F.SilkS")
			(effects
				(font
					(size 0.762 0.762)
					(thickness 0.2286)
				)
			)
		)
		(property "Value" "INA219BIDR"
			(at 3.16004 4.408671 0)
			(unlocked yes)
			(layer "F.SilkS")
			(hide yes)
			(effects
				(font
					(size 0.762 0.762)
					(thickness 0.2286)
				)
			)
		)
		(sheetname "03-POWER")
		(sheetfile "03-POWER.kicad_sch")
		(duplicate_pad_numbers_are_jumpers no)
		(fp_line
			(start -1.5 -2.5)
			(end 1.5 -2.5)
			(stroke
				(width 0.2)
				(type solid)
			)
			(layer "F.SilkS")
		)
		(fp_line
			(start -1.5 2.5)
			(end -1.5 -2.5)
			(stroke
				(width 0.2)
				(type solid)
			)
			(layer "F.SilkS")
		)
		(fp_line
			(start -1.5 2.5)
			(end 1.5 2.5)
			(stroke
				(width 0.2)
				(type solid)
			)
			(layer "F.SilkS")
		)
		(fp_line
			(start 1.5 2.5)
			(end 1.5 -2.5)
			(stroke
				(width 0.2)
				(type solid)
			)
			(layer "F.SilkS")
		)
		(fp_circle
			(center -4.05 -1.905)
			(end -4.05 -2.03)
			(stroke
				(width 0.25)
				(type solid)
			)
			(fill no)
			(layer "F.SilkS")
		)
		(fp_circle
			(center -0.725 -1.725)
			(end -0.725 -1.975)
			(stroke
				(width 0.5)
				(type solid)
			)
			(fill no)
			(layer "F.SilkS")
		)
		(fp_line
			(start -3.575 -2.75)
			(end 3.575 -2.75)
			(stroke
				(width 0.2)
				(type solid)
			)
			(layer "F.CrtYd")
		)
		(fp_line
			(start -3.575 2.75)
			(end -3.575 -2.75)
			(stroke
				(width 0.2)
				(type solid)
			)
			(layer "F.CrtYd")
		)
		(fp_line
			(start -3.575 2.75)
			(end 3.575 2.75)
			(stroke
				(width 0.2)
				(type solid)
			)
			(layer "F.CrtYd")
		)
		(fp_line
			(start 3.575 2.75)
			(end 3.575 -2.75)
			(stroke
				(width 0.2)
				(type solid)
			)
			(layer "F.CrtYd")
		)
		(fp_line
			(start -3.575 -2.75)
			(end 3.575 -2.75)
			(stroke
				(width 0.2)
				(type solid)
			)
			(layer "F.Fab")
		)
		(fp_line
			(start -3.575 2.75)
			(end -3.575 -2.75)
			(stroke
				(width 0.2)
				(type solid)
			)
			(layer "F.Fab")
		)
		(fp_line
			(start -3.575 2.75)
			(end 3.575 2.75)
			(stroke
				(width 0.2)
				(type solid)
			)
			(layer "F.Fab")
		)
		(fp_line
			(start -0.5 0)
			(end 0.5 0)
			(stroke
				(width 0.1)
				(type solid)
			)
			(layer "F.Fab")
		)
		(fp_line
			(start 0 0.5)
			(end 0 -0.5)
			(stroke
				(width 0.1)
				(type solid)
			)
			(layer "F.Fab")
		)
		(fp_line
			(start 3.575 2.75)
			(end 3.575 -2.75)
			(stroke
				(width 0.2)
				(type solid)
			)
			(layer "F.Fab")
		)
		(fp_text user "${REFERENCE}"
			(at -0.00001 0.09601 360)
			(unlocked yes)
			(layer "F.Fab")
			(effects
				(font
					(face "Arial")
					(size 0.63 0.63)
					(thickness 0.1)
				)
				(justify left bottom)
			)
		)
		(pad "1" smd roundrect
			(at -2.7 -1.905)
			(size 1.55 0.6)
			(layers "F.Cu" "F.Mask" "F.Paste")
			(roundrect_rratio 0.085)
			(net "NetR66_1")
			(solder_mask_margin 0)
			(solder_paste_margin 0)
		)
		(pad "2" smd roundrect
			(at -2.7 -0.635)
			(size 1.55 0.6)
			(layers "F.Cu" "F.Mask" "F.Paste")
			(roundrect_rratio 0.085)
			(net "NetR65_1")
			(solder_mask_margin 0)
			(solder_paste_margin 0)
		)
		(pad "3" smd roundrect
			(at -2.7 0.635)
			(size 1.55 0.6)
			(layers "F.Cu" "F.Mask" "F.Paste")
			(roundrect_rratio 0.085)
			(net "SENS_I2C_SDA")
			(solder_mask_margin 0)
			(solder_paste_margin 0)
		)
		(pad "4" smd roundrect
			(at -2.7 1.905)
			(size 1.55 0.6)
			(layers "F.Cu" "F.Mask" "F.Paste")
			(roundrect_rratio 0.085)
			(net "SENS_I2C_SCL")
			(solder_mask_margin 0)
			(solder_paste_margin 0)
		)
		(pad "5" smd roundrect
			(at 2.7 1.905)
			(size 1.55 0.6)
			(layers "F.Cu" "F.Mask" "F.Paste")
			(roundrect_rratio 0.085)
			(net "+3.3V")
			(solder_mask_margin 0)
			(solder_paste_margin 0)
		)
		(pad "6" smd roundrect
			(at 2.7 0.635)
			(size 1.55 0.6)
			(layers "F.Cu" "F.Mask" "F.Paste")
			(roundrect_rratio 0.085)
			(net "GND")
			(solder_mask_margin 0)
			(solder_paste_margin 0)
		)
		(pad "7" smd roundrect
			(at 2.7 -0.635)
			(size 1.55 0.6)
			(layers "F.Cu" "F.Mask" "F.Paste")
			(roundrect_rratio 0.085)
			(net "+5.0V")
			(solder_mask_margin 0)
			(solder_paste_margin 0)
		)
		(pad "8" smd roundrect
			(at 2.7 -1.905)
			(size 1.55 0.6)
			(layers "F.Cu" "F.Mask" "F.Paste")
			(roundrect_rratio 0.085)
			(net "P5V_SENSE")
			(solder_mask_margin 0)
			(solder_paste_margin 0)
		)
	)
	(footprint "Vault:RESC1005X40X25LL05T05"
		(layer "F.Cu")
		(at 84.65686 83.46371)
		(property "Reference" "R108"
			(at -2.87139 0.226921 0)
			(unlocked yes)
			(layer "F.SilkS")
			(effects
				(font
					(size 0.762 0.762)
					(thickness 0.2286)
				)
			)
		)
		(property "Value" "4.7K_0402"
			(at -2.389351 6.513005 270)
			(unlocked yes)
			(layer "F.SilkS")
			(hide yes)
			(effects
				(font
					(size 0.762 0.762)
					(thickness 0.2032)
				)
			)
		)
		(sheetname "02-USER_IO_STATUS")
		(sheetfile "02-USER_IO_STATUS.kicad_sch")
		(duplicate_pad_numbers_are_jumpers no)
		(pad "1" smd rect
			(at -0.39999 0 90)
			(size 0.45 0.45)
			(layers "F.Cu" "F.Mask" "F.Paste")
			(net "+3.3V")
		)
		(pad "2" smd rect
			(at 0.40001 0 90)
			(size 0.45 0.45)
			(layers "F.Cu" "F.Mask" "F.Paste")
			(net "NetR108_2")
		)
	)
	(footprint "Vault:RESC1005X40X25NL10T10"
		(layer "F.Cu")
		(at 174.1216 118.8162 -90)
		(property "Reference" "R118"
			(at 2.7032 -0.208719 270)
			(unlocked yes)
			(layer "F.SilkS")
			(effects
				(font
					(size 0.762 0.762)
					(thickness 0.2032)
				)
			)
		)
		(property "Value" "4.7K_1%_0402"
			(at -2.732271 8.747475 180)
			(unlocked yes)
			(layer "F.SilkS")
			(hide yes)
			(effects
				(font
					(size 0.762 0.762)
					(thickness 0.2032)
				)
			)
		)
		(sheetname "08-DIPSwitches_I2C")
		(sheetfile "08-DIPSwitches_I2C.kicad_sch")
		(duplicate_pad_numbers_are_jumpers no)
		(pad "1" smd rect
			(at -0.425 0)
			(size 0.6 0.65)
			(layers "F.Cu" "F.Mask" "F.Paste")
			(net "SENS_I2C_SCL")
		)
		(pad "2" smd rect
			(at 0.425 0)
			(size 0.6 0.65)
			(layers "F.Cu" "F.Mask" "F.Paste")
			(net "+3.3V")
		)
	)
	(footprint "GNSS:GNSS"
		(locked yes)
		(layer "F.Cu")
		(at 211.5592 136.4387 90)
		(property "Reference" "U15"
			(at 61.895579 -6.509 0)
			(unlocked yes)
			(layer "F.SilkS")
			(effects
				(font
					(size 0.762 0.762)
					(thickness 0.2286)
				)
			)
		)
		(property "Value" "RCB-F9T-1"
			(at -7.786871 -13.756155 0)
			(unlocked yes)
			(layer "F.SilkS")
			(hide yes)
			(effects
				(font
					(size 0.762 0.762)
					(thickness 0.2286)
				)
			)
		)
		(sheetname "05-GPS_IMU_SENSORS")
		(sheetfile "05-GPS_IMU_SENSORS.kicad_sch")
		(duplicate_pad_numbers_are_jumpers no)
		(fp_line
			(start 61.07 -20.47)
			(end 61.07 11.28)
			(stroke
				(width 0.254)
				(type solid)
			)
			(layer "F.SilkS")
		)
		(fp_line
			(start -6.11 -20.47)
			(end 61.07 -20.47)
			(stroke
				(width 0.254)
				(type solid)
			)
			(layer "F.SilkS")
		)
		(fp_line
			(start -6.11 -20.47)
			(end -6.11 11.28)
			(stroke
				(width 0.254)
				(type solid)
			)
			(layer "F.SilkS")
		)
		(fp_line
			(start -6.11 11.28)
			(end 61.07 11.28)
			(stroke
				(width 0.254)
				(type solid)
			)
			(layer "F.SilkS")
		)
		(pad "0" thru_hole circle
			(at 0 -2)
			(size 0 0)
			(drill 0.76)
			(layers "*.Cu" "*.Mask")
			(remove_unused_layers no)
			(thermal_bridge_angle 90)
		)
		(pad "0" thru_hole circle
			(at 0 2)
			(size 0 0)
			(drill 0.76)
			(layers "*.Cu" "*.Mask")
			(remove_unused_layers no)
			(thermal_bridge_angle 90)
		)
		(pad "1" smd rect
			(at -2.2225 3)
			(size 1.12 2.105)
			(layers "F.Cu" "F.Mask" "F.Paste")
			(net "GNSS2_P5V0")
		)
		(pad "2" smd rect
			(at 2.2225 3)
			(size 1.12 2.105)
			(layers "F.Cu" "F.Mask" "F.Paste")
			(net "GNSS2_P3V3")
		)
		(pad "3" smd rect
			(at -2.2225 1)
			(size 1.12 2.105)
			(layers "F.Cu" "F.Mask" "F.Paste")
			(net "RCB_GPS2_TX")
		)
		(pad "4" smd rect
			(at 2.2225 1)
			(size 1.12 2.105)
			(layers "F.Cu" "F.Mask" "F.Paste")
			(net "GPS2_RST")
		)
		(pad "5" smd rect
			(at -2.2225 -1)
			(size 1.12 2.105)
			(layers "F.Cu" "F.Mask" "F.Paste")
			(net "RCB_GPS2_RX")
		)
		(pad "6" smd rect
			(at 2.2225 -1)
			(size 1.12 2.105)
			(layers "F.Cu" "F.Mask" "F.Paste")
			(net "RCB_GPS2_TP1")
		)
		(pad "7" smd rect
			(at -2.2225 -3)
			(size 1.12 2.105)
			(layers "F.Cu" "F.Mask" "F.Paste")
			(net "RCB_GPS2_TP2")
		)
		(pad "8" smd rect
			(at 2.2225 -3)
			(size 1.12 2.105)
			(layers "F.Cu" "F.Mask" "F.Paste")
			(net "GND")
		)
	)
	(footprint "Vault:SOT143-4L"
		(layer "F.Cu")
		(at 71.8716 101.5662 90)
		(property "Reference" "D1"
			(at -0.572805 2.464089 270)
			(unlocked yes)
			(layer "F.SilkS")
			(effects
				(font
					(size 0.762 0.762)
					(thickness 0.2286)
				)
			)
		)
		(property "Value" "8240136"
			(at 2.6781 3.341871 90)
			(unlocked yes)
			(layer "F.SilkS")
			(hide yes)
			(effects
				(font
					(size 0.762 0.762)
					(thickness 0.2286)
				)
			)
		)
		(sheetname "01-USER_IO")
		(sheetfile "01-USER_IO.kicad_sch")
		(duplicate_pad_numbers_are_jumpers no)
		(fp_line
			(start 2.05 -1.7)
			(end 2.05 1.7)
			(stroke
				(width 0.2)
				(type solid)
			)
			(layer "F.SilkS")
		)
		(fp_line
			(start -2.05 -1.7)
			(end 2.05 -1.7)
			(stroke
				(width 0.2)
				(type solid)
			)
			(layer "F.SilkS")
		)
		(fp_line
			(start -2.05 -1.7)
			(end -2.05 1.675)
			(stroke
				(width 0.2)
				(type solid)
			)
			(layer "F.SilkS")
		)
		(fp_line
			(start -2.05 1.7)
			(end 2.05 1.7)
			(stroke
				(width 0.2)
				(type solid)
			)
			(layer "F.SilkS")
		)
		(fp_circle
			(center -2.404 -1.075)
			(end -2.15 -1.075)
			(stroke
				(width 0.2)
				(type solid)
			)
			(fill no)
			(layer "F.SilkS")
		)
		(pad "1" smd rect
			(at -1.1 -0.75 180)
			(size 1.4 1.4)
			(layers "F.Cu" "F.Mask" "F.Paste")
			(net "GND")
		)
		(pad "2" smd rect
			(at -1.1 0.95 180)
			(size 1 1.4)
			(layers "F.Cu" "F.Mask" "F.Paste")
			(net "NetAN2_1")
		)
		(pad "3" smd rect
			(at 1.1 0.95 180)
			(size 1 1.4)
			(layers "F.Cu" "F.Mask" "F.Paste")
			(net "NetAN1_1")
		)
		(pad "4" smd rect
			(at 1.1 -0.95 180)
			(size 1 1.4)
			(layers "F.Cu" "F.Mask" "F.Paste")
			(net "+3.3V")
		)
	)
	(footprint "Vault:FP-LTST-C191KGKT-MFG"
		(layer "F.Cu")
		(at 79.4216 53.8662)
		(property "Reference" "D10"
			(at -2.5714 0.389861 0)
			(unlocked yes)
			(layer "F.SilkS")
			(effects
				(font
					(size 0.762 0.762)
					(thickness 0.2286)
				)
			)
		)
		(property "Value" "LTST-C191KGKT"
			(at 1.2818 2.452871 0)
			(unlocked yes)
			(layer "F.SilkS")
			(hide yes)
			(effects
				(font
					(size 0.762 0.762)
					(thickness 0.2286)
				)
			)
		)
		(sheetname "02-USER_IO_STATUS")
		(sheetfile "02-USER_IO_STATUS.kicad_sch")
		(duplicate_pad_numbers_are_jumpers no)
		(fp_line
			(start -0.85 -0.775)
			(end 0.85 -0.775)
			(stroke
				(width 0.2)
				(type solid)
			)
			(layer "F.SilkS")
		)
		(fp_line
			(start -0.85 0.775)
			(end 0.85 0.775)
			(stroke
				(width 0.2)
				(type solid)
			)
			(layer "F.SilkS")
		)
		(fp_circle
			(center -1.7 0)
			(end -1.7 -0.125)
			(stroke
				(width 0.25)
				(type solid)
			)
			(fill no)
			(layer "F.SilkS")
		)
		(fp_line
			(start -1.25 -0.55)
			(end 1.25 -0.55)
			(stroke
				(width 0.2)
				(type solid)
			)
			(layer "F.CrtYd")
		)
		(fp_line
			(start -1.25 0.55)
			(end -1.25 -0.55)
			(stroke
				(width 0.2)
				(type solid)
			)
			(layer "F.CrtYd")
		)
		(fp_line
			(start -1.25 0.55)
			(end 1.25 0.55)
			(stroke
				(width 0.2)
				(type solid)
			)
			(layer "F.CrtYd")
		)
		(fp_line
			(start 1.25 0.55)
			(end 1.25 -0.55)
			(stroke
				(width 0.2)
				(type solid)
			)
			(layer "F.CrtYd")
		)
		(fp_line
			(start -1.25 -0.55)
			(end 1.25 -0.55)
			(stroke
				(width 0.2)
				(type solid)
			)
			(layer "F.Fab")
		)
		(fp_line
			(start -1.25 0.55)
			(end -1.25 -0.55)
			(stroke
				(width 0.2)
				(type solid)
			)
			(layer "F.Fab")
		)
		(fp_line
			(start -1.25 0.55)
			(end 1.25 0.55)
			(stroke
				(width 0.2)
				(type solid)
			)
			(layer "F.Fab")
		)
		(fp_line
			(start -0.5 0)
			(end 0.5 0)
			(stroke
				(width 0.1)
				(type solid)
			)
			(layer "F.Fab")
		)
		(fp_line
			(start 0 0.5)
			(end 0 -0.5)
			(stroke
				(width 0.1)
				(type solid)
			)
			(layer "F.Fab")
		)
		(fp_line
			(start 1.25 0.55)
			(end 1.25 -0.55)
			(stroke
				(width 0.2)
				(type solid)
			)
			(layer "F.Fab")
		)
		(fp_text user "${REFERENCE}"
			(at 0 0.28425 360)
			(unlocked yes)
			(layer "F.Fab")
			(effects
				(font
					(face "Arial")
					(size 0.63 0.63)
					(thickness 0.1)
				)
				(justify left bottom)
			)
		)
		(pad "1" smd rect
			(at -0.75 0)
			(size 0.8 0.8)
			(layers "F.Cu" "F.Mask" "F.Paste")
			(net "NetD10_1")
			(solder_mask_margin 0)
			(solder_paste_margin 0)
		)
		(pad "2" smd rect
			(at 0.75 0)
			(size 0.8 0.8)
			(layers "F.Cu" "F.Mask" "F.Paste")
			(net "+3.3V")
			(solder_mask_margin 0)
			(solder_paste_margin 0)
		)
	)
	(footprint "Vault:RESC1005X40X25NL10T10"
		(layer "F.Cu")
		(at 175.6216 114.3162)
		(property "Reference" "R116"
			(at 2.8032 0.026931 0)
			(unlocked yes)
			(layer "F.SilkS")
			(effects
				(font
					(size 0.762 0.762)
					(thickness 0.2032)
				)
			)
		)
		(property "Value" "4.7K_1%_0402"
			(at -2.732271 8.747465 270)
			(unlocked yes)
			(layer "F.SilkS")
			(hide yes)
			(effects
				(font
					(size 0.762 0.762)
					(thickness 0.2032)
				)
			)
		)
		(sheetname "08-DIPSwitches_I2C")
		(sheetfile "08-DIPSwitches_I2C.kicad_sch")
		(duplicate_pad_numbers_are_jumpers no)
		(pad "1" smd rect
			(at -0.425 0 90)
			(size 0.6 0.65)
			(layers "F.Cu" "F.Mask" "F.Paste")
			(net "ANADC_I2C_SCL")
		)
		(pad "2" smd rect
			(at 0.425 0 90)
			(size 0.6 0.65)
			(layers "F.Cu" "F.Mask" "F.Paste")
			(net "+3.3V")
		)
	)
	(footprint "Vault:RESC1005X40X25NL10T10"
		(layer "F.Cu")
		(at 166.9216 110.4162 180)
		(property "Reference" "R123"
			(at 2.2968 0.073079 0)
			(unlocked yes)
			(layer "F.SilkS")
			(effects
				(font
					(size 0.762 0.762)
					(thickness 0.2032)
				)
			)
		)
		(property "Value" "4.7K_1%_0402"
			(at -2.732271 8.747465 90)
			(unlocked yes)
			(layer "F.SilkS")
			(hide yes)
			(effects
				(font
					(size 0.762 0.762)
					(thickness 0.2032)
				)
			)
		)
		(sheetname "08-DIPSwitches_I2C")
		(sheetfile "08-DIPSwitches_I2C.kicad_sch")
		(duplicate_pad_numbers_are_jumpers no)
		(pad "1" smd rect
			(at -0.425 0 270)
			(size 0.6 0.65)
			(layers "F.Cu" "F.Mask" "F.Paste")
			(net "SDA")
		)
		(pad "2" smd rect
			(at 0.425 0 270)
			(size 0.6 0.65)
			(layers "F.Cu" "F.Mask" "F.Paste")
			(net "+3.3V")
		)
	)
	(footprint "Vault:RESC1005X40X25NL05T05"
		(layer "F.Cu")
		(at 111.1216 58.2162 -90)
		(property "Reference" "R164"
			(at 2.7032 -0.373069 270)
			(unlocked yes)
			(layer "F.SilkS")
			(effects
				(font
					(size 0.762 0.762)
					(thickness 0.2032)
				)
			)
		)
		(property "Value" "DNI_27_1%_0402"
			(at -2.732271 10.270975 180)
			(unlocked yes)
			(layer "F.SilkS")
			(hide yes)
			(effects
				(font
					(size 0.762 0.762)
					(thickness 0.2032)
				)
			)
		)
		(sheetname "11-M2_RCB_MUX")
		(sheetfile "11-M2_RCB_MUX.kicad_sch")
		(duplicate_pad_numbers_are_jumpers no)
		(pad "1" smd rect
			(at -0.45 0)
			(size 0.55 0.55)
			(layers "F.Cu" "F.Mask" "F.Paste")
			(net "M2_GPS1_TP1")
		)
		(pad "2" smd rect
			(at 0.45 0)
			(size 0.55 0.55)
			(layers "F.Cu" "F.Mask" "F.Paste")
			(net "GPS1_TP1")
		)
	)
	(footprint "Vault:RESC1005X40X25NL10T10"
		(layer "F.Cu")
		(at 71.8216 143.4162 90)
		(property "Reference" "R32"
			(at -0.1714 -1.173069 90)
			(unlocked yes)
			(layer "F.SilkS")
			(effects
				(font
					(size 0.762 0.762)
					(thickness 0.2286)
				)
			)
		)
		(property "Value" "4.7K_1%_0402"
			(at -3.087871 2.374035 0)
			(unlocked yes)
			(layer "F.SilkS")
			(hide yes)
			(effects
				(font
					(size 0.762 0.762)
					(thickness 0.2286)
				)
			)
		)
		(sheetname "01-USER_IO")
		(sheetfile "01-USER_IO.kicad_sch")
		(duplicate_pad_numbers_are_jumpers no)
		(pad "1" smd rect
			(at -0.425 0 180)
			(size 0.6 0.65)
			(layers "F.Cu" "F.Mask" "F.Paste")
			(net "+3.3V")
		)
		(pad "2" smd rect
			(at 0.425 0 180)
			(size 0.6 0.65)
			(layers "F.Cu" "F.Mask" "F.Paste")
			(net "ANT4_IO_IN")
		)
	)
	(footprint "Vault:CAPC1608X87X45ML20T05"
		(layer "F.Cu")
		(at 136.40433 85.04267 -90)
		(property "Reference" "C63"
			(at 0.17353 0.789385 90)
			(unlocked yes)
			(layer "F.SilkS")
			(effects
				(font
					(size 0.762 0.762)
					(thickness 0.2286)
				)
				(justify left bottom)
			)
		)
		(property "Value" "0.1uF"
			(at 1.829705 -4.27005 0)
			(unlocked yes)
			(layer "F.SilkS")
			(hide yes)
			(effects
				(font
					(size 0.762 0.762)
					(thickness 0.2286)
				)
				(justify left bottom)
			)
		)
		(sheetname "06-MAC")
		(sheetfile "06-MAC.kicad_sch")
		(duplicate_pad_numbers_are_jumpers no)
		(pad "1" smd rect
			(at -0.7 0)
			(size 1.1 1.05)
			(layers "F.Cu" "F.Mask" "F.Paste")
			(net "GND")
		)
		(pad "2" smd rect
			(at 0.7 0)
			(size 1.1 1.05)
			(layers "F.Cu" "F.Mask" "F.Paste")
			(net "MAC_VCC")
		)
	)
	(footprint "Vault:RESC1005X40X25LL05T05"
		(layer "F.Cu")
		(at 113.2216 70.1162 180)
		(property "Reference" "R138"
			(at -0.373069 -2.21891 270)
			(unlocked yes)
			(layer "F.SilkS")
			(effects
				(font
					(size 0.762 0.762)
					(thickness 0.2032)
				)
			)
		)
		(property "Value" "0_1%_0402"
			(at -2.579871 6.63996 90)
			(unlocked yes)
			(layer "F.SilkS")
			(hide yes)
			(effects
				(font
					(size 0.762 0.762)
					(thickness 0.2032)
				)
			)
		)
		(sheetname "10-M2_GPS")
		(sheetfile "10-M2_GPS.kicad_sch")
		(duplicate_pad_numbers_are_jumpers no)
		(pad "1" smd rect
			(at -0.4 0 270)
			(size 0.45 0.45)
			(layers "F.Cu" "F.Mask" "F.Paste")
			(net "NetJ44_46")
		)
		(pad "2" smd rect
			(at 0.4 0 270)
			(size 0.45 0.45)
			(layers "F.Cu" "F.Mask" "F.Paste")
			(net "M2_GPS1_TP1")
		)
	)
	(footprint "Vault:RESC1005X40X25LL05T10"
		(layer "F.Cu")
		(at 113.9216 52.2162 90)
		(property "Reference" "R147"
			(at 0.0032 7.626931 90)
			(unlocked yes)
			(layer "F.SilkS")
			(effects
				(font
					(size 0.762 0.762)
					(thickness 0.2032)
				)
			)
		)
		(property "Value" "49.9_1%_0402"
			(at -2.579871 8.798265 0)
			(unlocked yes)
			(layer "F.SilkS")
			(hide yes)
			(effects
				(font
					(size 0.762 0.762)
					(thickness 0.2032)
				)
			)
		)
		(sheetname "11-M2_RCB_MUX")
		(sheetfile "11-M2_RCB_MUX.kicad_sch")
		(duplicate_pad_numbers_are_jumpers no)
		(pad "1" smd rect
			(at -0.375 0 180)
			(size 0.45 0.5)
			(layers "F.Cu" "F.Mask" "F.Paste")
			(net "NetR147_1")
		)
		(pad "2" smd rect
			(at 0.375 0 180)
			(size 0.45 0.5)
			(layers "F.Cu" "F.Mask" "F.Paste")
			(net "GPS1_TP2")
		)
	)
	(footprint "Vault:FP-DO-214AB_SMC_J-Bend-MFG"
		(layer "F.Cu")
		(at 215.3216 71.5162 180)
		(property "Reference" "D23"
			(at 5.873079 -0.0714 90)
			(unlocked yes)
			(layer "F.SilkS")
			(effects
				(font
					(size 0.762 0.762)
					(thickness 0.2286)
				)
			)
		)
		(property "Value" "SMDJ12A"
			(at -6.847071 2.1193 90)
			(unlocked yes)
			(layer "F.SilkS")
			(hide yes)
			(effects
				(font
					(size 0.762 0.762)
					(thickness 0.2286)
				)
			)
		)
		(sheetname "03-POWER")
		(sheetfile "03-POWER.kicad_sch")
		(duplicate_pad_numbers_are_jumpers no)
		(fp_line
			(start 3.555 3.11)
			(end -3.555 3.11)
			(stroke
				(width 0.2)
				(type solid)
			)
			(layer "F.SilkS")
		)
		(fp_line
			(start 3.555 2.025)
			(end 3.555 3.11)
			(stroke
				(width 0.2)
				(type solid)
			)
			(layer "F.SilkS")
		)
		(fp_line
			(start 3.555 -3.11)
			(end 3.555 -2.025)
			(stroke
				(width 0.2)
				(type solid)
			)
			(layer "F.SilkS")
		)
		(fp_line
			(start 3.555 -3.11)
			(end -3.555 -3.11)
			(stroke
				(width 0.2)
				(type solid)
			)
			(layer "F.SilkS")
		)
		(fp_line
			(start -3.555 2.025)
			(end -3.555 3.11)
			(stroke
				(width 0.2)
				(type solid)
			)
			(layer "F.SilkS")
		)
		(fp_line
			(start -3.555 -3.11)
			(end -3.555 -2.025)
			(stroke
				(width 0.2)
				(type solid)
			)
			(layer "F.SilkS")
		)
		(fp_circle
			(center -5.05 0)
			(end -5.05 0.125)
			(stroke
				(width 0.25)
				(type solid)
			)
			(fill no)
			(layer "F.SilkS")
		)
		(fp_line
			(start 4.6 3.21)
			(end -4.6 3.21)
			(stroke
				(width 0.2)
				(type solid)
			)
			(layer "F.CrtYd")
		)
		(fp_line
			(start 4.6 -3.21)
			(end 4.6 3.21)
			(stroke
				(width 0.2)
				(type solid)
			)
			(layer "F.CrtYd")
		)
		(fp_line
			(start 4.6 -3.21)
			(end -4.6 -3.21)
			(stroke
				(width 0.2)
				(type solid)
			)
			(layer "F.CrtYd")
		)
		(fp_line
			(start -4.6 -3.21)
			(end -4.6 3.21)
			(stroke
				(width 0.2)
				(type solid)
			)
			(layer "F.CrtYd")
		)
		(fp_line
			(start 4.6 3.21)
			(end -4.6 3.21)
			(stroke
				(width 0.2)
				(type solid)
			)
			(layer "F.Fab")
		)
		(fp_line
			(start 4.6 -3.21)
			(end 4.6 3.21)
			(stroke
				(width 0.2)
				(type solid)
			)
			(layer "F.Fab")
		)
		(fp_line
			(start 4.6 -3.21)
			(end -4.6 -3.21)
			(stroke
				(width 0.2)
				(type solid)
			)
			(layer "F.Fab")
		)
		(fp_line
			(start 0.5 0)
			(end -0.5 0)
			(stroke
				(width 0.1)
				(type solid)
			)
			(layer "F.Fab")
		)
		(fp_line
			(start 0 -0.5)
			(end 0 0.5)
			(stroke
				(width 0.1)
				(type solid)
			)
			(layer "F.Fab")
		)
		(fp_line
			(start -4.6 -3.21)
			(end -4.6 3.21)
			(stroke
				(width 0.2)
				(type solid)
			)
			(layer "F.Fab")
		)
		(fp_text user "${REFERENCE}"
			(at -0.00001 0.09602 180)
			(unlocked yes)
			(layer "F.Fab")
			(effects
				(font
					(face "Arial")
					(size 0.63 0.63)
					(thickness 0.1)
				)
				(justify left bottom)
			)
		)
		(pad "1" smd rect
			(at -3.3 0 180)
			(size 2.4 3.3)
			(layers "F.Cu" "F.Mask" "F.Paste")
			(net "+12V_SENS")
			(solder_mask_margin 0)
			(solder_paste_margin 0)
		)
		(pad "2" smd rect
			(at 3.3 0 180)
			(size 2.4 3.3)
			(layers "F.Cu" "F.Mask" "F.Paste")
			(net "GND")
			(solder_mask_margin 0)
			(solder_paste_margin 0)
		)
	)
	(footprint "Vault:RESC1005X40X25NL05T05"
		(layer "F.Cu")
		(at 150.8216 128.6162)
		(property "Reference" "R91"
			(at -2.171395 -0.073069 0)
			(unlocked yes)
			(layer "F.SilkS")
			(effects
				(font
					(size 0.762 0.762)
					(thickness 0.2286)
				)
			)
		)
		(property "Value" "27_1%_0402"
			(at -2.732271 7.37632 270)
			(unlocked yes)
			(layer "F.SilkS")
			(hide yes)
			(effects
				(font
					(size 0.762 0.762)
					(thickness 0.2286)
				)
			)
		)
		(sheetname "09-USBUart_PPSMUX_UARTMUX")
		(sheetfile "09-USBUart_PPSMUX_UARTMUX.kicad_sch")
		(duplicate_pad_numbers_are_jumpers no)
		(pad "1" smd rect
			(at -0.45 0 90)
			(size 0.55 0.55)
			(layers "F.Cu" "F.Mask" "F.Paste")
			(net "GPS2_TX_FPGA")
		)
		(pad "2" smd rect
			(at 0.45 0 90)
			(size 0.55 0.55)
			(layers "F.Cu" "F.Mask" "F.Paste")
			(net "NetR91_2")
		)
	)
	(footprint "Vault:RESC1005X40X25NL05T05"
		(layer "F.Cu")
		(at 155.4216 127.3162 -90)
		(property "Reference" "R90"
			(at -2.0714 0.026931 270)
			(unlocked yes)
			(layer "F.SilkS")
			(effects
				(font
					(size 0.762 0.762)
					(thickness 0.2286)
				)
			)
		)
		(property "Value" "27_1%_0402"
			(at -2.732271 7.37632 180)
			(unlocked yes)
			(layer "F.SilkS")
			(hide yes)
			(effects
				(font
					(size 0.762 0.762)
					(thickness 0.2286)
				)
			)
		)
		(sheetname "09-USBUart_PPSMUX_UARTMUX")
		(sheetfile "09-USBUart_PPSMUX_UARTMUX.kicad_sch")
		(duplicate_pad_numbers_are_jumpers no)
		(pad "1" smd rect
			(at -0.45 0)
			(size 0.55 0.55)
			(layers "F.Cu" "F.Mask" "F.Paste")
			(net "FTDI_RX")
		)
		(pad "2" smd rect
			(at 0.45 0)
			(size 0.55 0.55)
			(layers "F.Cu" "F.Mask" "F.Paste")
			(net "NetR90_2")
		)
	)
	(footprint "Vault:RESC1005X40X25NL05T05"
		(layer "F.Cu")
		(at 153.3216 132.2162)
		(property "Reference" "R103"
			(at -0.0714 1.126931 0)
			(unlocked yes)
			(layer "F.SilkS")
			(effects
				(font
					(size 0.762 0.762)
					(thickness 0.2286)
				)
			)
		)
		(property "Value" "DNI_27_1%_0402"
			(at -2.732281 10.296375 270)
			(unlocked yes)
			(layer "F.SilkS")
			(hide yes)
			(effects
				(font
					(size 0.762 0.762)
					(thickness 0.2286)
				)
			)
		)
		(sheetname "09-USBUart_PPSMUX_UARTMUX")
		(sheetfile "09-USBUart_PPSMUX_UARTMUX.kicad_sch")
		(duplicate_pad_numbers_are_jumpers no)
		(pad "1" smd rect
			(at -0.45 0 90)
			(size 0.55 0.55)
			(layers "F.Cu" "F.Mask" "F.Paste")
			(net "GPS2_RX_FPGA")
		)
		(pad "2" smd rect
			(at 0.45 0 90)
			(size 0.55 0.55)
			(layers "F.Cu" "F.Mask" "F.Paste")
			(net "GPS2_RX")
		)
	)
	(footprint "Vault:FP-MYMGK-12-MFG"
		(layer "F.Cu")
		(at 179.5216 92.9162 -90)
		(property "Reference" "U18"
			(at -4.373079 0.3714 0)
			(unlocked yes)
			(layer "F.SilkS")
			(effects
				(font
					(size 0.762 0.762)
					(thickness 0.2286)
				)
			)
		)
		(property "Value" "DNI_MYMGK00506ERSR"
			(at 7.146775 5.234191 270)
			(unlocked yes)
			(layer "F.SilkS")
			(hide yes)
			(effects
				(font
					(size 0.762 0.762)
					(thickness 0.2286)
				)
			)
		)
		(sheetname "03-POWER")
		(sheetfile "03-POWER.kicad_sch")
		(duplicate_pad_numbers_are_jumpers no)
		(fp_line
			(start -3.825 4.575)
			(end -3.825 -4.575)
			(stroke
				(width 0.2)
				(type solid)
			)
			(layer "F.SilkS")
		)
		(fp_line
			(start -3.625 4.575)
			(end -3.825 4.575)
			(stroke
				(width 0.2)
				(type solid)
			)
			(layer "F.SilkS")
		)
		(fp_line
			(start 0.325 4.575)
			(end -0.325 4.575)
			(stroke
				(width 0.2)
				(type solid)
			)
			(layer "F.SilkS")
		)
		(fp_line
			(start 3.825 4.575)
			(end 3.625 4.575)
			(stroke
				(width 0.2)
				(type solid)
			)
			(layer "F.SilkS")
		)
		(fp_line
			(start 3.825 4.575)
			(end 3.825 -4.575)
			(stroke
				(width 0.2)
				(type solid)
			)
			(layer "F.SilkS")
		)
		(fp_line
			(start -3.625 -4.575)
			(end -3.825 -4.575)
			(stroke
				(width 0.2)
				(type solid)
			)
			(layer "F.SilkS")
		)
		(fp_line
			(start 0.325 -4.575)
			(end -0.325 -4.575)
			(stroke
				(width 0.2)
				(type solid)
			)
			(layer "F.SilkS")
		)
		(fp_line
			(start 3.825 -4.575)
			(end 3.625 -4.575)
			(stroke
				(width 0.2)
				(type solid)
			)
			(layer "F.SilkS")
		)
		(fp_circle
			(center -4.575 -3.625)
			(end -4.7 -3.625)
			(stroke
				(width 0.25)
				(type solid)
			)
			(fill no)
			(layer "F.SilkS")
		)
		(fp_line
			(start -4.325 5.075)
			(end -4.325 -5.075)
			(stroke
				(width 0.2)
				(type solid)
			)
			(layer "F.CrtYd")
		)
		(fp_line
			(start 4.325 5.075)
			(end -4.325 5.075)
			(stroke
				(width 0.2)
				(type solid)
			)
			(layer "F.CrtYd")
		)
		(fp_line
			(start 4.325 5.075)
			(end 4.325 -5.075)
			(stroke
				(width 0.2)
				(type solid)
			)
			(layer "F.CrtYd")
		)
		(fp_line
			(start 4.325 -5.075)
			(end -4.325 -5.075)
			(stroke
				(width 0.2)
				(type solid)
			)
			(layer "F.CrtYd")
		)
		(fp_line
			(start -4.325 5.075)
			(end -4.325 -5.075)
			(stroke
				(width 0.2)
				(type solid)
			)
			(layer "F.Fab")
		)
		(fp_line
			(start 4.325 5.075)
			(end -4.325 5.075)
			(stroke
				(width 0.2)
				(type solid)
			)
			(layer "F.Fab")
		)
		(fp_line
			(start 4.325 5.075)
			(end 4.325 -5.075)
			(stroke
				(width 0.2)
				(type solid)
			)
			(layer "F.Fab")
		)
		(fp_line
			(start 0 0.5)
			(end 0 -0.5)
			(stroke
				(width 0.1)
				(type solid)
			)
			(layer "F.Fab")
		)
		(fp_line
			(start 0.5 0)
			(end -0.5 0)
			(stroke
				(width 0.1)
				(type solid)
			)
			(layer "F.Fab")
		)
		(fp_line
			(start 4.325 -5.075)
			(end -4.325 -5.075)
			(stroke
				(width 0.2)
				(type solid)
			)
			(layer "F.Fab")
		)
		(fp_text user "${REFERENCE}"
			(at -0.00001 0.09602 270)
			(unlocked yes)
			(layer "F.Fab")
			(effects
				(font
					(face "Arial")
					(size 0.63 0.63)
					(thickness 0.1)
				)
				(justify left bottom)
			)
		)
		(pad "" smd custom
			(at -1.7 -0.75)
			(size 0.000001 0.000001)
			(layers "F.Cu" "F.Mask" "F.Paste")
			(solder_mask_margin 0)
			(solder_paste_margin 0)
			(thermal_bridge_angle 90)
			(options
				(clearance outline)
				(anchor circle)
			)
			(primitives
				(gr_poly
					(pts
						(xy 0 0) (xy 0 1) (xy 0.9 1) (xy 0.9 0.45) (xy 0.45 0)
					)
					(width 0)
					(fill yes)
				)
			)
		)
		(pad "1" smd rect
			(at -2.75 -3.55 270)
			(size 1 1.4)
			(layers "F.Cu" "F.Mask" "F.Paste")
			(net "+12V")
			(solder_mask_margin 0)
			(solder_paste_margin 0)
		)
		(pad "2" smd rect
			(at -1.2 -3.55 270)
			(size 1 1.4)
			(layers "F.Cu" "F.Mask" "F.Paste")
			(net "+12V")
			(solder_mask_margin 0)
			(solder_paste_margin 0)
		)
		(pad "3" smd rect
			(at -2.75 -1.2 270)
			(size 1 0.9)
			(layers "F.Cu" "F.Mask" "F.Paste")
			(net "GND")
			(solder_mask_margin 0)
			(solder_paste_margin 0)
		)
		(pad "4" smd rect
			(at -2.75 0 270)
			(size 1 0.9)
			(layers "F.Cu" "F.Mask" "F.Paste")
			(net "NetR61_2")
			(solder_mask_margin 0)
			(solder_paste_margin 0)
		)
		(pad "5" smd rect
			(at -2.75 1.2 270)
			(size 1 0.9)
			(layers "F.Cu" "F.Mask" "F.Paste")
			(net "P3V3_SENSE")
			(solder_mask_margin 0)
			(solder_paste_margin 0)
		)
		(pad "6" smd rect
			(at -2.75 3.55 270)
			(size 1 1.4)
			(layers "F.Cu" "F.Mask" "F.Paste")
			(net "P3V3_SENSE")
			(solder_mask_margin 0)
			(solder_paste_margin 0)
		)
		(pad "7" smd rect
			(at -1.2 3.55 270)
			(size 1 1.4)
			(layers "F.Cu" "F.Mask" "F.Paste")
			(net "P3V3_SENSE")
			(solder_mask_margin 0)
			(solder_paste_margin 0)
		)
		(pad "8" smd rect
			(at 1.2 3.55 270)
			(size 1 1.4)
			(layers "F.Cu" "F.Mask" "F.Paste")
			(net "GND")
			(solder_mask_margin 0)
			(solder_paste_margin 0)
		)
		(pad "9" smd rect
			(at 2.75 3.55 270)
			(size 1 1.4)
			(layers "F.Cu" "F.Mask" "F.Paste")
			(net "GND")
			(solder_mask_margin 0)
			(solder_paste_margin 0)
		)
		(pad "10" smd rect
			(at 2.75 1.2 270)
			(size 1 0.9)
			(layers "F.Cu" "F.Mask" "F.Paste")
			(net "GND")
			(solder_mask_margin 0)
			(solder_paste_margin 0)
		)
		(pad "11" smd rect
			(at 2.75 0 270)
			(size 1 0.9)
			(layers "F.Cu" "F.Mask" "F.Paste")
			(net "NetR183_2")
			(solder_mask_margin 0)
			(solder_paste_margin 0)
		)
		(pad "12" smd rect
			(at 2.75 -1.2 270)
			(size 1 0.9)
			(layers "F.Cu" "F.Mask" "F.Paste")
			(net "NetR129_2")
			(solder_mask_margin 0)
			(solder_paste_margin 0)
		)
		(pad "13" smd rect
			(at 2.75 -3.55 270)
			(size 1 1.4)
			(layers "F.Cu" "F.Mask" "F.Paste")
			(net "GND")
			(solder_mask_margin 0)
			(solder_paste_margin 0)
		)
		(pad "14" smd rect
			(at 1.2 -3.55 270)
			(size 1 1.4)
			(layers "F.Cu" "F.Mask" "F.Paste")
			(net "GND")
			(solder_mask_margin 0)
			(solder_paste_margin 0)
		)
		(pad "15" smd circle
			(at -1.15563 -1.16197 270)
			(size 0.74127 0.74127)
			(layers "F.Cu" "F.Mask" "F.Paste")
			(net "GND")
			(solder_mask_margin 0)
			(solder_paste_margin 0)
			(thermal_bridge_angle 90)
		)
		(pad "16" smd rect
			(at -1.2 0 270)
			(size 1 0.9)
			(layers "F.Cu" "F.Mask" "F.Paste")
			(net "GND")
			(solder_mask_margin 0)
			(solder_paste_margin 0)
		)
		(pad "17" smd rect
			(at -1.2 1.2 270)
			(size 1 0.9)
			(layers "F.Cu" "F.Mask" "F.Paste")
			(net "GND")
			(solder_mask_margin 0)
			(solder_paste_margin 0)
		)
		(pad "18" smd rect
			(at 0 -1.2 270)
			(size 1 0.9)
			(layers "F.Cu" "F.Mask" "F.Paste")
			(net "GND")
			(solder_mask_margin 0)
			(solder_paste_margin 0)
		)
		(pad "19" smd rect
			(at 0 0 270)
			(size 1 0.9)
			(layers "F.Cu" "F.Mask" "F.Paste")
			(net "GND")
			(solder_mask_margin 0)
			(solder_paste_margin 0)
		)
		(pad "20" smd rect
			(at 0 1.2 270)
			(size 1 0.9)
			(layers "F.Cu" "F.Mask" "F.Paste")
			(net "GND")
			(solder_mask_margin 0)
			(solder_paste_margin 0)
		)
		(pad "21" smd rect
			(at 1.2 -1.2 270)
			(size 1 0.9)
			(layers "F.Cu" "F.Mask" "F.Paste")
			(net "GND")
			(solder_mask_margin 0)
			(solder_paste_margin 0)
		)
		(pad "22" smd rect
			(at 1.2 0 270)
			(size 1 0.9)
			(layers "F.Cu" "F.Mask" "F.Paste")
			(net "GND")
			(solder_mask_margin 0)
			(solder_paste_margin 0)
		)
		(pad "23" smd rect
			(at 1.2 1.2 270)
			(size 1 0.9)
			(layers "F.Cu" "F.Mask" "F.Paste")
			(net "GND")
			(solder_mask_margin 0)
			(solder_paste_margin 0)
		)
	)
	(footprint "Vault:RESC1005X40X25LL05T10"
		(layer "F.Cu")
		(at 195.9216 120.0162 -90)
		(property "Reference" "R166"
			(at -2.6032 -0.226931 90)
			(unlocked yes)
			(layer "F.SilkS")
			(effects
				(font
					(size 0.762 0.762)
					(thickness 0.2032)
				)
			)
		)
		(property "Value" "DNI_49.9_1%_0402"
			(at -2.579871 11.71832 180)
			(unlocked yes)
			(layer "F.SilkS")
			(hide yes)
			(effects
				(font
					(size 0.762 0.762)
					(thickness 0.2032)
				)
			)
		)
		(sheetname "11-M2_RCB_MUX")
		(sheetfile "11-M2_RCB_MUX.kicad_sch")
		(duplicate_pad_numbers_are_jumpers no)
		(pad "1" smd rect
			(at -0.375 0)
			(size 0.45 0.5)
			(layers "F.Cu" "F.Mask" "F.Paste")
			(net "GPS2_PIN11")
		)
		(pad "2" smd rect
			(at 0.375 0)
			(size 0.45 0.5)
			(layers "F.Cu" "F.Mask" "F.Paste")
			(net "RCB_GPS2_PIN11")
		)
	)
	(footprint "Vault:FP-BME280-MFG"
		(layer "F.Cu")
		(at 105.60369 87.71708 -90)
		(property "Reference" "U14"
			(at 2.073069 0.92859 180)
			(unlocked yes)
			(layer "F.SilkS")
			(effects
				(font
					(size 0.762 0.762)
					(thickness 0.2286)
				)
			)
		)
		(property "Value" "BME280"
			(at 2.9069 3.443471 270)
			(unlocked yes)
			(layer "F.SilkS")
			(hide yes)
			(effects
				(font
					(size 0.762 0.762)
					(thickness 0.2286)
				)
			)
		)
		(sheetname "05-GPS_IMU_SENSORS")
		(sheetfile "05-GPS_IMU_SENSORS.kicad_sch")
		(duplicate_pad_numbers_are_jumpers no)
		(fp_line
			(start 1.3 1.55)
			(end -1.3 1.55)
			(stroke
				(width 0.2)
				(type solid)
			)
			(layer "F.SilkS")
		)
		(fp_line
			(start 1.3 -1.55)
			(end -1.3 -1.55)
			(stroke
				(width 0.2)
				(type solid)
			)
			(layer "F.SilkS")
		)
		(fp_circle
			(center 1.85 -0.975)
			(end 1.725 -0.975)
			(stroke
				(width 0.25)
				(type solid)
			)
			(fill no)
			(layer "F.SilkS")
		)
		(fp_line
			(start -1.8 1.8)
			(end -1.8 -1.8)
			(stroke
				(width 0.2)
				(type solid)
			)
			(layer "F.CrtYd")
		)
		(fp_line
			(start 1.8 1.8)
			(end -1.8 1.8)
			(stroke
				(width 0.2)
				(type solid)
			)
			(layer "F.CrtYd")
		)
		(fp_line
			(start 1.8 1.8)
			(end 1.8 -1.8)
			(stroke
				(width 0.2)
				(type solid)
			)
			(layer "F.CrtYd")
		)
		(fp_line
			(start 1.8 -1.8)
			(end -1.8 -1.8)
			(stroke
				(width 0.2)
				(type solid)
			)
			(layer "F.CrtYd")
		)
		(fp_line
			(start -1.8 1.8)
			(end -1.8 -1.8)
			(stroke
				(width 0.2)
				(type solid)
			)
			(layer "F.Fab")
		)
		(fp_line
			(start 1.8 1.8)
			(end -1.8 1.8)
			(stroke
				(width 0.2)
				(type solid)
			)
			(layer "F.Fab")
		)
		(fp_line
			(start 1.8 1.8)
			(end 1.8 -1.8)
			(stroke
				(width 0.2)
				(type solid)
			)
			(layer "F.Fab")
		)
		(fp_line
			(start 0 0.5)
			(end 0 -0.5)
			(stroke
				(width 0.1)
				(type solid)
			)
			(layer "F.Fab")
		)
		(fp_line
			(start 0.5 0)
			(end -0.5 0)
			(stroke
				(width 0.1)
				(type solid)
			)
			(layer "F.Fab")
		)
		(fp_line
			(start 1.8 -1.8)
			(end -1.8 -1.8)
			(stroke
				(width 0.2)
				(type solid)
			)
			(layer "F.Fab")
		)
		(fp_text user "${REFERENCE}"
			(at 0 0.28425 270)
			(unlocked yes)
			(layer "F.Fab")
			(effects
				(font
					(face "Arial")
					(size 0.63 0.63)
					(thickness 0.1)
				)
				(justify left bottom)
			)
		)
		(pad "1" smd rect
			(at 1.025 -0.975 270)
			(size 0.5 0.35)
			(layers "F.Cu" "F.Mask" "F.Paste")
			(net "GND")
			(solder_mask_margin 0)
			(solder_paste_margin 0)
		)
		(pad "2" smd rect
			(at 1.025 -0.325 270)
			(size 0.5 0.35)
			(layers "F.Cu" "F.Mask" "F.Paste")
			(net "+3.3V")
			(solder_mask_margin 0)
			(solder_paste_margin 0)
		)
		(pad "3" smd rect
			(at 1.025 0.325 270)
			(size 0.5 0.35)
			(layers "F.Cu" "F.Mask" "F.Paste")
			(net "SENS_I2C_SDA")
			(solder_mask_margin 0)
			(solder_paste_margin 0)
		)
		(pad "4" smd rect
			(at 1.025 0.975 270)
			(size 0.5 0.35)
			(layers "F.Cu" "F.Mask" "F.Paste")
			(net "SENS_I2C_SCL")
			(solder_mask_margin 0)
			(solder_paste_margin 0)
		)
		(pad "5" smd rect
			(at -1.025 0.975 270)
			(size 0.5 0.35)
			(layers "F.Cu" "F.Mask" "F.Paste")
			(net "GND")
			(solder_mask_margin 0)
			(solder_paste_margin 0)
		)
		(pad "6" smd rect
			(at -1.025 0.325 270)
			(size 0.5 0.35)
			(layers "F.Cu" "F.Mask" "F.Paste")
			(net "+3.3V")
			(solder_mask_margin 0)
			(solder_paste_margin 0)
		)
		(pad "7" smd rect
			(at -1.025 -0.325 270)
			(size 0.5 0.35)
			(layers "F.Cu" "F.Mask" "F.Paste")
			(net "GND")
			(solder_mask_margin 0)
			(solder_paste_margin 0)
		)
		(pad "8" smd rect
			(at -1.025 -0.975 270)
			(size 0.5 0.35)
			(layers "F.Cu" "F.Mask" "F.Paste")
			(net "+3.3V")
			(solder_mask_margin 0)
			(solder_paste_margin 0)
		)
	)
	(footprint "Vault:RESC1005X40X25LL05T10"
		(layer "F.Cu")
		(at 122.9216 78.4162)
		(property "Reference" "R177"
			(at 2.4032 0.126921 0)
			(unlocked yes)
			(layer "F.SilkS")
			(effects
				(font
					(size 0.762 0.762)
					(thickness 0.2032)
				)
			)
		)
		(property "Value" "49.9_1%_0402"
			(at -2.579871 8.798265 270)
			(unlocked yes)
			(layer "F.SilkS")
			(hide yes)
			(effects
				(font
					(size 0.762 0.762)
					(thickness 0.2032)
				)
			)
		)
		(sheetname "11-M2_RCB_MUX")
		(sheetfile "11-M2_RCB_MUX.kicad_sch")
		(duplicate_pad_numbers_are_jumpers no)
		(pad "1" smd rect
			(at -0.375 0 90)
			(size 0.45 0.5)
			(layers "F.Cu" "F.Mask" "F.Paste")
			(net "NetR177_1")
		)
		(pad "2" smd rect
			(at 0.375 0 90)
			(size 0.45 0.5)
			(layers "F.Cu" "F.Mask" "F.Paste")
			(net "GPS1_PIN12")
		)
	)
	(footprint "Vault:FP-TAJE-MFG"
		(layer "F.Cu")
		(at 98.4216 67.8162 90)
		(property "Reference" "C71"
			(at 4.673079 -2.045995 0)
			(unlocked yes)
			(layer "F.SilkS")
			(effects
				(font
					(size 0.762 0.762)
					(thickness 0.254)
				)
			)
		)
		(property "Value" "470uF_10V_2917"
			(at -5.818351 8.162815 0)
			(unlocked yes)
			(layer "F.SilkS")
			(hide yes)
			(effects
				(font
					(size 0.762 0.762)
					(thickness 0.2032)
				)
			)
		)
		(sheetname "03-POWER")
		(sheetfile "03-POWER.kicad_sch")
		(duplicate_pad_numbers_are_jumpers no)
		(fp_line
			(start 3.75 -2.25)
			(end 3.75 -1.875)
			(stroke
				(width 0.2)
				(type solid)
			)
			(layer "F.SilkS")
		)
		(fp_line
			(start -3.75 -2.25)
			(end 3.75 -2.25)
			(stroke
				(width 0.2)
				(type solid)
			)
			(layer "F.SilkS")
		)
		(fp_line
			(start -3.75 -2.25)
			(end -3.75 -1.875)
			(stroke
				(width 0.2)
				(type solid)
			)
			(layer "F.SilkS")
		)
		(fp_line
			(start 4.675 -0.3)
			(end 4.675 0.3)
			(stroke
				(width 0.2)
				(type solid)
			)
			(layer "F.SilkS")
		)
		(fp_line
			(start 4.375 0)
			(end 4.975 0)
			(stroke
				(width 0.2)
				(type solid)
			)
			(layer "F.SilkS")
		)
		(fp_line
			(start 3.75 1.875)
			(end 3.75 2.25)
			(stroke
				(width 0.2)
				(type solid)
			)
			(layer "F.SilkS")
		)
		(fp_line
			(start -3.75 1.875)
			(end -3.75 2.25)
			(stroke
				(width 0.2)
				(type solid)
			)
			(layer "F.SilkS")
		)
		(fp_line
			(start -3.75 2.25)
			(end 3.75 2.25)
			(stroke
				(width 0.2)
				(type solid)
			)
			(layer "F.SilkS")
		)
		(fp_line
			(start 4.1 -2.35)
			(end 4.1 2.35)
			(stroke
				(width 0.2)
				(type solid)
			)
			(layer "F.CrtYd")
		)
		(fp_line
			(start -4.1 -2.35)
			(end 4.1 -2.35)
			(stroke
				(width 0.2)
				(type solid)
			)
			(layer "F.CrtYd")
		)
		(fp_line
			(start -4.1 -2.35)
			(end -4.1 2.35)
			(stroke
				(width 0.2)
				(type solid)
			)
			(layer "F.CrtYd")
		)
		(fp_line
			(start -4.1 2.35)
			(end 4.1 2.35)
			(stroke
				(width 0.2)
				(type solid)
			)
			(layer "F.CrtYd")
		)
		(fp_line
			(start 4.1 -2.35)
			(end 4.1 2.35)
			(stroke
				(width 0.2)
				(type solid)
			)
			(layer "F.Fab")
		)
		(fp_line
			(start -4.1 -2.35)
			(end 4.1 -2.35)
			(stroke
				(width 0.2)
				(type solid)
			)
			(layer "F.Fab")
		)
		(fp_line
			(start -4.1 -2.35)
			(end -4.1 2.35)
			(stroke
				(width 0.2)
				(type solid)
			)
			(layer "F.Fab")
		)
		(fp_line
			(start 0 -0.5)
			(end 0 0.5)
			(stroke
				(width 0.1)
				(type solid)
			)
			(layer "F.Fab")
		)
		(fp_line
			(start -0.5 0)
			(end 0.5 0)
			(stroke
				(width 0.1)
				(type solid)
			)
			(layer "F.Fab")
		)
		(fp_line
			(start -4.1 2.35)
			(end 4.1 2.35)
			(stroke
				(width 0.2)
				(type solid)
			)
			(layer "F.Fab")
		)
		(fp_text user "${REFERENCE}"
			(at 0 0.28425 90)
			(unlocked yes)
			(layer "F.Fab")
			(effects
				(font
					(face "Arial")
					(size 0.63 0.63)
					(thickness 0.1)
				)
				(justify left bottom)
			)
		)
		(pad "1" smd rect
			(at -3 0 90)
			(size 2 3)
			(layers "F.Cu" "F.Mask" "F.Paste")
			(net "GND")
			(solder_mask_margin 0)
			(solder_paste_margin 0)
		)
		(pad "2" smd rect
			(at 3 0 90)
			(size 2 3)
			(layers "F.Cu" "F.Mask" "F.Paste")
			(net "+5.0V")
			(solder_mask_margin 0)
			(solder_paste_margin 0)
		)
	)
	(footprint "Vault:FP-TAJE-MFG"
		(layer "F.Cu")
		(at 160.1216 94.2162)
		(property "Reference" "C4"
			(at 1.50937 3.402815 0)
			(unlocked yes)
			(layer "F.SilkS")
			(effects
				(font
					(size 0.762 0.762)
					(thickness 0.2286)
				)
				(justify left bottom)
			)
		)
		(property "Value" "470uF_10V_2917"
			(at 11.7497 7.622845 0)
			(unlocked yes)
			(layer "F.SilkS")
			(hide yes)
			(effects
				(font
					(size 0.762 0.762)
					(thickness 0.2286)
				)
				(justify left bottom)
			)
		)
		(sheetname "03-POWER")
		(sheetfile "03-POWER.kicad_sch")
		(duplicate_pad_numbers_are_jumpers no)
		(fp_line
			(start -3.75 -2.25)
			(end 3.75 -2.25)
			(stroke
				(width 0.2)
				(type solid)
			)
			(layer "F.SilkS")
		)
		(fp_line
			(start -3.75 -1.875)
			(end -3.75 -2.25)
			(stroke
				(width 0.2)
				(type solid)
			)
			(layer "F.SilkS")
		)
		(fp_line
			(start -3.75 2.25)
			(end -3.75 1.875)
			(stroke
				(width 0.2)
				(type solid)
			)
			(layer "F.SilkS")
		)
		(fp_line
			(start -3.75 2.25)
			(end 3.75 2.25)
			(stroke
				(width 0.2)
				(type solid)
			)
			(layer "F.SilkS")
		)
		(fp_line
			(start 3.75 -1.875)
			(end 3.75 -2.25)
			(stroke
				(width 0.2)
				(type solid)
			)
			(layer "F.SilkS")
		)
		(fp_line
			(start 3.75 2.25)
			(end 3.75 1.875)
			(stroke
				(width 0.2)
				(type solid)
			)
			(layer "F.SilkS")
		)
		(fp_line
			(start 4.375 0)
			(end 4.975 0)
			(stroke
				(width 0.2)
				(type solid)
			)
			(layer "F.SilkS")
		)
		(fp_line
			(start 4.675 0.3)
			(end 4.675 -0.3)
			(stroke
				(width 0.2)
				(type solid)
			)
			(layer "F.SilkS")
		)
		(fp_line
			(start -4.1 -2.35)
			(end 4.1 -2.35)
			(stroke
				(width 0.2)
				(type solid)
			)
			(layer "F.CrtYd")
		)
		(fp_line
			(start -4.1 2.35)
			(end -4.1 -2.35)
			(stroke
				(width 0.2)
				(type solid)
			)
			(layer "F.CrtYd")
		)
		(fp_line
			(start -4.1 2.35)
			(end 4.1 2.35)
			(stroke
				(width 0.2)
				(type solid)
			)
			(layer "F.CrtYd")
		)
		(fp_line
			(start 4.1 2.35)
			(end 4.1 -2.35)
			(stroke
				(width 0.2)
				(type solid)
			)
			(layer "F.CrtYd")
		)
		(fp_line
			(start -4.1 -2.35)
			(end 4.1 -2.35)
			(stroke
				(width 0.2)
				(type solid)
			)
			(layer "F.Fab")
		)
		(fp_line
			(start -4.1 2.35)
			(end -4.1 -2.35)
			(stroke
				(width 0.2)
				(type solid)
			)
			(layer "F.Fab")
		)
		(fp_line
			(start -4.1 2.35)
			(end 4.1 2.35)
			(stroke
				(width 0.2)
				(type solid)
			)
			(layer "F.Fab")
		)
		(fp_line
			(start -0.5 0)
			(end 0.5 0)
			(stroke
				(width 0.1)
				(type solid)
			)
			(layer "F.Fab")
		)
		(fp_line
			(start 0 0.5)
			(end 0 -0.5)
			(stroke
				(width 0.1)
				(type solid)
			)
			(layer "F.Fab")
		)
		(fp_line
			(start 4.1 2.35)
			(end 4.1 -2.35)
			(stroke
				(width 0.2)
				(type solid)
			)
			(layer "F.Fab")
		)
		(fp_text user "${REFERENCE}"
			(at 0 0.28425 360)
			(unlocked yes)
			(layer "F.Fab")
			(effects
				(font
					(face "Arial")
					(size 0.63 0.63)
					(thickness 0.1)
				)
				(justify left bottom)
			)
		)
		(pad "1" smd rect
			(at -3 0)
			(size 2 3)
			(layers "F.Cu" "F.Mask" "F.Paste")
			(net "GND")
			(solder_mask_margin 0)
			(solder_paste_margin 0)
		)
		(pad "2" smd rect
			(at 3 0)
			(size 2 3)
			(layers "F.Cu" "F.Mask" "F.Paste")
			(net "+3.3V")
			(solder_mask_margin 0)
			(solder_paste_margin 0)
		)
	)
	(footprint "Vault:RESC1005X40X25LL05T10"
		(layer "F.Cu")
		(at 117.7216 80.8162)
		(property "Reference" "R172"
			(at -0.7968 -1.173079 0)
			(unlocked yes)
			(layer "F.SilkS")
			(effects
				(font
					(size 0.762 0.762)
					(thickness 0.2032)
				)
			)
		)
		(property "Value" "DNI_49.9_1%_0402"
			(at -2.579871 11.71832 270)
			(unlocked yes)
			(layer "F.SilkS")
			(hide yes)
			(effects
				(font
					(size 0.762 0.762)
					(thickness 0.2032)
				)
			)
		)
		(sheetname "11-M2_RCB_MUX")
		(sheetfile "11-M2_RCB_MUX.kicad_sch")
		(duplicate_pad_numbers_are_jumpers no)
		(pad "1" smd rect
			(at -0.375 0 90)
			(size 0.45 0.5)
			(layers "F.Cu" "F.Mask" "F.Paste")
			(net "GPS1_PIN11")
		)
		(pad "2" smd rect
			(at 0.375 0 90)
			(size 0.45 0.5)
			(layers "F.Cu" "F.Mask" "F.Paste")
			(net "M2_GPS1_PIN11")
		)
	)
	(footprint "Vault:RESC1005X40X25NL05T05"
		(layer "F.Cu")
		(at 152.6216 115.1162)
		(property "Reference" "R94"
			(at -2.0714 -0.073079 0)
			(unlocked yes)
			(layer "F.SilkS")
			(effects
				(font
					(size 0.762 0.762)
					(thickness 0.2286)
				)
			)
		)
		(property "Value" "27_1%_0402"
			(at -2.935481 7.78247 270)
			(unlocked yes)
			(layer "F.SilkS")
			(hide yes)
			(effects
				(font
					(size 0.762 0.762)
					(thickness 0.2286)
				)
			)
		)
		(sheetname "08-DIPSwitches_I2C")
		(sheetfile "08-DIPSwitches_I2C.kicad_sch")
		(duplicate_pad_numbers_are_jumpers no)
		(pad "1" smd rect
			(at -0.45 0 90)
			(size 0.55 0.55)
			(layers "F.Cu" "F.Mask" "F.Paste")
			(net "FPGA_MAC_UART_TX")
		)
		(pad "2" smd rect
			(at 0.45 0 90)
			(size 0.55 0.55)
			(layers "F.Cu" "F.Mask" "F.Paste")
			(net "NetR94_2")
		)
	)
	(footprint "Vault:M08A_N"
		(layer "F.Cu")
		(at 130.7216 86.3162 90)
		(property "Reference" "U3"
			(at 2.428605 -2.873079 90)
			(unlocked yes)
			(layer "F.SilkS")
			(effects
				(font
					(size 0.762 0.762)
					(thickness 0.2286)
				)
			)
		)
		(property "Value" "DS90LV027AQMA"
			(at 6.35958 4.332471 90)
			(unlocked yes)
			(layer "F.SilkS")
			(hide yes)
			(effects
				(font
					(size 0.762 0.762)
					(thickness 0.2286)
				)
			)
		)
		(sheetname "06-MAC")
		(sheetfile "06-MAC.kicad_sch")
		(duplicate_pad_numbers_are_jumpers no)
		(fp_line
			(start 0.9 -2.5)
			(end 0.9 2.5)
			(stroke
				(width 0.2)
				(type solid)
			)
			(layer "F.SilkS")
		)
		(fp_line
			(start -0.9 -2.5)
			(end 0.9 -2.5)
			(stroke
				(width 0.2)
				(type solid)
			)
			(layer "F.SilkS")
		)
		(fp_line
			(start -0.9 -2.5)
			(end -0.9 2.5)
			(stroke
				(width 0.2)
				(type solid)
			)
			(layer "F.SilkS")
		)
		(fp_line
			(start -0.9 2.5)
			(end 0.9 2.5)
			(stroke
				(width 0.2)
				(type solid)
			)
			(layer "F.SilkS")
		)
		(fp_circle
			(center -2.4 -2.755)
			(end -2.275 -2.755)
			(stroke
				(width 0.25)
				(type solid)
			)
			(fill no)
			(layer "F.SilkS")
		)
		(fp_circle
			(center -0.1 -1.7)
			(end 0.1 -1.7)
			(stroke
				(width 0.4)
				(type solid)
			)
			(fill no)
			(layer "F.SilkS")
		)
		(pad "1" smd oval
			(at -2.4 -1.905 180)
			(size 0.6 2.2)
			(layers "F.Cu" "F.Mask" "F.Paste")
			(net "+3.3V")
		)
		(pad "2" smd oval
			(at -2.4 -0.635 180)
			(size 0.6 2.2)
			(layers "F.Cu" "F.Mask" "F.Paste")
			(net "FPGA_MAC_PPS_IN1-")
		)
		(pad "3" smd oval
			(at -2.4 0.635 180)
			(size 0.6 2.2)
			(layers "F.Cu" "F.Mask" "F.Paste")
			(net "FPGA_MAC_PPS_DIFF_IN0")
		)
		(pad "4" smd oval
			(at -2.4 1.905 180)
			(size 0.6 2.2)
			(layers "F.Cu" "F.Mask" "F.Paste")
			(net "GND")
		)
		(pad "5" smd oval
			(at 2.4 1.905 180)
			(size 0.6 2.2)
			(layers "F.Cu" "F.Mask" "F.Paste")
			(net "MAC_PPS_IN0-")
		)
		(pad "6" smd oval
			(at 2.4 0.635 180)
			(size 0.6 2.2)
			(layers "F.Cu" "F.Mask" "F.Paste")
			(net "MAC_PPS_IN0+")
		)
		(pad "7" smd oval
			(at 2.4 -0.635 180)
			(size 0.6 2.2)
			(layers "F.Cu" "F.Mask" "F.Paste")
			(net "MAC_PPS_IN1+")
		)
		(pad "8" smd oval
			(at 2.4 -1.905 180)
			(size 0.6 2.2)
			(layers "F.Cu" "F.Mask" "F.Paste")
			(net "MAC_PPS_IN1-")
		)
	)
	(footprint "Vault:FP-RC0603-0_55-MFG"
		(layer "F.Cu")
		(at 87.75686 82.56371)
		(property "Reference" "R40"
			(at -0.2286 1.473069 180)
			(unlocked yes)
			(layer "F.SilkS")
			(effects
				(font
					(size 0.762 0.762)
					(thickness 0.2286)
				)
			)
		)
		(property "Value" "DNI_100k"
			(at -2.998991 2.37408 270)
			(unlocked yes)
			(layer "F.SilkS")
			(hide yes)
			(effects
				(font
					(size 0.762 0.762)
					(thickness 0.2286)
				)
			)
		)
		(sheetname "02-USER_IO_STATUS")
		(sheetfile "02-USER_IO_STATUS.kicad_sch")
		(duplicate_pad_numbers_are_jumpers no)
		(fp_line
			(start -0.025 -0.45)
			(end 0.02501 -0.45)
			(stroke
				(width 0.2)
				(type solid)
			)
			(layer "F.SilkS")
		)
		(fp_line
			(start -0.025 0.45)
			(end 0.02501 0.45)
			(stroke
				(width 0.2)
				(type solid)
			)
			(layer "F.SilkS")
		)
		(fp_line
			(start -1.4 -0.55)
			(end 1.4 -0.55)
			(stroke
				(width 0.2)
				(type solid)
			)
			(layer "F.CrtYd")
		)
		(fp_line
			(start -1.4 0.55)
			(end -1.4 -0.55)
			(stroke
				(width 0.2)
				(type solid)
			)
			(layer "F.CrtYd")
		)
		(fp_line
			(start -1.4 0.55)
			(end 1.4 0.55)
			(stroke
				(width 0.2)
				(type solid)
			)
			(layer "F.CrtYd")
		)
		(fp_line
			(start 1.4 0.55)
			(end 1.4 -0.55)
			(stroke
				(width 0.2)
				(type solid)
			)
			(layer "F.CrtYd")
		)
		(fp_line
			(start -1.4 -0.55)
			(end 1.4 -0.55)
			(stroke
				(width 0.2)
				(type solid)
			)
			(layer "F.Fab")
		)
		(fp_line
			(start -1.4 0.55)
			(end -1.4 -0.55)
			(stroke
				(width 0.2)
				(type solid)
			)
			(layer "F.Fab")
		)
		(fp_line
			(start -1.4 0.55)
			(end 1.4 0.55)
			(stroke
				(width 0.2)
				(type solid)
			)
			(layer "F.Fab")
		)
		(fp_line
			(start -0.5 0)
			(end 0.5 0)
			(stroke
				(width 0.1)
				(type solid)
			)
			(layer "F.Fab")
		)
		(fp_line
			(start 0 0.5)
			(end 0 -0.5)
			(stroke
				(width 0.1)
				(type solid)
			)
			(layer "F.Fab")
		)
		(fp_line
			(start 1.4 0.55)
			(end 1.4 -0.55)
			(stroke
				(width 0.2)
				(type solid)
			)
			(layer "F.Fab")
		)
		(pad "1" smd rect
			(at -0.85 0)
			(size 0.9 0.8)
			(layers "F.Cu" "F.Mask" "F.Paste")
			(net "GND")
			(solder_mask_margin 0)
			(solder_paste_margin 0)
		)
		(pad "2" smd rect
			(at 0.85 0)
			(size 0.9 0.8)
			(layers "F.Cu" "F.Mask" "F.Paste")
			(net "NetR40_2")
			(solder_mask_margin 0)
			(solder_paste_margin 0)
		)
	)
	(footprint "Vault:RESC1005X40X25LL05T10"
		(layer "F.Cu")
		(at 112.4216 58.0162 -90)
		(property "Reference" "R150"
			(at 2.7032 0.026931 270)
			(unlocked yes)
			(layer "F.SilkS")
			(effects
				(font
					(size 0.762 0.762)
					(thickness 0.2032)
				)
			)
		)
		(property "Value" "49.9_1%_0402"
			(at -2.579871 8.798275 180)
			(unlocked yes)
			(layer "F.SilkS")
			(hide yes)
			(effects
				(font
					(size 0.762 0.762)
					(thickness 0.2032)
				)
			)
		)
		(sheetname "11-M2_RCB_MUX")
		(sheetfile "11-M2_RCB_MUX.kicad_sch")
		(duplicate_pad_numbers_are_jumpers no)
		(pad "1" smd rect
			(at -0.375 0)
			(size 0.45 0.5)
			(layers "F.Cu" "F.Mask" "F.Paste")
			(net "NetR150_1")
		)
		(pad "2" smd rect
			(at 0.375 0)
			(size 0.45 0.5)
			(layers "F.Cu" "F.Mask" "F.Paste")
			(net "GPS1_TP1")
		)
	)
	(footprint "Vault:FP-T521X476M035ATE030-MFG"
		(layer "F.Cu")
		(at 96.8216 52.0162 180)
		(property "Reference" "C72"
			(at 4.673069 -1.6968 90)
			(unlocked yes)
			(layer "F.SilkS")
			(effects
				(font
					(size 0.762 0.762)
					(thickness 0.2032)
				)
			)
		)
		(property "Value" "47uF_35V_2917"
			(at -5.843751 7.45182 90)
			(unlocked yes)
			(layer "F.SilkS")
			(hide yes)
			(effects
				(font
					(size 0.762 0.762)
					(thickness 0.2032)
				)
			)
		)
		(sheetname "03-POWER")
		(sheetfile "03-POWER.kicad_sch")
		(duplicate_pad_numbers_are_jumpers no)
		(fp_line
			(start 5 1.52399)
			(end 4.4 1.52399)
			(stroke
				(width 0.2)
				(type solid)
			)
			(layer "F.SilkS")
		)
		(fp_line
			(start 4.7 1.22399)
			(end 4.7 1.82399)
			(stroke
				(width 0.2)
				(type solid)
			)
			(layer "F.SilkS")
		)
		(fp_line
			(start 3.8 2.3)
			(end -3.8 2.3)
			(stroke
				(width 0.2)
				(type solid)
			)
			(layer "F.SilkS")
		)
		(fp_line
			(start 3.8 1.54)
			(end 3.8 2.3)
			(stroke
				(width 0.2)
				(type solid)
			)
			(layer "F.SilkS")
		)
		(fp_line
			(start 3.8 -2.3)
			(end 3.8 -1.54)
			(stroke
				(width 0.2)
				(type solid)
			)
			(layer "F.SilkS")
		)
		(fp_line
			(start 3.8 -2.3)
			(end -3.8 -2.3)
			(stroke
				(width 0.2)
				(type solid)
			)
			(layer "F.SilkS")
		)
		(fp_line
			(start -3.8 1.54)
			(end -3.8 2.3)
			(stroke
				(width 0.2)
				(type solid)
			)
			(layer "F.SilkS")
		)
		(fp_line
			(start -3.8 -2.3)
			(end -3.8 -1.54)
			(stroke
				(width 0.2)
				(type solid)
			)
			(layer "F.SilkS")
		)
		(fp_line
			(start 4.13 2.42)
			(end -4.13 2.42)
			(stroke
				(width 0.2)
				(type solid)
			)
			(layer "F.CrtYd")
		)
		(fp_line
			(start 4.13 -2.42)
			(end 4.13 2.42)
			(stroke
				(width 0.2)
				(type solid)
			)
			(layer "F.CrtYd")
		)
		(fp_line
			(start 4.13 -2.42)
			(end -4.13 -2.42)
			(stroke
				(width 0.2)
				(type solid)
			)
			(layer "F.CrtYd")
		)
		(fp_line
			(start -4.13 -2.42)
			(end -4.13 2.42)
			(stroke
				(width 0.2)
				(type solid)
			)
			(layer "F.CrtYd")
		)
		(fp_line
			(start 4.13 2.42)
			(end -4.13 2.42)
			(stroke
				(width 0.2)
				(type solid)
			)
			(layer "F.Fab")
		)
		(fp_line
			(start 4.13 -2.42)
			(end 4.13 2.42)
			(stroke
				(width 0.2)
				(type solid)
			)
			(layer "F.Fab")
		)
		(fp_line
			(start 4.13 -2.42)
			(end -4.13 -2.42)
			(stroke
				(width 0.2)
				(type solid)
			)
			(layer "F.Fab")
		)
		(fp_line
			(start 0.5 0)
			(end -0.5 0)
			(stroke
				(width 0.1)
				(type solid)
			)
			(layer "F.Fab")
		)
		(fp_line
			(start 0 -0.5)
			(end 0 0.5)
			(stroke
				(width 0.1)
				(type solid)
			)
			(layer "F.Fab")
		)
		(fp_line
			(start -4.13 -2.42)
			(end -4.13 2.42)
			(stroke
				(width 0.2)
				(type solid)
			)
			(layer "F.Fab")
		)
		(fp_text user "${REFERENCE}"
			(at 0 0.28425 180)
			(unlocked yes)
			(layer "F.Fab")
			(effects
				(font
					(face "Arial")
					(size 0.63 0.63)
					(thickness 0.1)
				)
				(justify left bottom)
			)
		)
		(pad "1" smd rect
			(at -3.01 0 180)
			(size 1.99 2.33)
			(layers "F.Cu" "F.Mask" "F.Paste")
			(net "GND")
			(solder_mask_margin 0)
			(solder_paste_margin 0)
		)
		(pad "2" smd rect
			(at 3.01 0 180)
			(size 1.99 2.33)
			(layers "F.Cu" "F.Mask" "F.Paste")
			(net "+12V")
			(solder_mask_margin 0)
			(solder_paste_margin 0)
		)
	)
	(footprint "Vault:FP-C3216-160-0_2-MFG"
		(layer "F.Cu")
		(at 92.72394 70.79377 180)
		(property "Reference" "C13"
			(at 1.10234 1.284225 0)
			(unlocked yes)
			(layer "F.SilkS")
			(effects
				(font
					(size 0.762 0.762)
					(thickness 0.2286)
				)
				(justify left bottom)
			)
		)
		(property "Value" "47uF_16V_1206"
			(at -0.3062 -14.963945 0)
			(unlocked yes)
			(layer "F.SilkS")
			(hide yes)
			(effects
				(font
					(size 0.762 0.762)
					(thickness 0.2286)
				)
				(justify left bottom)
			)
		)
		(sheetname "03-POWER")
		(sheetfile "03-POWER.kicad_sch")
		(duplicate_pad_numbers_are_jumpers no)
		(fp_line
			(start 0.725 0.9)
			(end -0.725 0.9)
			(stroke
				(width 0.2)
				(type solid)
			)
			(layer "F.SilkS")
		)
		(fp_line
			(start 0.725 -0.9)
			(end -0.725 -0.9)
			(stroke
				(width 0.2)
				(type solid)
			)
			(layer "F.SilkS")
		)
		(fp_line
			(start 2.3 1)
			(end -2.3 1)
			(stroke
				(width 0.2)
				(type solid)
			)
			(layer "F.CrtYd")
		)
		(fp_line
			(start 2.3 -1)
			(end 2.3 1)
			(stroke
				(width 0.2)
				(type solid)
			)
			(layer "F.CrtYd")
		)
		(fp_line
			(start 2.3 -1)
			(end -2.3 -1)
			(stroke
				(width 0.2)
				(type solid)
			)
			(layer "F.CrtYd")
		)
		(fp_line
			(start -2.3 -1)
			(end -2.3 1)
			(stroke
				(width 0.2)
				(type solid)
			)
			(layer "F.CrtYd")
		)
		(fp_line
			(start 2.3 1)
			(end -2.3 1)
			(stroke
				(width 0.2)
				(type solid)
			)
			(layer "F.Fab")
		)
		(fp_line
			(start 2.3 -1)
			(end 2.3 1)
			(stroke
				(width 0.2)
				(type solid)
			)
			(layer "F.Fab")
		)
		(fp_line
			(start 2.3 -1)
			(end -2.3 -1)
			(stroke
				(width 0.2)
				(type solid)
			)
			(layer "F.Fab")
		)
		(fp_line
			(start 0.5 0)
			(end -0.5 0)
			(stroke
				(width 0.1)
				(type solid)
			)
			(layer "F.Fab")
		)
		(fp_line
			(start 0 -0.5)
			(end 0 0.5)
			(stroke
				(width 0.1)
				(type solid)
			)
			(layer "F.Fab")
		)
		(fp_line
			(start -2.3 -1)
			(end -2.3 1)
			(stroke
				(width 0.2)
				(type solid)
			)
			(layer "F.Fab")
		)
		(fp_text user "${REFERENCE}"
			(at -0.00001 0.09602 180)
			(unlocked yes)
			(layer "F.Fab")
			(effects
				(font
					(face "Arial")
					(size 0.63 0.63)
					(thickness 0.1)
				)
				(justify left bottom)
			)
		)
		(pad "1" smd rect
			(at -1.65 0 180)
			(size 1.1 1.35)
			(layers "F.Cu" "F.Mask" "F.Paste")
			(net "+5.0V")
			(solder_mask_margin 0)
			(solder_paste_margin 0)
		)
		(pad "2" smd rect
			(at 1.65 0 180)
			(size 1.1 1.35)
			(layers "F.Cu" "F.Mask" "F.Paste")
			(net "GND")
			(solder_mask_margin 0)
			(solder_paste_margin 0)
		)
	)
	(footprint "Vault:CAPC1608X87X45ML20T05"
		(layer "F.Cu")
		(at 88.35686 86.56371 90)
		(property "Reference" "C40"
			(at 0.4786 -3.473069 90)
			(unlocked yes)
			(layer "F.SilkS")
			(effects
				(font
					(size 0.762 0.762)
					(thickness 0.2286)
				)
			)
		)
		(property "Value" "0.1uF"
			(at 2.069035 2.630671 90)
			(unlocked yes)
			(layer "F.SilkS")
			(hide yes)
			(effects
				(font
					(size 0.762 0.762)
					(thickness 0.2286)
				)
			)
		)
		(sheetname "02-USER_IO_STATUS")
		(sheetfile "02-USER_IO_STATUS.kicad_sch")
		(duplicate_pad_numbers_are_jumpers no)
		(pad "1" smd rect
			(at -0.7 0 180)
			(size 1.1 1.05)
			(layers "F.Cu" "F.Mask" "F.Paste")
			(net "GND")
		)
		(pad "2" smd rect
			(at 0.7 0 180)
			(size 1.1 1.05)
			(layers "F.Cu" "F.Mask" "F.Paste")
			(net "+3.3V")
		)
	)
	(footprint "Vault:FP-0603-L_1_6_0_2-W_0_8_0-MFG"
		(layer "F.Cu")
		(at 109.8216 80.91748 -90)
		(property "Reference" "C8"
			(at -2.4 0.493345 270)
			(unlocked yes)
			(layer "F.SilkS")
			(effects
				(font
					(size 0.762 0.762)
					(thickness 0.2286)
				)
				(justify left bottom)
			)
		)
		(property "Value" "10uF_16V_0603"
			(at 31.257845 -2.1089 0)
			(unlocked yes)
			(layer "F.SilkS")
			(hide yes)
			(effects
				(font
					(size 0.762 0.762)
					(thickness 0.2286)
				)
				(justify left bottom)
			)
		)
		(sheetname "05-GPS_IMU_SENSORS")
		(sheetfile "05-GPS_IMU_SENSORS.kicad_sch")
		(duplicate_pad_numbers_are_jumpers no)
		(fp_line
			(start 0.9 0.825)
			(end -0.9 0.825)
			(stroke
				(width 0.2)
				(type solid)
			)
			(layer "F.SilkS")
		)
		(fp_line
			(start 0.9 -0.825)
			(end -0.9 -0.825)
			(stroke
				(width 0.2)
				(type solid)
			)
			(layer "F.SilkS")
		)
		(fp_line
			(start -1.15 0.6)
			(end -1.15 -0.6)
			(stroke
				(width 0.2)
				(type solid)
			)
			(layer "F.CrtYd")
		)
		(fp_line
			(start 1.15 0.6)
			(end -1.15 0.6)
			(stroke
				(width 0.2)
				(type solid)
			)
			(layer "F.CrtYd")
		)
		(fp_line
			(start 1.15 0.6)
			(end 1.15 -0.6)
			(stroke
				(width 0.2)
				(type solid)
			)
			(layer "F.CrtYd")
		)
		(fp_line
			(start 1.15 -0.6)
			(end -1.15 -0.6)
			(stroke
				(width 0.2)
				(type solid)
			)
			(layer "F.CrtYd")
		)
		(fp_line
			(start -1.15 0.6)
			(end -1.15 -0.6)
			(stroke
				(width 0.2)
				(type solid)
			)
			(layer "F.Fab")
		)
		(fp_line
			(start 1.15 0.6)
			(end -1.15 0.6)
			(stroke
				(width 0.2)
				(type solid)
			)
			(layer "F.Fab")
		)
		(fp_line
			(start 1.15 0.6)
			(end 1.15 -0.6)
			(stroke
				(width 0.2)
				(type solid)
			)
			(layer "F.Fab")
		)
		(fp_line
			(start 0 0.5)
			(end 0 -0.5)
			(stroke
				(width 0.1)
				(type solid)
			)
			(layer "F.Fab")
		)
		(fp_line
			(start 0.5 0)
			(end -0.5 0)
			(stroke
				(width 0.1)
				(type solid)
			)
			(layer "F.Fab")
		)
		(fp_line
			(start 1.15 -0.6)
			(end -1.15 -0.6)
			(stroke
				(width 0.2)
				(type solid)
			)
			(layer "F.Fab")
		)
		(fp_text user "${REFERENCE}"
			(at -0.00001 0.09602 270)
			(unlocked yes)
			(layer "F.Fab")
			(effects
				(font
					(face "Arial")
					(size 0.63 0.63)
					(thickness 0.1)
				)
				(justify left bottom)
			)
		)
		(pad "1" smd rect
			(at -0.7 0 270)
			(size 0.7 0.7)
			(layers "F.Cu" "F.Mask" "F.Paste")
			(net "BNO_P3V3")
			(solder_mask_margin 0)
			(solder_paste_margin 0)
		)
		(pad "2" smd rect
			(at 0.7 0 270)
			(size 0.7 0.7)
			(layers "F.Cu" "F.Mask" "F.Paste")
			(net "GND")
			(solder_mask_margin 0)
			(solder_paste_margin 0)
		)
	)
	(footprint "Vault:FP-LTST-C191KGKT-MFG"
		(layer "F.Cu")
		(at 223.9216 93.2162)
		(property "Reference" "D19"
			(at -2.8968 0.126921 0)
			(unlocked yes)
			(layer "F.SilkS")
			(effects
				(font
					(size 0.762 0.762)
					(thickness 0.2032)
				)
			)
		)
		(property "Value" "LTST-C191KGKT"
			(at -3.494271 8.97586 270)
			(unlocked yes)
			(layer "F.SilkS")
			(hide yes)
			(effects
				(font
					(size 0.762 0.762)
					(thickness 0.2032)
				)
			)
		)
		(sheetname "08-DIPSwitches_I2C")
		(sheetfile "08-DIPSwitches_I2C.kicad_sch")
		(duplicate_pad_numbers_are_jumpers no)
		(fp_line
			(start -0.85 -0.775)
			(end 0.85 -0.775)
			(stroke
				(width 0.2)
				(type solid)
			)
			(layer "F.SilkS")
		)
		(fp_line
			(start -0.85 0.775)
			(end 0.85 0.775)
			(stroke
				(width 0.2)
				(type solid)
			)
			(layer "F.SilkS")
		)
		(fp_circle
			(center -1.7 0)
			(end -1.7 -0.125)
			(stroke
				(width 0.25)
				(type solid)
			)
			(fill no)
			(layer "F.SilkS")
		)
		(fp_line
			(start -1.25 -0.55)
			(end 1.25 -0.55)
			(stroke
				(width 0.2)
				(type solid)
			)
			(layer "F.CrtYd")
		)
		(fp_line
			(start -1.25 0.55)
			(end -1.25 -0.55)
			(stroke
				(width 0.2)
				(type solid)
			)
			(layer "F.CrtYd")
		)
		(fp_line
			(start -1.25 0.55)
			(end 1.25 0.55)
			(stroke
				(width 0.2)
				(type solid)
			)
			(layer "F.CrtYd")
		)
		(fp_line
			(start 1.25 0.55)
			(end 1.25 -0.55)
			(stroke
				(width 0.2)
				(type solid)
			)
			(layer "F.CrtYd")
		)
		(fp_line
			(start -1.25 -0.55)
			(end 1.25 -0.55)
			(stroke
				(width 0.2)
				(type solid)
			)
			(layer "F.Fab")
		)
		(fp_line
			(start -1.25 0.55)
			(end -1.25 -0.55)
			(stroke
				(width 0.2)
				(type solid)
			)
			(layer "F.Fab")
		)
		(fp_line
			(start -1.25 0.55)
			(end 1.25 0.55)
			(stroke
				(width 0.2)
				(type solid)
			)
			(layer "F.Fab")
		)
		(fp_line
			(start -0.5 0)
			(end 0.5 0)
			(stroke
				(width 0.1)
				(type solid)
			)
			(layer "F.Fab")
		)
		(fp_line
			(start 0 0.5)
			(end 0 -0.5)
			(stroke
				(width 0.1)
				(type solid)
			)
			(layer "F.Fab")
		)
		(fp_line
			(start 1.25 0.55)
			(end 1.25 -0.55)
			(stroke
				(width 0.2)
				(type solid)
			)
			(layer "F.Fab")
		)
		(fp_text user "${REFERENCE}"
			(at 0 0.28425 360)
			(unlocked yes)
			(layer "F.Fab")
			(effects
				(font
					(face "Arial")
					(size 0.63 0.63)
					(thickness 0.1)
				)
				(justify left bottom)
			)
		)
		(pad "1" smd rect
			(at -0.75 0)
			(size 0.8 0.8)
			(layers "F.Cu" "F.Mask" "F.Paste")
			(net "NetD19_1")
			(solder_mask_margin 0)
			(solder_paste_margin 0)
		)
		(pad "2" smd rect
			(at 0.75 0)
			(size 0.8 0.8)
			(layers "F.Cu" "F.Mask" "F.Paste")
			(net "+3.3V")
			(solder_mask_margin 0)
			(solder_paste_margin 0)
		)
	)
	(footprint "SA53:SolderSocket"
		(locked yes)
		(layer "F.Cu")
		(at 113.3256 140.0162 90)
		(property "Reference" "SKT10"
			(at -3.426921 -0.575395 0)
			(unlocked yes)
			(layer "F.SilkS")
			(effects
				(font
					(size 0.762 0.762)
					(thickness 0.2286)
				)
			)
		)
		(property "Value" "0332-0-43-80-18-27-10-0"
			(at -2.910071 16.1362 0)
			(unlocked yes)
			(layer "F.SilkS")
			(hide yes)
			(effects
				(font
					(size 0.762 0.762)
					(thickness 0.2286)
				)
			)
		)
		(sheetname "06-MAC")
		(sheetfile "06-MAC.kicad_sch")
		(duplicate_pad_numbers_are_jumpers no)
		(pad "1" thru_hole circle
			(at 0 0 90)
			(size 2.54 2.54)
			(drill 2.0066)
			(layers "*.Cu" "*.Mask")
			(remove_unused_layers no)
			(net "MAC_PPS_OUT")
			(thermal_bridge_angle 90)
		)
	)
	(footprint "SA53:SolderSocket"
		(locked yes)
		(layer "F.Cu")
		(at 125.4216 140.0162 90)
		(property "Reference" "SKT4"
			(at -3.426921 3.0286 0)
			(unlocked yes)
			(layer "F.SilkS")
			(effects
				(font
					(size 0.762 0.762)
					(thickness 0.2286)
				)
			)
		)
		(property "Value" "0332-0-43-80-18-27-10-0"
			(at -2.910071 16.1362 0)
			(unlocked yes)
			(layer "F.SilkS")
			(hide yes)
			(effects
				(font
					(size 0.762 0.762)
					(thickness 0.2286)
				)
			)
		)
		(sheetname "06-MAC")
		(sheetfile "06-MAC.kicad_sch")
		(duplicate_pad_numbers_are_jumpers no)
		(pad "1" thru_hole circle
			(at 0 0 90)
			(size 2.54 2.54)
			(drill 2.0066)
			(layers "*.Cu" "*.Mask")
			(remove_unused_layers no)
			(net "MAC_BITE")
			(thermal_bridge_angle 90)
		)
	)
	(footprint "Vault:FP-RUT0012A-MFG"
		(layer "F.Cu")
		(at 194.1216 122.6162)
		(property "Reference" "U30"
			(at -2.160579 -2.3157 90)
			(unlocked yes)
			(layer "F.SilkS")
			(effects
				(font
					(size 0.762 0.762)
					(thickness 0.2032)
				)
			)
		)
		(property "Value" "TMUX1072RUTR"
			(at 7.401265 3.164071 0)
			(unlocked yes)
			(layer "F.SilkS")
			(hide yes)
			(effects
				(font
					(size 0.762 0.762)
					(thickness 0.2032)
				)
			)
		)
		(sheetname "11-M2_RCB_MUX")
		(sheetfile "11-M2_RCB_MUX.kicad_sch")
		(duplicate_pad_numbers_are_jumpers no)
		(fp_line
			(start -0.9 -1.525)
			(end 0.9 -1.525)
			(stroke
				(width 0.2)
				(type solid)
			)
			(layer "F.SilkS")
		)
		(fp_line
			(start -0.9 1.525)
			(end 0.9 1.525)
			(stroke
				(width 0.2)
				(type solid)
			)
			(layer "F.SilkS")
		)
		(fp_circle
			(center -1.575 -0.8)
			(end -1.575 -0.925)
			(stroke
				(width 0.25)
				(type solid)
			)
			(fill no)
			(layer "F.SilkS")
		)
		(fp_rect
			(start -0.85 -0.3)
			(end -0.35 -0.5)
			(stroke
				(width 0)
				(type default)
			)
			(fill yes)
			(layer "F.Paste")
		)
		(fp_rect
			(start -0.85 0.1)
			(end -0.35 -0.1)
			(stroke
				(width 0)
				(type default)
			)
			(fill yes)
			(layer "F.Paste")
		)
		(fp_rect
			(start -0.85 0.5)
			(end -0.35 0.3)
			(stroke
				(width 0)
				(type default)
			)
			(fill yes)
			(layer "F.Paste")
		)
		(fp_rect
			(start -0.85 0.9)
			(end -0.35 0.7)
			(stroke
				(width 0)
				(type default)
			)
			(fill yes)
			(layer "F.Paste")
		)
		(fp_rect
			(start -0.1 -0.5)
			(end 0.1 -1)
			(stroke
				(width 0)
				(type default)
			)
			(fill yes)
			(layer "F.Paste")
		)
		(fp_rect
			(start -0.1 1)
			(end 0.1 0.5)
			(stroke
				(width 0)
				(type default)
			)
			(fill yes)
			(layer "F.Paste")
		)
		(fp_rect
			(start 0.35 -0.7)
			(end 0.85 -0.9)
			(stroke
				(width 0)
				(type default)
			)
			(fill yes)
			(layer "F.Paste")
		)
		(fp_rect
			(start 0.35 -0.3)
			(end 0.85 -0.5)
			(stroke
				(width 0)
				(type default)
			)
			(fill yes)
			(layer "F.Paste")
		)
		(fp_rect
			(start 0.35 0.1)
			(end 0.85 -0.1)
			(stroke
				(width 0)
				(type default)
			)
			(fill yes)
			(layer "F.Paste")
		)
		(fp_rect
			(start 0.35 0.5)
			(end 0.85 0.3)
			(stroke
				(width 0)
				(type default)
			)
			(fill yes)
			(layer "F.Paste")
		)
		(fp_rect
			(start 0.35 0.9)
			(end 0.85 0.7)
			(stroke
				(width 0)
				(type default)
			)
			(fill yes)
			(layer "F.Paste")
		)
		(fp_poly
			(pts
				(xy -0.5 -1) (xy -0.35 -1) (xy -0.35 -0.7) (xy -0.85 -0.7) (xy -0.85 -0.9) (xy -0.5 -0.9)
			)
			(stroke
				(width 0)
				(type default)
			)
			(fill yes)
			(layer "F.Paste")
		)
		(fp_line
			(start -1.05 -1.2)
			(end 1.05 -1.2)
			(stroke
				(width 0.2)
				(type solid)
			)
			(layer "F.CrtYd")
		)
		(fp_line
			(start -1.05 1.2)
			(end -1.05 -1.2)
			(stroke
				(width 0.2)
				(type solid)
			)
			(layer "F.CrtYd")
		)
		(fp_line
			(start -1.05 1.2)
			(end 1.05 1.2)
			(stroke
				(width 0.2)
				(type solid)
			)
			(layer "F.CrtYd")
		)
		(fp_line
			(start 1.05 1.2)
			(end 1.05 -1.2)
			(stroke
				(width 0.2)
				(type solid)
			)
			(layer "F.CrtYd")
		)
		(fp_line
			(start -1.05 -1.2)
			(end 1.05 -1.2)
			(stroke
				(width 0.2)
				(type solid)
			)
			(layer "F.Fab")
		)
		(fp_line
			(start -1.05 1.2)
			(end -1.05 -1.2)
			(stroke
				(width 0.2)
				(type solid)
			)
			(layer "F.Fab")
		)
		(fp_line
			(start -1.05 1.2)
			(end 1.05 1.2)
			(stroke
				(width 0.2)
				(type solid)
			)
			(layer "F.Fab")
		)
		(fp_line
			(start -0.5 0)
			(end 0.5 0)
			(stroke
				(width 0.1)
				(type solid)
			)
			(layer "F.Fab")
		)
		(fp_line
			(start 0 0.5)
			(end 0 -0.5)
			(stroke
				(width 0.1)
				(type solid)
			)
			(layer "F.Fab")
		)
		(fp_line
			(start 1.05 1.2)
			(end 1.05 -1.2)
			(stroke
				(width 0.2)
				(type solid)
			)
			(layer "F.Fab")
		)
		(fp_text user "${REFERENCE}"
			(at -0.00001 0.09602 0)
			(unlocked yes)
			(layer "F.Fab")
			(effects
				(font
					(face "Arial")
					(size 0.63 0.63)
					(thickness 0.1)
				)
				(justify left bottom)
			)
		)
		(pad "" smd custom
			(at -0.5 -1.1)
			(size 0.000001 0.000001)
			(layers "F.Cu" "F.Mask")
			(solder_mask_margin 0)
			(thermal_bridge_angle 90)
			(options
				(clearance outline)
				(anchor circle)
			)
			(primitives
				(gr_poly
					(pts
						(xy 0 0) (xy 0.15 0) (xy 0.15 0.4) (xy -0.45 0.4) (xy -0.45 0.2) (xy 0 0.2)
					)
					(width 0)
					(fill yes)
				)
			)
		)
		(pad "1" smd circle
			(at -0.45 -0.8)
			(size 0.18 0.18)
			(layers "F.Cu" "F.Mask" "F.Paste")
			(net "DIP_SW_GPS2_SEL")
			(solder_mask_margin 0)
			(solder_paste_margin -1000)
			(thermal_bridge_angle 90)
		)
		(pad "2" smd rect
			(at -0.65 -0.4)
			(size 0.6 0.2)
			(layers "F.Cu" "F.Mask" "F.Paste")
			(net "M2_GPS2_PIN11")
			(solder_mask_margin 0)
			(solder_paste_margin -1000)
		)
		(pad "3" smd rect
			(at -0.65 0)
			(size 0.6 0.2)
			(layers "F.Cu" "F.Mask" "F.Paste")
			(net "GND")
			(solder_mask_margin 0)
			(solder_paste_margin -1000)
		)
		(pad "4" smd rect
			(at -0.65 0.4)
			(size 0.6 0.2)
			(layers "F.Cu" "F.Mask" "F.Paste")
			(net "M2_GPS2_PIN12")
			(solder_mask_margin 0)
			(solder_paste_margin -1000)
		)
		(pad "5" smd rect
			(at -0.65 0.8)
			(size 0.6 0.2)
			(layers "F.Cu" "F.Mask" "F.Paste")
			(net "DIP_SW_GPS2_SEL")
			(solder_mask_margin 0)
			(solder_paste_margin -1000)
		)
		(pad "6" smd rect
			(at 0 0.8)
			(size 0.2 0.6)
			(layers "F.Cu" "F.Mask" "F.Paste")
			(net "GND")
			(solder_mask_margin 0)
			(solder_paste_margin -1000)
		)
		(pad "7" smd rect
			(at 0.65 0.8)
			(size 0.6 0.2)
			(layers "F.Cu" "F.Mask" "F.Paste")
			(net "NetR175_1")
			(solder_mask_margin 0)
			(solder_paste_margin -1000)
		)
		(pad "8" smd rect
			(at 0.65 0.4)
			(size 0.6 0.2)
			(layers "F.Cu" "F.Mask" "F.Paste")
			(net "RCB_GPS2_PIN12")
			(solder_mask_margin 0)
			(solder_paste_margin -1000)
		)
		(pad "9" smd rect
			(at 0.65 0)
			(size 0.6 0.2)
			(layers "F.Cu" "F.Mask" "F.Paste")
			(net "+3.3V")
			(solder_mask_margin 0)
			(solder_paste_margin -1000)
		)
		(pad "10" smd rect
			(at 0.65 -0.4)
			(size 0.6 0.2)
			(layers "F.Cu" "F.Mask" "F.Paste")
			(net "RCB_GPS2_PIN11")
			(solder_mask_margin 0)
			(solder_paste_margin -1000)
		)
		(pad "11" smd rect
			(at 0.65 -0.8)
			(size 0.6 0.2)
			(layers "F.Cu" "F.Mask" "F.Paste")
			(net "NetR171_1")
			(solder_mask_margin 0)
			(solder_paste_margin -1000)
		)
		(pad "12" smd rect
			(at 0 -0.8)
			(size 0.2 0.6)
			(layers "F.Cu" "F.Mask" "F.Paste")
			(net "GND")
			(solder_mask_margin 0)
			(solder_paste_margin -1000)
		)
	)
	(footprint "Passives:FUSM1608X60N"
		(layer "F.Cu")
		(at 222.1216 64.8162 -90)
		(property "Reference" "F1"
			(at 0.6 0.706655 90)
			(unlocked yes)
			(layer "F.SilkS")
			(effects
				(font
					(size 0.762 0.762)
					(thickness 0.2286)
				)
				(justify left bottom)
			)
		)
		(property "Value" "FUSE_0603_5.00A"
			(at 4.987045 2.1929 0)
			(unlocked yes)
			(layer "F.SilkS")
			(hide yes)
			(effects
				(font
					(size 0.762 0.762)
					(thickness 0.2286)
				)
				(justify left bottom)
			)
		)
		(sheetname "03-POWER")
		(sheetfile "03-POWER.kicad_sch")
		(duplicate_pad_numbers_are_jumpers no)
		(fp_line
			(start 0 0.5)
			(end 0 -0.5)
			(stroke
				(width 0.1524)
				(type solid)
			)
			(layer "F.SilkS")
		)
		(pad "1" smd rect
			(at -0.69 0)
			(size 1 0.72)
			(layers "F.Cu" "F.Mask" "F.Paste")
			(net "NetCR1_2")
		)
		(pad "2" smd rect
			(at 0.69 0)
			(size 1 0.72)
			(layers "F.Cu" "F.Mask" "F.Paste")
			(net "+12V_SENS")
		)
	)
	(footprint "Vault:FP-5TS1-IPC_C"
		(layer "F.Cu")
		(at 180.90984 105.1162 -90)
		(property "Reference" "U7"
			(at -2.735479 -0.228605 0)
			(unlocked yes)
			(layer "F.SilkS")
			(effects
				(font
					(size 0.762 0.762)
					(thickness 0.2286)
				)
			)
		)
		(property "Value" "AT24MAC402-STUM-T"
			(at 10.727395 3.189471 270)
			(unlocked yes)
			(layer "F.SilkS")
			(hide yes)
			(effects
				(font
					(size 0.762 0.762)
					(thickness 0.2286)
				)
			)
		)
		(sheetname "05-GPS_IMU_SENSORS")
		(sheetfile "05-GPS_IMU_SENSORS.kicad_sch")
		(duplicate_pad_numbers_are_jumpers no)
		(fp_line
			(start 0.17207 1.44999)
			(end -0.17207 1.44999)
			(stroke
				(width 0.2)
				(type solid)
			)
			(layer "F.SilkS")
		)
		(fp_line
			(start 0.8 0.30893)
			(end 0.8 -0.30894)
			(stroke
				(width 0.2)
				(type solid)
			)
			(layer "F.SilkS")
		)
		(fp_line
			(start 0.17207 -1.45)
			(end -0.17207 -1.45)
			(stroke
				(width 0.2)
				(type solid)
			)
			(layer "F.SilkS")
		)
		(fp_circle
			(center -2.21036 -0.95001)
			(end -2.33536 -0.95001)
			(stroke
				(width 0.25)
				(type solid)
			)
			(fill no)
			(layer "F.SilkS")
		)
		(fp_line
			(start -1.68536 1.54999)
			(end -1.68536 -1.55)
			(stroke
				(width 0.2)
				(type solid)
			)
			(layer "F.CrtYd")
		)
		(fp_line
			(start 1.68535 1.54999)
			(end -1.68536 1.54999)
			(stroke
				(width 0.2)
				(type solid)
			)
			(layer "F.CrtYd")
		)
		(fp_line
			(start 1.68535 1.54999)
			(end 1.68535 -1.55)
			(stroke
				(width 0.2)
				(type solid)
			)
			(layer "F.CrtYd")
		)
		(fp_line
			(start 1.68535 -1.55)
			(end -1.68536 -1.55)
			(stroke
				(width 0.2)
				(type solid)
			)
			(layer "F.CrtYd")
		)
		(fp_line
			(start -1.68536 1.54999)
			(end -1.68536 -1.55)
			(stroke
				(width 0.2)
				(type solid)
			)
			(layer "F.Fab")
		)
		(fp_line
			(start 1.68535 1.54999)
			(end -1.68536 1.54999)
			(stroke
				(width 0.2)
				(type solid)
			)
			(layer "F.Fab")
		)
		(fp_line
			(start 1.68535 1.54999)
			(end 1.68535 -1.55)
			(stroke
				(width 0.2)
				(type solid)
			)
			(layer "F.Fab")
		)
		(fp_line
			(start 0 0.49999)
			(end 0 -0.5)
			(stroke
				(width 0.1)
				(type solid)
			)
			(layer "F.Fab")
		)
		(fp_line
			(start 0.5 0)
			(end -0.5 0)
			(stroke
				(width 0.1)
				(type solid)
			)
			(layer "F.Fab")
		)
		(fp_line
			(start 1.68535 -1.55)
			(end -1.68536 -1.55)
			(stroke
				(width 0.2)
				(type solid)
			)
			(layer "F.Fab")
		)
		(fp_text user "${REFERENCE}"
			(at 0 0.28424 270)
			(unlocked yes)
			(layer "F.Fab")
			(effects
				(font
					(face "Arial")
					(size 0.63 0.63)
					(thickness 0.1)
				)
				(justify left bottom)
			)
		)
		(pad "1" smd rect
			(at -1.06621 -0.95001 270)
			(size 1.03828 0.53213)
			(layers "F.Cu" "F.Mask" "F.Paste")
			(net "SCL")
			(solder_mask_margin 0)
			(solder_paste_margin 0)
		)
		(pad "2" smd roundrect
			(at -1.06621 0 270)
			(size 1.03828 0.53213)
			(layers "F.Cu" "F.Mask" "F.Paste")
			(roundrect_rratio 0.5)
			(net "GND")
			(solder_mask_margin 0)
			(solder_paste_margin 0)
		)
		(pad "3" smd roundrect
			(at -1.06621 0.95 270)
			(size 1.03828 0.53213)
			(layers "F.Cu" "F.Mask" "F.Paste")
			(roundrect_rratio 0.5)
			(net "SDA")
			(solder_mask_margin 0)
			(solder_paste_margin 0)
		)
		(pad "4" smd roundrect
			(at 1.06621 0.95 270)
			(size 1.03828 0.53213)
			(layers "F.Cu" "F.Mask" "F.Paste")
			(roundrect_rratio 0.5)
			(net "+3.3V")
			(solder_mask_margin 0)
			(solder_paste_margin 0)
		)
		(pad "5" smd roundrect
			(at 1.06621 -0.95001 270)
			(size 1.03828 0.53213)
			(layers "F.Cu" "F.Mask" "F.Paste")
			(roundrect_rratio 0.5)
			(net "EXT_EEPROM_WP")
			(solder_mask_margin 0)
			(solder_paste_margin 0)
		)
	)
	(footprint "Vault:RESC1005X40X25NL05T05"
		(layer "F.Cu")
		(at 194.9216 128.7162 90)
		(property "Reference" "R153"
			(at 1.373069 -0.0968 0)
			(unlocked yes)
			(layer "F.SilkS")
			(effects
				(font
					(size 0.762 0.762)
					(thickness 0.2032)
				)
			)
		)
		(property "Value" "DNI_27_1%_0402"
			(at -2.732271 10.270975 0)
			(unlocked yes)
			(layer "F.SilkS")
			(hide yes)
			(effects
				(font
					(size 0.762 0.762)
					(thickness 0.2032)
				)
			)
		)
		(sheetname "11-M2_RCB_MUX")
		(sheetfile "11-M2_RCB_MUX.kicad_sch")
		(duplicate_pad_numbers_are_jumpers no)
		(pad "1" smd rect
			(at -0.45 0 180)
			(size 0.55 0.55)
			(layers "F.Cu" "F.Mask" "F.Paste")
			(net "RCB_GPS2_TP2")
		)
		(pad "2" smd rect
			(at 0.45 0 180)
			(size 0.55 0.55)
			(layers "F.Cu" "F.Mask" "F.Paste")
			(net "GPS2_TP2")
		)
	)
	(footprint "Vault:RESC1005X40X25NL05T05"
		(layer "F.Cu")
		(at 195.7216 135.8162)
		(property "Reference" "R158"
			(at 1.6032 0.926921 0)
			(unlocked yes)
			(layer "F.SilkS")
			(effects
				(font
					(size 0.762 0.762)
					(thickness 0.2032)
				)
			)
		)
		(property "Value" "DNI_27_1%_0402"
			(at -2.732271 10.270975 270)
			(unlocked yes)
			(layer "F.SilkS")
			(hide yes)
			(effects
				(font
					(size 0.762 0.762)
					(thickness 0.2032)
				)
			)
		)
		(sheetname "11-M2_RCB_MUX")
		(sheetfile "11-M2_RCB_MUX.kicad_sch")
		(duplicate_pad_numbers_are_jumpers no)
		(pad "1" smd rect
			(at -0.45 0 90)
			(size 0.55 0.55)
			(layers "F.Cu" "F.Mask" "F.Paste")
			(net "M2_GPS2_TP1")
		)
		(pad "2" smd rect
			(at 0.45 0 90)
			(size 0.55 0.55)
			(layers "F.Cu" "F.Mask" "F.Paste")
			(net "GPS2_TP1")
		)
	)
	(footprint "Vault:FP-0402-L_1_0_1-W_0_5_0_1-IPC_C"
		(layer "F.Cu")
		(at 73.9216 143.8162 180)
		(property "Reference" "C28"
			(at 0.2286 -1.473069 180)
			(unlocked yes)
			(layer "F.SilkS")
			(effects
				(font
					(size 0.762 0.762)
					(thickness 0.2286)
				)
			)
		)
		(property "Value" "0.1uF_25V_0402"
			(at 2.069035 2.567191 180)
			(unlocked yes)
			(layer "F.SilkS")
			(hide yes)
			(effects
				(font
					(size 0.762 0.762)
					(thickness 0.2286)
				)
			)
		)
		(sheetname "01-USER_IO")
		(sheetfile "01-USER_IO.kicad_sch")
		(duplicate_pad_numbers_are_jumpers no)
		(fp_line
			(start 0.65607 0.7)
			(end -0.65606 0.7)
			(stroke
				(width 0.2)
				(type solid)
			)
			(layer "F.SilkS")
		)
		(fp_line
			(start 0.65607 -0.7)
			(end -0.65606 -0.7)
			(stroke
				(width 0.2)
				(type solid)
			)
			(layer "F.SilkS")
		)
		(fp_line
			(start 0.75607 0.4)
			(end -0.75606 0.4)
			(stroke
				(width 0.2)
				(type solid)
			)
			(layer "F.CrtYd")
		)
		(fp_line
			(start 0.75607 -0.4)
			(end 0.75607 0.4)
			(stroke
				(width 0.2)
				(type solid)
			)
			(layer "F.CrtYd")
		)
		(fp_line
			(start 0.75607 -0.4)
			(end -0.75606 -0.4)
			(stroke
				(width 0.2)
				(type solid)
			)
			(layer "F.CrtYd")
		)
		(fp_line
			(start -0.75606 -0.4)
			(end -0.75606 0.4)
			(stroke
				(width 0.2)
				(type solid)
			)
			(layer "F.CrtYd")
		)
		(fp_line
			(start 0.75607 0.4)
			(end -0.75606 0.4)
			(stroke
				(width 0.2)
				(type solid)
			)
			(layer "F.Fab")
		)
		(fp_line
			(start 0.75607 -0.4)
			(end 0.75607 0.4)
			(stroke
				(width 0.2)
				(type solid)
			)
			(layer "F.Fab")
		)
		(fp_line
			(start 0.75607 -0.4)
			(end -0.75606 -0.4)
			(stroke
				(width 0.2)
				(type solid)
			)
			(layer "F.Fab")
		)
		(fp_line
			(start 0.5 0)
			(end -0.5 0)
			(stroke
				(width 0.1)
				(type solid)
			)
			(layer "F.Fab")
		)
		(fp_line
			(start 0 -0.5)
			(end 0 0.5)
			(stroke
				(width 0.1)
				(type solid)
			)
			(layer "F.Fab")
		)
		(fp_line
			(start -0.75606 -0.4)
			(end -0.75606 0.4)
			(stroke
				(width 0.2)
				(type solid)
			)
			(layer "F.Fab")
		)
		(fp_text user "${REFERENCE}"
			(at -0.00001 0.09601 180)
			(unlocked yes)
			(layer "F.Fab")
			(effects
				(font
					(face "Arial")
					(size 0.63 0.63)
					(thickness 0.1)
				)
				(justify left bottom)
			)
		)
		(pad "1" smd rect
			(at -0.36553 0 180)
			(size 0.58106 0.51213)
			(layers "F.Cu" "F.Mask" "F.Paste")
			(net "+3.3V")
			(solder_mask_margin 0)
			(solder_paste_margin 0)
		)
		(pad "2" smd rect
			(at 0.36554 0 180)
			(size 0.58106 0.51213)
			(layers "F.Cu" "F.Mask" "F.Paste")
			(net "GND")
			(solder_mask_margin 0)
			(solder_paste_margin 0)
		)
	)
	(footprint "Vault:FP-RUT0012A-MFG"
		(layer "F.Cu")
		(at 153.5216 129.7162)
		(property "Reference" "U22"
			(at -2.37291 -2.371569 0)
			(unlocked yes)
			(layer "F.SilkS")
			(effects
				(font
					(size 0.762 0.762)
					(thickness 0.2286)
				)
			)
		)
		(property "Value" "TMUX1072RUTR"
			(at 7.426665 3.164071 0)
			(unlocked yes)
			(layer "F.SilkS")
			(hide yes)
			(effects
				(font
					(size 0.762 0.762)
					(thickness 0.2286)
				)
			)
		)
		(sheetname "09-USBUart_PPSMUX_UARTMUX")
		(sheetfile "09-USBUart_PPSMUX_UARTMUX.kicad_sch")
		(duplicate_pad_numbers_are_jumpers no)
		(fp_line
			(start -0.9 -1.525)
			(end 0.9 -1.525)
			(stroke
				(width 0.2)
				(type solid)
			)
			(layer "F.SilkS")
		)
		(fp_line
			(start -0.9 1.525)
			(end 0.9 1.525)
			(stroke
				(width 0.2)
				(type solid)
			)
			(layer "F.SilkS")
		)
		(fp_circle
			(center -1.575 -0.8)
			(end -1.575 -0.925)
			(stroke
				(width 0.25)
				(type solid)
			)
			(fill no)
			(layer "F.SilkS")
		)
		(fp_rect
			(start -0.85 -0.3)
			(end -0.35 -0.5)
			(stroke
				(width 0)
				(type default)
			)
			(fill yes)
			(layer "F.Paste")
		)
		(fp_rect
			(start -0.85 0.1)
			(end -0.35 -0.1)
			(stroke
				(width 0)
				(type default)
			)
			(fill yes)
			(layer "F.Paste")
		)
		(fp_rect
			(start -0.85 0.5)
			(end -0.35 0.3)
			(stroke
				(width 0)
				(type default)
			)
			(fill yes)
			(layer "F.Paste")
		)
		(fp_rect
			(start -0.85 0.9)
			(end -0.35 0.7)
			(stroke
				(width 0)
				(type default)
			)
			(fill yes)
			(layer "F.Paste")
		)
		(fp_rect
			(start -0.1 -0.5)
			(end 0.1 -1)
			(stroke
				(width 0)
				(type default)
			)
			(fill yes)
			(layer "F.Paste")
		)
		(fp_rect
			(start -0.1 1)
			(end 0.1 0.5)
			(stroke
				(width 0)
				(type default)
			)
			(fill yes)
			(layer "F.Paste")
		)
		(fp_rect
			(start 0.35 -0.7)
			(end 0.85 -0.9)
			(stroke
				(width 0)
				(type default)
			)
			(fill yes)
			(layer "F.Paste")
		)
		(fp_rect
			(start 0.35 -0.3)
			(end 0.85 -0.5)
			(stroke
				(width 0)
				(type default)
			)
			(fill yes)
			(layer "F.Paste")
		)
		(fp_rect
			(start 0.35 0.1)
			(end 0.85 -0.1)
			(stroke
				(width 0)
				(type default)
			)
			(fill yes)
			(layer "F.Paste")
		)
		(fp_rect
			(start 0.35 0.5)
			(end 0.85 0.3)
			(stroke
				(width 0)
				(type default)
			)
			(fill yes)
			(layer "F.Paste")
		)
		(fp_rect
			(start 0.35 0.9)
			(end 0.85 0.7)
			(stroke
				(width 0)
				(type default)
			)
			(fill yes)
			(layer "F.Paste")
		)
		(fp_poly
			(pts
				(xy -0.5 -1) (xy -0.35 -1) (xy -0.35 -0.7) (xy -0.85 -0.7) (xy -0.85 -0.9) (xy -0.5 -0.9)
			)
			(stroke
				(width 0)
				(type default)
			)
			(fill yes)
			(layer "F.Paste")
		)
		(fp_line
			(start -1.05 -1.2)
			(end 1.05 -1.2)
			(stroke
				(width 0.2)
				(type solid)
			)
			(layer "F.CrtYd")
		)
		(fp_line
			(start -1.05 1.2)
			(end -1.05 -1.2)
			(stroke
				(width 0.2)
				(type solid)
			)
			(layer "F.CrtYd")
		)
		(fp_line
			(start -1.05 1.2)
			(end 1.05 1.2)
			(stroke
				(width 0.2)
				(type solid)
			)
			(layer "F.CrtYd")
		)
		(fp_line
			(start 1.05 1.2)
			(end 1.05 -1.2)
			(stroke
				(width 0.2)
				(type solid)
			)
			(layer "F.CrtYd")
		)
		(fp_line
			(start -1.05 -1.2)
			(end 1.05 -1.2)
			(stroke
				(width 0.2)
				(type solid)
			)
			(layer "F.Fab")
		)
		(fp_line
			(start -1.05 1.2)
			(end -1.05 -1.2)
			(stroke
				(width 0.2)
				(type solid)
			)
			(layer "F.Fab")
		)
		(fp_line
			(start -1.05 1.2)
			(end 1.05 1.2)
			(stroke
				(width 0.2)
				(type solid)
			)
			(layer "F.Fab")
		)
		(fp_line
			(start -0.5 0)
			(end 0.5 0)
			(stroke
				(width 0.1)
				(type solid)
			)
			(layer "F.Fab")
		)
		(fp_line
			(start 0 0.5)
			(end 0 -0.5)
			(stroke
				(width 0.1)
				(type solid)
			)
			(layer "F.Fab")
		)
		(fp_line
			(start 1.05 1.2)
			(end 1.05 -1.2)
			(stroke
				(width 0.2)
				(type solid)
			)
			(layer "F.Fab")
		)
		(fp_text user "${REFERENCE}"
			(at -0.00001 0.09602 0)
			(unlocked yes)
			(layer "F.Fab")
			(effects
				(font
					(face "Arial")
					(size 0.63 0.63)
					(thickness 0.1)
				)
				(justify left bottom)
			)
		)
		(pad "" smd custom
			(at -0.5 -1.1)
			(size 0.000001 0.000001)
			(layers "F.Cu" "F.Mask")
			(solder_mask_margin 0)
			(thermal_bridge_angle 90)
			(options
				(clearance outline)
				(anchor circle)
			)
			(primitives
				(gr_poly
					(pts
						(xy 0 0) (xy 0.15 0) (xy 0.15 0.4) (xy -0.45 0.4) (xy -0.45 0.2) (xy 0 0.2)
					)
					(width 0)
					(fill yes)
				)
			)
		)
		(pad "1" smd circle
			(at -0.45 -0.8)
			(size 0.18 0.18)
			(layers "F.Cu" "F.Mask" "F.Paste")
			(net "DIP_SW_UART_SEL")
			(solder_mask_margin 0)
			(solder_paste_margin -1000)
			(thermal_bridge_angle 90)
		)
		(pad "2" smd rect
			(at -0.65 -0.4)
			(size 0.6 0.2)
			(layers "F.Cu" "F.Mask" "F.Paste")
			(net "NetR91_2")
			(solder_mask_margin 0)
			(solder_paste_margin -1000)
		)
		(pad "3" smd rect
			(at -0.65 0)
			(size 0.6 0.2)
			(layers "F.Cu" "F.Mask" "F.Paste")
			(net "GND")
			(solder_mask_margin 0)
			(solder_paste_margin -1000)
		)
		(pad "4" smd rect
			(at -0.65 0.4)
			(size 0.6 0.2)
			(layers "F.Cu" "F.Mask" "F.Paste")
			(net "NetR93_2")
			(solder_mask_margin 0)
			(solder_paste_margin -1000)
		)
		(pad "5" smd rect
			(at -0.65 0.8)
			(size 0.6 0.2)
			(layers "F.Cu" "F.Mask" "F.Paste")
			(net "DIP_SW_UART_SEL")
			(solder_mask_margin 0)
			(solder_paste_margin -1000)
		)
		(pad "6" smd rect
			(at 0 0.8)
			(size 0.2 0.6)
			(layers "F.Cu" "F.Mask" "F.Paste")
			(net "GND")
			(solder_mask_margin 0)
			(solder_paste_margin -1000)
		)
		(pad "7" smd rect
			(at 0.65 0.8)
			(size 0.6 0.2)
			(layers "F.Cu" "F.Mask" "F.Paste")
			(net "GPS2_RX")
			(solder_mask_margin 0)
			(solder_paste_margin -1000)
		)
		(pad "8" smd rect
			(at 0.65 0.4)
			(size 0.6 0.2)
			(layers "F.Cu" "F.Mask" "F.Paste")
			(net "NetR92_2")
			(solder_mask_margin 0)
			(solder_paste_margin -1000)
		)
		(pad "9" smd rect
			(at 0.65 0)
			(size 0.6 0.2)
			(layers "F.Cu" "F.Mask" "F.Paste")
			(net "GNSS2_P3V3")
			(solder_mask_margin 0)
			(solder_paste_margin -1000)
		)
		(pad "10" smd rect
			(at 0.65 -0.4)
			(size 0.6 0.2)
			(layers "F.Cu" "F.Mask" "F.Paste")
			(net "NetR90_2")
			(solder_mask_margin 0)
			(solder_paste_margin -1000)
		)
		(pad "11" smd rect
			(at 0.65 -0.8)
			(size 0.6 0.2)
			(layers "F.Cu" "F.Mask" "F.Paste")
			(net "GPS2_TX")
			(solder_mask_margin 0)
			(solder_paste_margin -1000)
		)
		(pad "12" smd rect
			(at 0 -0.8)
			(size 0.2 0.6)
			(layers "F.Cu" "F.Mask" "F.Paste")
			(net "GND")
			(solder_mask_margin 0)
			(solder_paste_margin -1000)
		)
	)
	(footprint "Vault:CAPC1608X87X45ML20T05"
		(layer "F.Cu")
		(at 227.5216 65.5162 -90)
		(property "Reference" "C2"
			(at -1.8 -0.393345 90)
			(unlocked yes)
			(layer "F.SilkS")
			(effects
				(font
					(size 0.762 0.762)
					(thickness 0.2286)
				)
				(justify left bottom)
			)
		)
		(property "Value" "0.1uF"
			(at 1.525445 1.1493 0)
			(unlocked yes)
			(layer "F.SilkS")
			(hide yes)
			(effects
				(font
					(size 0.762 0.762)
					(thickness 0.2286)
				)
				(justify left bottom)
			)
		)
		(sheetname "03-POWER")
		(sheetfile "03-POWER.kicad_sch")
		(duplicate_pad_numbers_are_jumpers no)
		(pad "1" smd rect
			(at -0.7 0)
			(size 1.1 1.05)
			(layers "F.Cu" "F.Mask" "F.Paste")
			(net "GND")
		)
		(pad "2" smd rect
			(at 0.7 0)
			(size 1.1 1.05)
			(layers "F.Cu" "F.Mask" "F.Paste")
			(net "+12V")
		)
	)
	(footprint "Miscellaneous Connectors:HDR2X6_CEN"
		(layer "F.Cu")
		(at 226.9216 80.0562 -90)
		(property "Reference" "P3"
			(at 5.031395 1.873079 90)
			(unlocked yes)
			(layer "F.SilkS")
			(effects
				(font
					(size 0.762 0.762)
					(thickness 0.2286)
				)
			)
		)
		(property "Value" "EXT GPIO"
			(at -4.281671 2.296855 180)
			(unlocked yes)
			(layer "F.SilkS")
			(hide yes)
			(effects
				(font
					(size 0.762 0.762)
					(thickness 0.2286)
				)
			)
		)
		(sheetname "05-GPS_IMU_SENSORS")
		(sheetfile "05-GPS_IMU_SENSORS.kicad_sch")
		(duplicate_pad_numbers_are_jumpers no)
		(fp_line
			(start -1.27 1.27)
			(end -1.27 -3.81)
			(stroke
				(width 0.2)
				(type solid)
			)
			(layer "F.SilkS")
		)
		(fp_line
			(start 13.97 1.27)
			(end -1.27 1.27)
			(stroke
				(width 0.2)
				(type solid)
			)
			(layer "F.SilkS")
		)
		(fp_line
			(start 13.97 1.27)
			(end 13.97 -3.81)
			(stroke
				(width 0.2)
				(type solid)
			)
			(layer "F.SilkS")
		)
		(fp_line
			(start 13.97 -3.81)
			(end -1.27 -3.81)
			(stroke
				(width 0.2)
				(type solid)
			)
			(layer "F.SilkS")
		)
		(fp_text user "6"
			(at 10.56 2.655575 270)
			(unlocked yes)
			(layer "F.SilkS")
			(effects
				(font
					(size 1.27 1.27)
					(thickness 0.2032)
				)
				(justify left bottom)
			)
		)
		(fp_text user "1"
			(at -2.14 0.855575 270)
			(unlocked yes)
			(layer "F.SilkS")
			(effects
				(font
					(size 1.27 1.27)
					(thickness 0.2032)
				)
				(justify left bottom)
			)
		)
		(fp_text user "7"
			(at -2.54 -1.876425 270)
			(unlocked yes)
			(layer "F.SilkS")
			(effects
				(font
					(size 1.27 1.27)
					(thickness 0.2032)
				)
				(justify left bottom)
			)
		)
		(fp_text user "12"
			(at 11.68946 -3.654425 270)
			(unlocked yes)
			(layer "F.SilkS")
			(effects
				(font
					(size 1.27 1.27)
					(thickness 0.2032)
				)
				(justify left bottom)
			)
		)
		(pad "1" thru_hole rect
			(at 0 0 270)
			(size 1.5 1.5)
			(drill 0.9)
			(layers "*.Cu" "*.Mask")
			(remove_unused_layers no)
			(net "EXT_GPIO_1")
		)
		(pad "2" thru_hole circle
			(at 2.54 0 270)
			(size 1.5 1.5)
			(drill 0.9)
			(layers "*.Cu" "*.Mask")
			(remove_unused_layers no)
			(net "EXT_GPIO_2")
			(thermal_bridge_angle 90)
		)
		(pad "3" thru_hole circle
			(at 5.08 0 270)
			(size 1.5 1.5)
			(drill 0.9)
			(layers "*.Cu" "*.Mask")
			(remove_unused_layers no)
			(net "EXT_GPIO_3")
			(thermal_bridge_angle 90)
		)
		(pad "4" thru_hole circle
			(at 7.62 0 270)
			(size 1.5 1.5)
			(drill 0.9)
			(layers "*.Cu" "*.Mask")
			(remove_unused_layers no)
			(net "EXT_GPIO_4")
			(thermal_bridge_angle 90)
		)
		(pad "5" thru_hole circle
			(at 10.16 0 270)
			(size 1.5 1.5)
			(drill 0.9)
			(layers "*.Cu" "*.Mask")
			(remove_unused_layers no)
			(net "GND")
			(thermal_bridge_angle 90)
		)
		(pad "6" thru_hole circle
			(at 12.7 0 270)
			(size 1.5 1.5)
			(drill 0.9)
			(layers "*.Cu" "*.Mask")
			(remove_unused_layers no)
			(net "+3.3V")
			(thermal_bridge_angle 90)
		)
		(pad "7" thru_hole circle
			(at 0 -2.54 270)
			(size 1.5 1.5)
			(drill 0.9)
			(layers "*.Cu" "*.Mask")
			(remove_unused_layers no)
			(net "EXT_GPIO_7")
			(thermal_bridge_angle 90)
		)
		(pad "8" thru_hole circle
			(at 2.54 -2.54 270)
			(size 1.5 1.5)
			(drill 0.9)
			(layers "*.Cu" "*.Mask")
			(remove_unused_layers no)
			(net "EXT_GPIO_8")
			(thermal_bridge_angle 90)
		)
		(pad "9" thru_hole circle
			(at 5.08 -2.54 270)
			(size 1.5 1.5)
			(drill 0.9)
			(layers "*.Cu" "*.Mask")
			(remove_unused_layers no)
			(net "EXT_GPIO_9")
			(thermal_bridge_angle 90)
		)
		(pad "10" thru_hole circle
			(at 7.62 -2.54 270)
			(size 1.5 1.5)
			(drill 0.9)
			(layers "*.Cu" "*.Mask")
			(remove_unused_layers no)
			(net "EXT_GPIO_10")
			(thermal_bridge_angle 90)
		)
		(pad "11" thru_hole circle
			(at 10.16 -2.54 270)
			(size 1.5 1.5)
			(drill 0.9)
			(layers "*.Cu" "*.Mask")
			(remove_unused_layers no)
			(net "GND")
			(thermal_bridge_angle 90)
		)
		(pad "12" thru_hole circle
			(at 12.7 -2.54 270)
			(size 1.5 1.5)
			(drill 0.9)
			(layers "*.Cu" "*.Mask")
			(remove_unused_layers no)
			(net "+3.3V")
			(thermal_bridge_angle 90)
		)
	)
	(footprint "Vault:RESC3116X65X50ML20T20"
		(layer "F.Cu")
		(at 140.7716 87.8662)
		(property "Reference" "R46"
			(at 4.0786 -0.023069 0)
			(unlocked yes)
			(layer "F.SilkS")
			(effects
				(font
					(size 0.762 0.762)
					(thickness 0.2286)
				)
			)
		)
		(property "Value" "DNI_0_5%_1206"
			(at 7.27402 3.291071 0)
			(unlocked yes)
			(layer "F.SilkS")
			(hide yes)
			(effects
				(font
					(size 0.762 0.762)
					(thickness 0.2286)
				)
			)
		)
		(sheetname "06-MAC")
		(sheetfile "06-MAC.kicad_sch")
		(duplicate_pad_numbers_are_jumpers no)
		(fp_line
			(start -0.35 -0.85)
			(end 0.35 -0.85)
			(stroke
				(width 0.2)
				(type solid)
			)
			(layer "F.SilkS")
		)
		(fp_line
			(start -0.35 0.85)
			(end 0.35 0.85)
			(stroke
				(width 0.2)
				(type solid)
			)
			(layer "F.SilkS")
		)
		(pad "1" smd rect
			(at -1.475 0 90)
			(size 1.9 1.45)
			(layers "F.Cu" "F.Mask" "F.Paste")
			(net "MAC_VCC")
		)
		(pad "2" smd rect
			(at 1.475 0 90)
			(size 1.9 1.45)
			(layers "F.Cu" "F.Mask" "F.Paste")
			(net "+12V")
		)
	)
	(footprint "Vault:RESC1005X40X25NL10T10"
		(layer "F.Cu")
		(at 175.5216 115.6162)
		(property "Reference" "R115"
			(at 2.7032 0.126931 0)
			(unlocked yes)
			(layer "F.SilkS")
			(effects
				(font
					(size 0.762 0.762)
					(thickness 0.2032)
				)
			)
		)
		(property "Value" "4.7K_1%_0402"
			(at -2.732271 8.747465 270)
			(unlocked yes)
			(layer "F.SilkS")
			(hide yes)
			(effects
				(font
					(size 0.762 0.762)
					(thickness 0.2032)
				)
			)
		)
		(sheetname "08-DIPSwitches_I2C")
		(sheetfile "08-DIPSwitches_I2C.kicad_sch")
		(duplicate_pad_numbers_are_jumpers no)
		(pad "1" smd rect
			(at -0.425 0 90)
			(size 0.6 0.65)
			(layers "F.Cu" "F.Mask" "F.Paste")
			(net "ANADC_I2C_SDA")
		)
		(pad "2" smd rect
			(at 0.425 0 90)
			(size 0.6 0.65)
			(layers "F.Cu" "F.Mask" "F.Paste")
			(net "+3.3V")
		)
	)
	(footprint "Vault:RESC1005X40X25LL05T05"
		(layer "F.Cu")
		(at 113.2216 68.9162 180)
		(property "Reference" "R130"
			(at -0.326931 2.4032 90)
			(unlocked yes)
			(layer "F.SilkS")
			(effects
				(font
					(size 0.762 0.762)
					(thickness 0.2032)
				)
			)
		)
		(property "Value" "DNI_0_1%_0402"
			(at -2.579871 9.56002 90)
			(unlocked yes)
			(layer "F.SilkS")
			(hide yes)
			(effects
				(font
					(size 0.762 0.762)
					(thickness 0.2032)
				)
			)
		)
		(sheetname "10-M2_GPS")
		(sheetfile "10-M2_GPS.kicad_sch")
		(duplicate_pad_numbers_are_jumpers no)
		(pad "1" smd rect
			(at -0.4 0 270)
			(size 0.45 0.45)
			(layers "F.Cu" "F.Mask" "F.Paste")
			(net "NetJ44_35")
		)
		(pad "2" smd rect
			(at 0.4 0 270)
			(size 0.45 0.45)
			(layers "F.Cu" "F.Mask" "F.Paste")
			(net "M2_GPS1_TP1")
		)
	)
	(footprint "SA53:SolderSocket"
		(locked yes)
		(layer "F.Cu")
		(at 122.4216 140.0162 90)
		(property "Reference" "SKT3"
			(at -3.426921 2.1286 0)
			(unlocked yes)
			(layer "F.SilkS")
			(effects
				(font
					(size 0.762 0.762)
					(thickness 0.2286)
				)
			)
		)
		(property "Value" "0332-0-43-80-18-27-10-0"
			(at -2.910071 16.1362 0)
			(unlocked yes)
			(layer "F.SilkS")
			(hide yes)
			(effects
				(font
					(size 0.762 0.762)
					(thickness 0.2286)
				)
			)
		)
		(sheetname "06-MAC")
		(sheetfile "06-MAC.kicad_sch")
		(duplicate_pad_numbers_are_jumpers no)
		(pad "1" thru_hole circle
			(at 0 0 90)
			(size 2.54 2.54)
			(drill 2.0066)
			(layers "*.Cu" "*.Mask")
			(remove_unused_layers no)
			(net "MAC_RX")
			(thermal_bridge_angle 90)
		)
	)
	(footprint "Vault:RESC3116X65X50ML20T20"
		(layer "F.Cu")
		(at 140.7716 93.8662)
		(property "Reference" "R47"
			(at 3.9286 -0.073069 0)
			(unlocked yes)
			(layer "F.SilkS")
			(effects
				(font
					(size 0.762 0.762)
					(thickness 0.2286)
				)
			)
		)
		(property "Value" "DNI_0_5%_1206"
			(at 7.27402 3.291071 0)
			(unlocked yes)
			(layer "F.SilkS")
			(hide yes)
			(effects
				(font
					(size 0.762 0.762)
					(thickness 0.2286)
				)
			)
		)
		(sheetname "06-MAC")
		(sheetfile "06-MAC.kicad_sch")
		(duplicate_pad_numbers_are_jumpers no)
		(fp_line
			(start -0.35 -0.85)
			(end 0.35 -0.85)
			(stroke
				(width 0.2)
				(type solid)
			)
			(layer "F.SilkS")
		)
		(fp_line
			(start -0.35 0.85)
			(end 0.35 0.85)
			(stroke
				(width 0.2)
				(type solid)
			)
			(layer "F.SilkS")
		)
		(pad "1" smd rect
			(at -1.475 0 90)
			(size 1.9 1.45)
			(layers "F.Cu" "F.Mask" "F.Paste")
			(net "MAC_VCC")
		)
		(pad "2" smd rect
			(at 1.475 0 90)
			(size 1.9 1.45)
			(layers "F.Cu" "F.Mask" "F.Paste")
			(net "+3.3V")
		)
	)
	(footprint "Vault:FP-GRM31C-0_2-e0_3_0_8-IPC_C"
		(layer "F.Cu")
		(at 188.94582 86.9162)
		(property "Reference" "C77"
			(at 1.20438 -1.473069 0)
			(unlocked yes)
			(layer "F.SilkS")
			(effects
				(font
					(size 0.762 0.762)
					(thickness 0.2286)
				)
			)
		)
		(property "Value" "4.7uF_50V_1206"
			(at 8.594605 2.719551 0)
			(unlocked yes)
			(layer "F.SilkS")
			(hide yes)
			(effects
				(font
					(size 0.762 0.762)
					(thickness 0.2286)
				)
			)
		)
		(sheetname "03-POWER")
		(sheetfile "03-POWER.kicad_sch")
		(duplicate_pad_numbers_are_jumpers no)
		(fp_line
			(start -0.39847 -0.9)
			(end 0.39846 -0.9)
			(stroke
				(width 0.2)
				(type solid)
			)
			(layer "F.SilkS")
		)
		(fp_line
			(start -0.39847 0.9)
			(end 0.39846 0.9)
			(stroke
				(width 0.2)
				(type solid)
			)
			(layer "F.SilkS")
		)
		(fp_line
			(start -1.9531 -1)
			(end 1.9531 -1)
			(stroke
				(width 0.2)
				(type solid)
			)
			(layer "F.CrtYd")
		)
		(fp_line
			(start -1.9531 1)
			(end -1.9531 -1)
			(stroke
				(width 0.2)
				(type solid)
			)
			(layer "F.CrtYd")
		)
		(fp_line
			(start -1.9531 1)
			(end 1.9531 1)
			(stroke
				(width 0.2)
				(type solid)
			)
			(layer "F.CrtYd")
		)
		(fp_line
			(start 1.9531 1)
			(end 1.9531 -1)
			(stroke
				(width 0.2)
				(type solid)
			)
			(layer "F.CrtYd")
		)
		(fp_line
			(start -1.9531 -1)
			(end 1.9531 -1)
			(stroke
				(width 0.2)
				(type solid)
			)
			(layer "F.Fab")
		)
		(fp_line
			(start -1.9531 1)
			(end -1.9531 -1)
			(stroke
				(width 0.2)
				(type solid)
			)
			(layer "F.Fab")
		)
		(fp_line
			(start -1.9531 1)
			(end 1.9531 1)
			(stroke
				(width 0.2)
				(type solid)
			)
			(layer "F.Fab")
		)
		(fp_line
			(start -0.5 0)
			(end 0.5 0)
			(stroke
				(width 0.1)
				(type solid)
			)
			(layer "F.Fab")
		)
		(fp_line
			(start 0 0.5)
			(end 0 -0.5)
			(stroke
				(width 0.1)
				(type solid)
			)
			(layer "F.Fab")
		)
		(fp_line
			(start 1.9531 1)
			(end 1.9531 -1)
			(stroke
				(width 0.2)
				(type solid)
			)
			(layer "F.Fab")
		)
		(fp_text user "${REFERENCE}"
			(at -0.00001 0.09602 360)
			(unlocked yes)
			(layer "F.Fab")
			(effects
				(font
					(face "Arial")
					(size 0.63 0.63)
					(thickness 0.1)
				)
				(justify left bottom)
			)
		)
		(pad "1" smd rect
			(at -1.27578 0)
			(size 1.15464 1.7062)
			(layers "F.Cu" "F.Mask" "F.Paste")
			(net "+12V")
			(solder_mask_margin 0)
			(solder_paste_margin 0)
		)
		(pad "2" smd rect
			(at 1.27578 0)
			(size 1.15464 1.7062)
			(layers "F.Cu" "F.Mask" "F.Paste")
			(net "GND")
			(solder_mask_margin 0)
			(solder_paste_margin 0)
		)
	)
	(footprint "Vault:RESC1005X40X25NL05T05"
		(layer "F.Cu")
		(at 160.9716 130.3162 180)
		(property "Reference" "R86"
			(at -0.5786 -1.126921 0)
			(unlocked yes)
			(layer "F.SilkS")
			(effects
				(font
					(size 0.762 0.762)
					(thickness 0.2286)
				)
			)
		)
		(property "Value" "27_1%_0402"
			(at -2.732271 7.37632 90)
			(unlocked yes)
			(layer "F.SilkS")
			(hide yes)
			(effects
				(font
					(size 0.762 0.762)
					(thickness 0.2286)
				)
			)
		)
		(sheetname "09-USBUart_PPSMUX_UARTMUX")
		(sheetfile "09-USBUart_PPSMUX_UARTMUX.kicad_sch")
		(duplicate_pad_numbers_are_jumpers no)
		(pad "1" smd rect
			(at -0.45 0 270)
			(size 0.55 0.55)
			(layers "F.Cu" "F.Mask" "F.Paste")
			(net "GND")
		)
		(pad "2" smd rect
			(at 0.45 0 270)
			(size 0.55 0.55)
			(layers "F.Cu" "F.Mask" "F.Paste")
			(net "NetR86_2")
		)
	)
	(footprint "Vault:FP-D0008A-MFG"
		(layer "F.Cu")
		(at 168.78957 91.9162 90)
		(property "Reference" "U19"
			(at -0.2286 3.373069 270)
			(unlocked yes)
			(layer "F.SilkS")
			(effects
				(font
					(size 0.762 0.762)
					(thickness 0.2286)
				)
			)
		)
		(property "Value" "INA219BIDR"
			(at 3.16004 4.408671 90)
			(unlocked yes)
			(layer "F.SilkS")
			(hide yes)
			(effects
				(font
					(size 0.762 0.762)
					(thickness 0.2286)
				)
			)
		)
		(sheetname "03-POWER")
		(sheetfile "03-POWER.kicad_sch")
		(duplicate_pad_numbers_are_jumpers no)
		(fp_line
			(start 1.5 -2.5)
			(end 1.5 2.5)
			(stroke
				(width 0.2)
				(type solid)
			)
			(layer "F.SilkS")
		)
		(fp_line
			(start -1.5 -2.5)
			(end 1.5 -2.5)
			(stroke
				(width 0.2)
				(type solid)
			)
			(layer "F.SilkS")
		)
		(fp_line
			(start -1.5 -2.5)
			(end -1.5 2.5)
			(stroke
				(width 0.2)
				(type solid)
			)
			(layer "F.SilkS")
		)
		(fp_line
			(start -1.5 2.5)
			(end 1.5 2.5)
			(stroke
				(width 0.2)
				(type solid)
			)
			(layer "F.SilkS")
		)
		(fp_circle
			(center -4.05 -1.905)
			(end -3.925 -1.905)
			(stroke
				(width 0.25)
				(type solid)
			)
			(fill no)
			(layer "F.SilkS")
		)
		(fp_circle
			(center -0.725 -1.725)
			(end -0.475 -1.725)
			(stroke
				(width 0.5)
				(type solid)
			)
			(fill no)
			(layer "F.SilkS")
		)
		(fp_line
			(start 3.575 -2.75)
			(end 3.575 2.75)
			(stroke
				(width 0.2)
				(type solid)
			)
			(layer "F.CrtYd")
		)
		(fp_line
			(start -3.575 -2.75)
			(end 3.575 -2.75)
			(stroke
				(width 0.2)
				(type solid)
			)
			(layer "F.CrtYd")
		)
		(fp_line
			(start -3.575 -2.75)
			(end -3.575 2.75)
			(stroke
				(width 0.2)
				(type solid)
			)
			(layer "F.CrtYd")
		)
		(fp_line
			(start -3.575 2.75)
			(end 3.575 2.75)
			(stroke
				(width 0.2)
				(type solid)
			)
			(layer "F.CrtYd")
		)
		(fp_line
			(start 3.575 -2.75)
			(end 3.575 2.75)
			(stroke
				(width 0.2)
				(type solid)
			)
			(layer "F.Fab")
		)
		(fp_line
			(start -3.575 -2.75)
			(end 3.575 -2.75)
			(stroke
				(width 0.2)
				(type solid)
			)
			(layer "F.Fab")
		)
		(fp_line
			(start -3.575 -2.75)
			(end -3.575 2.75)
			(stroke
				(width 0.2)
				(type solid)
			)
			(layer "F.Fab")
		)
		(fp_line
			(start 0 -0.5)
			(end 0 0.5)
			(stroke
				(width 0.1)
				(type solid)
			)
			(layer "F.Fab")
		)
		(fp_line
			(start -0.5 0)
			(end 0.5 0)
			(stroke
				(width 0.1)
				(type solid)
			)
			(layer "F.Fab")
		)
		(fp_line
			(start -3.575 2.75)
			(end 3.575 2.75)
			(stroke
				(width 0.2)
				(type solid)
			)
			(layer "F.Fab")
		)
		(fp_text user "${REFERENCE}"
			(at -0.00001 0.09602 90)
			(unlocked yes)
			(layer "F.Fab")
			(effects
				(font
					(face "Arial")
					(size 0.63 0.63)
					(thickness 0.1)
				)
				(justify left bottom)
			)
		)
		(pad "1" smd roundrect
			(at -2.7 -1.905 90)
			(size 1.55 0.6)
			(layers "F.Cu" "F.Mask" "F.Paste")
			(roundrect_rratio 0.085)
			(net "NetR80_1")
			(solder_mask_margin 0)
			(solder_paste_margin 0)
		)
		(pad "2" smd roundrect
			(at -2.7 -0.635 90)
			(size 1.55 0.6)
			(layers "F.Cu" "F.Mask" "F.Paste")
			(roundrect_rratio 0.085)
			(net "NetR79_1")
			(solder_mask_margin 0)
			(solder_paste_margin 0)
		)
		(pad "3" smd roundrect
			(at -2.7 0.635 90)
			(size 1.55 0.6)
			(layers "F.Cu" "F.Mask" "F.Paste")
			(roundrect_rratio 0.085)
			(net "SENS_I2C_SDA")
			(solder_mask_margin 0)
			(solder_paste_margin 0)
		)
		(pad "4" smd roundrect
			(at -2.7 1.905 90)
			(size 1.55 0.6)
			(layers "F.Cu" "F.Mask" "F.Paste")
			(roundrect_rratio 0.085)
			(net "SENS_I2C_SCL")
			(solder_mask_margin 0)
			(solder_paste_margin 0)
		)
		(pad "5" smd roundrect
			(at 2.7 1.905 90)
			(size 1.55 0.6)
			(layers "F.Cu" "F.Mask" "F.Paste")
			(roundrect_rratio 0.085)
			(net "+3.3V")
			(solder_mask_margin 0)
			(solder_paste_margin 0)
		)
		(pad "6" smd roundrect
			(at 2.7 0.635 90)
			(size 1.55 0.6)
			(layers "F.Cu" "F.Mask" "F.Paste")
			(roundrect_rratio 0.085)
			(net "GND")
			(solder_mask_margin 0)
			(solder_paste_margin 0)
		)
		(pad "7" smd roundrect
			(at 2.7 -0.635 90)
			(size 1.55 0.6)
			(layers "F.Cu" "F.Mask" "F.Paste")
			(roundrect_rratio 0.085)
			(net "+3.3V")
			(solder_mask_margin 0)
			(solder_paste_margin 0)
		)
		(pad "8" smd roundrect
			(at 2.7 -1.905 90)
			(size 1.55 0.6)
			(layers "F.Cu" "F.Mask" "F.Paste")
			(roundrect_rratio 0.085)
			(net "P3V3_SENSE")
			(solder_mask_margin 0)
			(solder_paste_margin 0)
		)
	)
	(footprint "Vault:RESC1608X55X25NL10T15"
		(layer "F.Cu")
		(at 75.1216 126.4162 180)
		(property "Reference" "R28"
			(at 0.7 0.953785 0)
			(unlocked yes)
			(layer "F.SilkS")
			(effects
				(font
					(size 0.762 0.762)
					(thickness 0.2286)
				)
				(justify left bottom)
			)
		)
		(property "Value" "49.9R"
			(at 1.1445 -4.336645 0)
			(unlocked yes)
			(layer "F.SilkS")
			(hide yes)
			(effects
				(font
					(size 0.762 0.762)
					(thickness 0.2286)
				)
				(justify left bottom)
			)
		)
		(sheetname "01-USER_IO")
		(sheetfile "01-USER_IO.kicad_sch")
		(duplicate_pad_numbers_are_jumpers no)
		(pad "1" smd rect
			(at -0.7 0 270)
			(size 0.9 0.7)
			(layers "F.Cu" "F.Mask" "F.Paste")
			(net "NetR28_1")
		)
		(pad "2" smd rect
			(at 0.7 0 270)
			(size 0.9 0.7)
			(layers "F.Cu" "F.Mask" "F.Paste")
			(net "NetAN3_1")
		)
	)
	(footprint "Vault:RESC1005X40X25NL05T05"
		(layer "F.Cu")
		(at 157.6216 116.8162 180)
		(property "Reference" "R95"
			(at -3.0286 -0.126931 0)
			(unlocked yes)
			(layer "F.SilkS")
			(effects
				(font
					(size 0.762 0.762)
					(thickness 0.2286)
				)
			)
		)
		(property "Value" "27_1%_0402"
			(at -2.935471 7.78247 90)
			(unlocked yes)
			(layer "F.SilkS")
			(hide yes)
			(effects
				(font
					(size 0.762 0.762)
					(thickness 0.2286)
				)
			)
		)
		(sheetname "08-DIPSwitches_I2C")
		(sheetfile "08-DIPSwitches_I2C.kicad_sch")
		(duplicate_pad_numbers_are_jumpers no)
		(pad "1" smd rect
			(at -0.45 0 270)
			(size 0.55 0.55)
			(layers "F.Cu" "F.Mask" "F.Paste")
			(net "MAC_I2C_SDA")
		)
		(pad "2" smd rect
			(at 0.45 0 270)
			(size 0.55 0.55)
			(layers "F.Cu" "F.Mask" "F.Paste")
			(net "NetR95_2")
		)
	)
	(footprint "Vault:61300411121"
		(layer "F.Cu")
		(at 153.7216 90.8462 90)
		(property "Reference" "P5"
			(at 6.945129 0.164685 0)
			(unlocked yes)
			(layer "F.SilkS")
			(effects
				(font
					(size 0.762 0.762)
					(thickness 0.2032)
				)
			)
		)
		(property "Value" "61300411121"
			(at -6.999471 6.25871 0)
			(unlocked yes)
			(layer "F.SilkS")
			(hide yes)
			(effects
				(font
					(size 0.762 0.762)
					(thickness 0.2032)
				)
			)
		)
		(sheetname "05-GPS_IMU_SENSORS")
		(sheetfile "05-GPS_IMU_SENSORS.kicad_sch")
		(duplicate_pad_numbers_are_jumpers no)
		(fp_line
			(start 5.23 -1.345)
			(end 5.23 1.345)
			(stroke
				(width 0.2)
				(type solid)
			)
			(layer "F.SilkS")
		)
		(fp_line
			(start -5.23 -1.345)
			(end 5.23 -1.345)
			(stroke
				(width 0.2)
				(type solid)
			)
			(layer "F.SilkS")
		)
		(fp_line
			(start -5.23 -1.345)
			(end -5.23 1.345)
			(stroke
				(width 0.2)
				(type solid)
			)
			(layer "F.SilkS")
		)
		(fp_line
			(start -5.23 1.345)
			(end 5.23 1.345)
			(stroke
				(width 0.2)
				(type solid)
			)
			(layer "F.SilkS")
		)
		(pad "1" thru_hole rect
			(at -3.81 0 90)
			(size 1.6 1.6)
			(drill 1.1)
			(layers "*.Cu" "*.Mask")
			(remove_unused_layers no)
			(net "+3.3V")
		)
		(pad "2" thru_hole circle
			(at -1.27 0 90)
			(size 1.6 1.6)
			(drill 1.1)
			(layers "*.Cu" "*.Mask")
			(remove_unused_layers no)
			(net "GND")
			(thermal_bridge_angle 90)
		)
		(pad "3" thru_hole circle
			(at 1.27 0 90)
			(size 1.6 1.6)
			(drill 1.1)
			(layers "*.Cu" "*.Mask")
			(remove_unused_layers no)
			(net "DC_I2C_SCL")
			(thermal_bridge_angle 90)
		)
		(pad "4" thru_hole circle
			(at 3.81 0 90)
			(size 1.6 1.6)
			(drill 1.1)
			(layers "*.Cu" "*.Mask")
			(remove_unused_layers no)
			(net "DC_I2C_SDA")
			(thermal_bridge_angle 90)
		)
	)
	(footprint "Vault:RESC1608X55X30NL15T15"
		(layer "F.Cu")
		(at 87.70686 89.06371)
		(property "Reference" "R41"
			(at -2.521395 0.026921 0)
			(unlocked yes)
			(layer "F.SilkS")
			(effects
				(font
					(size 0.762 0.762)
					(thickness 0.2286)
				)
			)
		)
		(property "Value" "4.7K"
			(at 1.61204 2.325871 0)
			(unlocked yes)
			(layer "F.SilkS")
			(hide yes)
			(effects
				(font
					(size 0.762 0.762)
					(thickness 0.2286)
				)
			)
		)
		(sheetname "02-USER_IO_STATUS")
		(sheetfile "02-USER_IO_STATUS.kicad_sch")
		(duplicate_pad_numbers_are_jumpers no)
		(pad "1" smd rect
			(at -0.75 0 90)
			(size 0.95 0.95)
			(layers "F.Cu" "F.Mask" "F.Paste")
			(net "GND")
		)
		(pad "2" smd rect
			(at 0.75 0 90)
			(size 0.95 0.95)
			(layers "F.Cu" "F.Mask" "F.Paste")
			(net "NetR41_2")
		)
	)
	(footprint "SA53:SolderSocket"
		(locked yes)
		(layer "F.Cu")
		(at 86.9216 137.3162 90)
		(property "Reference" "SKT5"
			(at -6.626931 0.3286 0)
			(unlocked yes)
			(layer "F.SilkS")
			(effects
				(font
					(size 0.762 0.762)
					(thickness 0.2286)
				)
			)
		)
		(property "Value" "0332-0-43-80-18-27-10-0"
			(at -2.910071 16.1362 0)
			(unlocked yes)
			(layer "F.SilkS")
			(hide yes)
			(effects
				(font
					(size 0.762 0.762)
					(thickness 0.2286)
				)
			)
		)
		(sheetname "06-MAC")
		(sheetfile "06-MAC.kicad_sch")
		(duplicate_pad_numbers_are_jumpers no)
		(pad "1" thru_hole circle
			(at 0 0 90)
			(size 2.54 2.54)
			(drill 2.0066)
			(layers "*.Cu" "*.Mask")
			(remove_unused_layers no)
			(net "MAC_RF_OUT")
			(thermal_bridge_angle 90)
		)
	)
	(footprint "Vault:FP-39-30-0040-MFG"
		(layer "F.Cu")
		(at 225.5654 55.3207 90)
		(property "Reference" "J38"
			(at 4.711155 -10.3438 0)
			(unlocked yes)
			(layer "F.SilkS")
			(effects
				(font
					(size 0.762 0.762)
					(thickness 0.2286)
				)
				(justify left bottom)
			)
		)
		(property "Value" "39-30-0040"
			(at -20.802445 -1.5141 0)
			(unlocked yes)
			(layer "F.SilkS")
			(hide yes)
			(effects
				(font
					(size 0.762 0.762)
					(thickness 0.2286)
				)
				(justify left bottom)
			)
		)
		(sheetname "03-POWER")
		(sheetfile "03-POWER.kicad_sch")
		(duplicate_pad_numbers_are_jumpers no)
		(fp_line
			(start 5.0165 -6.35)
			(end 5.0165 6.731)
			(stroke
				(width 0.2)
				(type solid)
			)
			(layer "F.SilkS")
		)
		(fp_line
			(start 3.8455 -6.35)
			(end 5.0165 -6.35)
			(stroke
				(width 0.2)
				(type solid)
			)
			(layer "F.SilkS")
		)
		(fp_line
			(start -0.3455 -6.35)
			(end 0.3455 -6.35)
			(stroke
				(width 0.2)
				(type solid)
			)
			(layer "F.SilkS")
		)
		(fp_line
			(start -5.0165 -6.35)
			(end -3.8455 -6.35)
			(stroke
				(width 0.2)
				(type solid)
			)
			(layer "F.SilkS")
		)
		(fp_line
			(start -5.0165 -6.35)
			(end -5.0165 6.731)
			(stroke
				(width 0.2)
				(type solid)
			)
			(layer "F.SilkS")
		)
		(fp_line
			(start -5.0165 6.731)
			(end 5.0165 6.731)
			(stroke
				(width 0.2)
				(type solid)
			)
			(layer "F.SilkS")
		)
		(fp_circle
			(center 5.0045 -7.2438)
			(end 5.1295 -7.2438)
			(stroke
				(width 0.25)
				(type solid)
			)
			(fill no)
			(layer "F.SilkS")
		)
		(fp_line
			(start 5.1165 -14.5306)
			(end 5.1165 6.831)
			(stroke
				(width 0.2)
				(type solid)
			)
			(layer "F.CrtYd")
		)
		(fp_line
			(start -5.1165 -14.5306)
			(end 5.1165 -14.5306)
			(stroke
				(width 0.2)
				(type solid)
			)
			(layer "F.CrtYd")
		)
		(fp_line
			(start -5.1165 -14.5306)
			(end -5.1165 6.831)
			(stroke
				(width 0.2)
				(type solid)
			)
			(layer "F.CrtYd")
		)
		(fp_line
			(start -5.1165 6.831)
			(end 5.1165 6.831)
			(stroke
				(width 0.2)
				(type solid)
			)
			(layer "F.CrtYd")
		)
		(fp_line
			(start 5.1165 -14.5306)
			(end 5.1165 6.831)
			(stroke
				(width 0.2)
				(type solid)
			)
			(layer "F.Fab")
		)
		(fp_line
			(start -5.1165 -14.5306)
			(end 5.1165 -14.5306)
			(stroke
				(width 0.2)
				(type solid)
			)
			(layer "F.Fab")
		)
		(fp_line
			(start -5.1165 -14.5306)
			(end -5.1165 6.831)
			(stroke
				(width 0.2)
				(type solid)
			)
			(layer "F.Fab")
		)
		(fp_line
			(start 0 -0.5)
			(end 0 0.5)
			(stroke
				(width 0.1)
				(type solid)
			)
			(layer "F.Fab")
		)
		(fp_line
			(start -0.5 0)
			(end 0.5 0)
			(stroke
				(width 0.1)
				(type solid)
			)
			(layer "F.Fab")
		)
		(fp_line
			(start -5.1165 6.831)
			(end 5.1165 6.831)
			(stroke
				(width 0.2)
				(type solid)
			)
			(layer "F.Fab")
		)
		(fp_text user "${REFERENCE}"
			(at -0.00185 -3.56555 90)
			(unlocked yes)
			(layer "F.Fab")
			(effects
				(font
					(face "Arial")
					(size 0.63 0.63)
					(thickness 0.1)
				)
				(justify left bottom)
			)
		)
		(pad "" np_thru_hole circle
			(at 0 -0.254 90)
			(size 2.9972 2.9972)
			(drill 2.9972)
			(layers "*.Cu" "*.Mask")
			(solder_mask_margin 0)
			(solder_paste_margin -1000)
			(thermal_bridge_angle 90)
		)
		(pad "1" thru_hole rect
			(at 2.0955 -7.5438 90)
			(size 2.75 2.75)
			(drill 1.8)
			(layers "*.Cu" "*.Mask")
			(remove_unused_layers no)
			(net "GND")
			(solder_mask_margin 0)
			(solder_paste_margin -1000)
		)
		(pad "2" thru_hole circle
			(at -2.0955 -7.5438 90)
			(size 2.75 2.75)
			(drill 1.8)
			(layers "*.Cu" "*.Mask")
			(remove_unused_layers no)
			(net "GND")
			(solder_mask_margin 0)
			(solder_paste_margin -1000)
			(thermal_bridge_angle 90)
		)
		(pad "3" thru_hole circle
			(at 2.0955 -13.0556 90)
			(size 2.75 2.75)
			(drill 1.8)
			(layers "*.Cu" "*.Mask")
			(remove_unused_layers no)
			(net "NetCR1_1")
			(solder_mask_margin 0)
			(solder_paste_margin -1000)
			(thermal_bridge_angle 90)
		)
		(pad "4" thru_hole circle
			(at -2.0955 -13.0556 90)
			(size 2.75 2.75)
			(drill 1.8)
			(layers "*.Cu" "*.Mask")
			(remove_unused_layers no)
			(net "NetCR1_1")
			(solder_mask_margin 0)
			(solder_paste_margin -1000)
			(thermal_bridge_angle 90)
		)
	)
	(footprint "Vault:RESC1005X40X25NL05T05"
		(layer "F.Cu")
		(at 192.0216 135.2162 180)
		(property "Reference" "R149"
			(at -0.8936 -0.890901 0)
			(unlocked yes)
			(layer "F.SilkS")
			(effects
				(font
					(size 0.762 0.762)
					(thickness 0.2032)
				)
			)
		)
		(property "Value" "DNI_27_1%_0402"
			(at -2.732271 10.270975 90)
			(unlocked yes)
			(layer "F.SilkS")
			(hide yes)
			(effects
				(font
					(size 0.762 0.762)
					(thickness 0.2032)
				)
			)
		)
		(sheetname "11-M2_RCB_MUX")
		(sheetfile "11-M2_RCB_MUX.kicad_sch")
		(duplicate_pad_numbers_are_jumpers no)
		(pad "1" smd rect
			(at -0.45 0 270)
			(size 0.55 0.55)
			(layers "F.Cu" "F.Mask" "F.Paste")
			(net "RCB_GPS2_RX")
		)
		(pad "2" smd rect
			(at 0.45 0 270)
			(size 0.55 0.55)
			(layers "F.Cu" "F.Mask" "F.Paste")
			(net "GPS2_RX")
		)
	)
	(footprint "Vault:RESC1005X40X25LL05T10"
		(layer "F.Cu")
		(at 141.0216 103.9162 180)
		(property "Reference" "R104"
			(at 1.9714 0.173079 0)
			(unlocked yes)
			(layer "F.SilkS")
			(effects
				(font
					(size 0.762 0.762)
					(thickness 0.2286)
				)
			)
		)
		(property "Value" "DNI_49.9_1%_0402"
			(at -2.579871 11.74372 90)
			(unlocked yes)
			(layer "F.SilkS")
			(hide yes)
			(effects
				(font
					(size 0.762 0.762)
					(thickness 0.2286)
				)
			)
		)
		(sheetname "09-USBUart_PPSMUX_UARTMUX")
		(sheetfile "09-USBUart_PPSMUX_UARTMUX.kicad_sch")
		(duplicate_pad_numbers_are_jumpers no)
		(pad "1" smd rect
			(at -0.375 0 270)
			(size 0.45 0.5)
			(layers "F.Cu" "F.Mask" "F.Paste")
			(net "FPGA_MAC_PPS_OUT-")
		)
		(pad "2" smd rect
			(at 0.375 0 270)
			(size 0.45 0.5)
			(layers "F.Cu" "F.Mask" "F.Paste")
			(net "MAC_PPS_OUT")
		)
	)
	(footprint "Vault:AMPH-901-143-6RFX_V"
		(layer "F.Cu")
		(at 69.9716 122.0782 180)
		(property "Reference" "AN3"
			(at 0.85 3.868655 0)
			(unlocked yes)
			(layer "F.SilkS")
			(effects
				(font
					(size 0.762 0.762)
					(thickness 0.2286)
				)
				(justify left bottom)
			)
		)
		(property "Value" "RF2-49B-T-00-50-G-HDW"
			(at 4.6101 -1.960245 0)
			(unlocked yes)
			(layer "F.SilkS")
			(hide yes)
			(effects
				(font
					(size 0.762 0.762)
					(thickness 0.2286)
				)
				(justify left bottom)
			)
		)
		(sheetname "01-USER_IO")
		(sheetfile "01-USER_IO.kicad_sch")
		(duplicate_pad_numbers_are_jumpers no)
		(fp_line
			(start 3.5 -1.38)
			(end 3.5 1.38)
			(stroke
				(width 0.2)
				(type solid)
			)
			(layer "F.SilkS")
		)
		(fp_line
			(start 1.38 3.5)
			(end -1.38 3.5)
			(stroke
				(width 0.2)
				(type solid)
			)
			(layer "F.SilkS")
		)
		(fp_line
			(start 1.38 -3.5)
			(end -1.38 -3.5)
			(stroke
				(width 0.2)
				(type solid)
			)
			(layer "F.SilkS")
		)
		(fp_line
			(start -3.5 -1.38)
			(end -3.5 1.38)
			(stroke
				(width 0.2)
				(type solid)
			)
			(layer "F.SilkS")
		)
		(pad "1" thru_hole rect
			(at 0 0 180)
			(size 2 2)
			(drill 1.5)
			(layers "*.Cu" "*.Mask")
			(remove_unused_layers no)
			(net "NetAN3_1")
		)
		(pad "2" thru_hole circle
			(at -2.54 -2.54 180)
			(size 2.2 2.2)
			(drill 1.7)
			(layers "*.Cu" "*.Mask")
			(remove_unused_layers no)
			(net "GND")
			(thermal_bridge_angle 90)
		)
		(pad "3" thru_hole circle
			(at -2.54 2.54 180)
			(size 2.2 2.2)
			(drill 1.7)
			(layers "*.Cu" "*.Mask")
			(remove_unused_layers no)
			(net "GND")
			(thermal_bridge_angle 90)
		)
		(pad "4" thru_hole circle
			(at 2.54 2.54 180)
			(size 2.2 2.2)
			(drill 1.7)
			(layers "*.Cu" "*.Mask")
			(remove_unused_layers no)
			(net "GND")
			(thermal_bridge_angle 90)
		)
		(pad "5" thru_hole circle
			(at 2.54 -2.54 180)
			(size 2.2 2.2)
			(drill 1.7)
			(layers "*.Cu" "*.Mask")
			(remove_unused_layers no)
			(net "GND")
			(thermal_bridge_angle 90)
		)
	)
	(footprint "Vault:RESC1005X40X25LL05T10"
		(layer "F.Cu")
		(at 196.9216 134.9162)
		(property "Reference" "R145"
			(at 1.5032 0.826921 0)
			(unlocked yes)
			(layer "F.SilkS")
			(effects
				(font
					(size 0.762 0.762)
					(thickness 0.2032)
				)
			)
		)
		(property "Value" "49.9_1%_0402"
			(at -2.579881 8.798275 270)
			(unlocked yes)
			(layer "F.SilkS")
			(hide yes)
			(effects
				(font
					(size 0.762 0.762)
					(thickness 0.2032)
				)
			)
		)
		(sheetname "11-M2_RCB_MUX")
		(sheetfile "11-M2_RCB_MUX.kicad_sch")
		(duplicate_pad_numbers_are_jumpers no)
		(pad "1" smd rect
			(at -0.375 0 90)
			(size 0.45 0.5)
			(layers "F.Cu" "F.Mask" "F.Paste")
			(net "NetR145_1")
		)
		(pad "2" smd rect
			(at 0.375 0 90)
			(size 0.45 0.5)
			(layers "F.Cu" "F.Mask" "F.Paste")
			(net "GPS2_TP1")
		)
	)
	(footprint "Vault:RESC1005X40X25NL05T05"
		(layer "F.Cu")
		(at 110.5216 51.0162 90)
		(property "Reference" "R162"
			(at -0.5968 8.426931 90)
			(unlocked yes)
			(layer "F.SilkS")
			(effects
				(font
					(size 0.762 0.762)
					(thickness 0.2032)
				)
			)
		)
		(property "Value" "DNI_27_1%_0402"
			(at -2.732271 10.270965 0)
			(unlocked yes)
			(layer "F.SilkS")
			(hide yes)
			(effects
				(font
					(size 0.762 0.762)
					(thickness 0.2032)
				)
			)
		)
		(sheetname "11-M2_RCB_MUX")
		(sheetfile "11-M2_RCB_MUX.kicad_sch")
		(duplicate_pad_numbers_are_jumpers no)
		(pad "1" smd rect
			(at -0.45 0 180)
			(size 0.55 0.55)
			(layers "F.Cu" "F.Mask" "F.Paste")
			(net "M2_GPS1_TX")
		)
		(pad "2" smd rect
			(at 0.45 0 180)
			(size 0.55 0.55)
			(layers "F.Cu" "F.Mask" "F.Paste")
			(net "GPS1_TX")
		)
	)
	(footprint ""
		(layer "F.Cu")
		(at 180.0216 65.0162)
		(property "Reference" ""
			(at 0 0 0)
			(layer "F.SilkS")
			(effects
				(font
					(size 1.27 1.27)
				)
			)
		)
		(property "Value" ""
			(at 0 0 0)
			(layer "F.Fab")
			(effects
				(font
					(size 1.27 1.27)
				)
			)
		)
		(duplicate_pad_numbers_are_jumpers no)
		(pad "2" thru_hole circle
			(at 0 0)
			(size 6.5 6.5)
			(drill 4.2)
			(layers "*.Cu" "*.Mask")
			(remove_unused_layers no)
			(net "GND")
			(thermal_bridge_angle 90)
		)
	)
	(footprint "Vault:RESC1005X40X25LL05T10"
		(layer "F.Cu")
		(at 190.4216 133.9162 -90)
		(property "Reference" "R146"
			(at 2.5032 0.226931 270)
			(unlocked yes)
			(layer "F.SilkS")
			(effects
				(font
					(size 0.762 0.762)
					(thickness 0.2032)
				)
			)
		)
		(property "Value" "49.9_1%_0402"
			(at -2.579871 8.798265 180)
			(unlocked yes)
			(layer "F.SilkS")
			(hide yes)
			(effects
				(font
					(size 0.762 0.762)
					(thickness 0.2032)
				)
			)
		)
		(sheetname "11-M2_RCB_MUX")
		(sheetfile "11-M2_RCB_MUX.kicad_sch")
		(duplicate_pad_numbers_are_jumpers no)
		(pad "1" smd rect
			(at -0.375 0)
			(size 0.45 0.5)
			(layers "F.Cu" "F.Mask" "F.Paste")
			(net "NetR146_1")
		)
		(pad "2" smd rect
			(at 0.375 0)
			(size 0.45 0.5)
			(layers "F.Cu" "F.Mask" "F.Paste")
			(net "GPS2_RX")
		)
	)
	(footprint "Vault:FP-2199119-3-MFG"
		(locked yes)
		(layer "F.Cu")
		(at 208.2216 125.4162 180)
		(property "Reference" "J45"
			(at -11.873069 1.0968 270)
			(unlocked yes)
			(layer "F.SilkS")
			(effects
				(font
					(size 0.762 0.762)
					(thickness 0.2032)
				)
			)
		)
		(property "Value" "2199119-3"
			(at -12.739871 1.153695 90)
			(unlocked yes)
			(layer "F.SilkS")
			(hide yes)
			(effects
				(font
					(size 0.762 0.762)
					(thickness 0.2032)
				)
			)
		)
		(sheetname "10-M2_GPS")
		(sheetfile "10-M2_GPS.kicad_sch")
		(duplicate_pad_numbers_are_jumpers no)
		(fp_line
			(start 11 3.975)
			(end 9.525 3.975)
			(stroke
				(width 0.2)
				(type solid)
			)
			(layer "F.SilkS")
		)
		(fp_line
			(start 11 2.55)
			(end 11 3.975)
			(stroke
				(width 0.2)
				(type solid)
			)
			(layer "F.SilkS")
		)
		(fp_line
			(start 11 -1.375)
			(end 11 0.2)
			(stroke
				(width 0.2)
				(type solid)
			)
			(layer "F.SilkS")
		)
		(fp_line
			(start -4.775 -3.975)
			(end -6.225 -3.975)
			(stroke
				(width 0.2)
				(type solid)
			)
			(layer "F.SilkS")
		)
		(fp_line
			(start -5.025 3.975)
			(end -6.475 3.975)
			(stroke
				(width 0.2)
				(type solid)
			)
			(layer "F.SilkS")
		)
		(fp_line
			(start -9.525 3.975)
			(end -11 3.975)
			(stroke
				(width 0.2)
				(type solid)
			)
			(layer "F.SilkS")
		)
		(fp_line
			(start -11 -1.375)
			(end -11 3.975)
			(stroke
				(width 0.2)
				(type solid)
			)
			(layer "F.SilkS")
		)
		(fp_circle
			(center -9.275 -5.275)
			(end -9.275 -5.15)
			(stroke
				(width 0.25)
				(type solid)
			)
			(fill no)
			(layer "F.SilkS")
		)
		(fp_line
			(start 11.1 4.525)
			(end -11.1 4.525)
			(stroke
				(width 0.2)
				(type solid)
			)
			(layer "F.CrtYd")
		)
		(fp_line
			(start 11.1 -4.775)
			(end 11.1 4.525)
			(stroke
				(width 0.2)
				(type solid)
			)
			(layer "F.CrtYd")
		)
		(fp_line
			(start 11.1 -4.775)
			(end -11.1 -4.775)
			(stroke
				(width 0.2)
				(type solid)
			)
			(layer "F.CrtYd")
		)
		(fp_line
			(start -11.1 -4.775)
			(end -11.1 4.525)
			(stroke
				(width 0.2)
				(type solid)
			)
			(layer "F.CrtYd")
		)
		(fp_line
			(start 11.1 4.525)
			(end -11.1 4.525)
			(stroke
				(width 0.2)
				(type solid)
			)
			(layer "F.Fab")
		)
		(fp_line
			(start 11.1 -4.775)
			(end 11.1 4.525)
			(stroke
				(width 0.2)
				(type solid)
			)
			(layer "F.Fab")
		)
		(fp_line
			(start 11.1 -4.775)
			(end -11.1 -4.775)
			(stroke
				(width 0.2)
				(type solid)
			)
			(layer "F.Fab")
		)
		(fp_line
			(start 0.5 0)
			(end -0.5 0)
			(stroke
				(width 0.1)
				(type solid)
			)
			(layer "F.Fab")
		)
		(fp_line
			(start 0 -0.5)
			(end 0 0.5)
			(stroke
				(width 0.1)
				(type solid)
			)
			(layer "F.Fab")
		)
		(fp_line
			(start -11.1 -4.775)
			(end -11.1 4.525)
			(stroke
				(width 0.2)
				(type solid)
			)
			(layer "F.Fab")
		)
		(fp_text user "${REFERENCE}"
			(at -0.00185 0.15925 180)
			(unlocked yes)
			(layer "F.Fab")
			(effects
				(font
					(face "Arial")
					(size 0.63 0.63)
					(thickness 0.1)
				)
				(justify left bottom)
			)
		)
		(pad "" np_thru_hole circle
			(at -10 1.375 180)
			(size 1.1 1.1)
			(drill 1.1)
			(layers "*.Cu" "*.Mask")
			(solder_mask_margin 0)
			(solder_paste_margin -1000)
			(thermal_bridge_angle 90)
		)
		(pad "" np_thru_hole circle
			(at 10 1.375 180)
			(size 1.6 1.6)
			(drill 1.6)
			(layers "*.Cu" "*.Mask")
			(solder_mask_margin 0)
			(solder_paste_margin -1000)
			(thermal_bridge_angle 90)
		)
		(pad "1" smd rect
			(at -9.25 -3.9 180)
			(size 0.3 1.55)
			(layers "F.Cu" "F.Mask" "F.Paste")
			(solder_mask_margin 0)
			(solder_paste_margin 0)
		)
		(pad "2" smd rect
			(at -9 3.65 180)
			(size 0.3 1.55)
			(layers "F.Cu" "F.Mask" "F.Paste")
			(net "GNSS2_P3V3")
			(solder_mask_margin 0)
			(solder_paste_margin 0)
		)
		(pad "3" smd rect
			(at -8.75 -3.9 180)
			(size 0.3 1.55)
			(layers "F.Cu" "F.Mask" "F.Paste")
			(net "GND")
			(solder_mask_margin 0)
			(solder_paste_margin 0)
		)
		(pad "4" smd rect
			(at -8.5 3.65 180)
			(size 0.3 1.55)
			(layers "F.Cu" "F.Mask" "F.Paste")
			(net "GNSS2_P3V3")
			(solder_mask_margin 0)
			(solder_paste_margin 0)
		)
		(pad "5" smd rect
			(at -8.25 -3.9 180)
			(size 0.3 1.55)
			(layers "F.Cu" "F.Mask" "F.Paste")
			(net "GND")
			(solder_mask_margin 0)
			(solder_paste_margin 0)
		)
		(pad "6" smd rect
			(at -8 3.65 180)
			(size 0.3 1.55)
			(layers "F.Cu" "F.Mask" "F.Paste")
			(solder_mask_margin 0)
			(solder_paste_margin 0)
		)
		(pad "7" smd rect
			(at -7.75 -3.9 180)
			(size 0.3 1.55)
			(layers "F.Cu" "F.Mask" "F.Paste")
			(solder_mask_margin 0)
			(solder_paste_margin 0)
		)
		(pad "8" smd rect
			(at -7.5 3.65 180)
			(size 0.3 1.55)
			(layers "F.Cu" "F.Mask" "F.Paste")
			(solder_mask_margin 0)
			(solder_paste_margin 0)
		)
		(pad "9" smd rect
			(at -7.25 -3.9 180)
			(size 0.3 1.55)
			(layers "F.Cu" "F.Mask" "F.Paste")
			(solder_mask_margin 0)
			(solder_paste_margin 0)
		)
		(pad "10" smd rect
			(at -7 3.65 180)
			(size 0.3 1.55)
			(layers "F.Cu" "F.Mask" "F.Paste")
			(solder_mask_margin 0)
			(solder_paste_margin 0)
		)
		(pad "11" smd rect
			(at -6.75 -3.9 180)
			(size 0.3 1.55)
			(layers "F.Cu" "F.Mask" "F.Paste")
			(net "GND")
			(solder_mask_margin 0)
			(solder_paste_margin 0)
		)
		(pad "20" smd rect
			(at -4.5 3.65 180)
			(size 0.3 1.55)
			(layers "F.Cu" "F.Mask" "F.Paste")
			(net "M2_GPS2_PIN11")
			(solder_mask_margin 0)
			(solder_paste_margin 0)
		)
		(pad "21" smd rect
			(at -4.25 -3.9 180)
			(size 0.3 1.55)
			(layers "F.Cu" "F.Mask" "F.Paste")
			(solder_mask_margin 0)
			(solder_paste_margin 0)
		)
		(pad "22" smd rect
			(at -4 3.65 180)
			(size 0.3 1.55)
			(layers "F.Cu" "F.Mask" "F.Paste")
			(net "M2_GPS2_PIN12")
			(solder_mask_margin 0)
			(solder_paste_margin 0)
		)
		(pad "23" smd rect
			(at -3.75 -3.9 180)
			(size 0.3 1.55)
			(layers "F.Cu" "F.Mask" "F.Paste")
			(solder_mask_margin 0)
			(solder_paste_margin 0)
		)
		(pad "24" smd rect
			(at -3.5 3.65 180)
			(size 0.3 1.55)
			(layers "F.Cu" "F.Mask" "F.Paste")
			(solder_mask_margin 0)
			(solder_paste_margin 0)
		)
		(pad "25" smd rect
			(at -3.25 -3.9 180)
			(size 0.3 1.55)
			(layers "F.Cu" "F.Mask" "F.Paste")
			(solder_mask_margin 0)
			(solder_paste_margin 0)
		)
		(pad "26" smd rect
			(at -3 3.65 180)
			(size 0.3 1.55)
			(layers "F.Cu" "F.Mask" "F.Paste")
			(solder_mask_margin 0)
			(solder_paste_margin 0)
		)
		(pad "27" smd rect
			(at -2.75 -3.9 180)
			(size 0.3 1.55)
			(layers "F.Cu" "F.Mask" "F.Paste")
			(net "GND")
			(solder_mask_margin 0)
			(solder_paste_margin 0)
		)
		(pad "28" smd rect
			(at -2.5 3.65 180)
			(size 0.3 1.55)
			(layers "F.Cu" "F.Mask" "F.Paste")
			(solder_mask_margin 0)
			(solder_paste_margin 0)
		)
		(pad "29" smd rect
			(at -2.25 -3.9 180)
			(size 0.3 1.55)
			(layers "F.Cu" "F.Mask" "F.Paste")
			(solder_mask_margin 0)
			(solder_paste_margin 0)
		)
		(pad "30" smd rect
			(at -2 3.65 180)
			(size 0.3 1.55)
			(layers "F.Cu" "F.Mask" "F.Paste")
			(solder_mask_margin 0)
			(solder_paste_margin 0)
		)
		(pad "31" smd rect
			(at -1.75 -3.9 180)
			(size 0.3 1.55)
			(layers "F.Cu" "F.Mask" "F.Paste")
			(solder_mask_margin 0)
			(solder_paste_margin 0)
		)
		(pad "32" smd rect
			(at -1.5 3.65 180)
			(size 0.3 1.55)
			(layers "F.Cu" "F.Mask" "F.Paste")
			(solder_mask_margin 0)
			(solder_paste_margin 0)
		)
		(pad "33" smd rect
			(at -1.25 -3.9 180)
			(size 0.3 1.55)
			(layers "F.Cu" "F.Mask" "F.Paste")
			(net "GND")
			(solder_mask_margin 0)
			(solder_paste_margin 0)
		)
		(pad "34" smd rect
			(at -1 3.65 180)
			(size 0.3 1.55)
			(layers "F.Cu" "F.Mask" "F.Paste")
			(solder_mask_margin 0)
			(solder_paste_margin 0)
		)
		(pad "35" smd rect
			(at -0.75 -3.9 180)
			(size 0.3 1.55)
			(layers "F.Cu" "F.Mask" "F.Paste")
			(net "NetJ45_35")
			(solder_mask_margin 0)
			(solder_paste_margin 0)
		)
		(pad "36" smd rect
			(at -0.5 3.65 180)
			(size 0.3 1.55)
			(layers "F.Cu" "F.Mask" "F.Paste")
			(solder_mask_margin 0)
			(solder_paste_margin 0)
		)
		(pad "37" smd rect
			(at -0.25 -3.9 180)
			(size 0.3 1.55)
			(layers "F.Cu" "F.Mask" "F.Paste")
			(solder_mask_margin 0)
			(solder_paste_margin 0)
		)
		(pad "38" smd rect
			(at 0 3.65 180)
			(size 0.3 1.55)
			(layers "F.Cu" "F.Mask" "F.Paste")
			(solder_mask_margin 0)
			(solder_paste_margin 0)
		)
		(pad "39" smd rect
			(at 0.25 -3.9 180)
			(size 0.3 1.55)
			(layers "F.Cu" "F.Mask" "F.Paste")
			(net "GND")
			(solder_mask_margin 0)
			(solder_paste_margin 0)
		)
		(pad "40" smd rect
			(at 0.5 3.65 180)
			(size 0.3 1.55)
			(layers "F.Cu" "F.Mask" "F.Paste")
			(net "GPS2_PIN13")
			(solder_mask_margin 0)
			(solder_paste_margin 0)
		)
		(pad "41" smd rect
			(at 0.75 -3.9 180)
			(size 0.3 1.55)
			(layers "F.Cu" "F.Mask" "F.Paste")
			(solder_mask_margin 0)
			(solder_paste_margin 0)
		)
		(pad "42" smd rect
			(at 1 3.65 180)
			(size 0.3 1.55)
			(layers "F.Cu" "F.Mask" "F.Paste")
			(net "GPS2_PIN14")
			(solder_mask_margin 0)
			(solder_paste_margin 0)
		)
		(pad "43" smd rect
			(at 1.25 -3.9 180)
			(size 0.3 1.55)
			(layers "F.Cu" "F.Mask" "F.Paste")
			(solder_mask_margin 0)
			(solder_paste_margin 0)
		)
		(pad "44" smd rect
			(at 1.5 3.65 180)
			(size 0.3 1.55)
			(layers "F.Cu" "F.Mask" "F.Paste")
			(net "GPS2_PIN15")
			(solder_mask_margin 0)
			(solder_paste_margin 0)
		)
		(pad "45" smd rect
			(at 1.75 -3.9 180)
			(size 0.3 1.55)
			(layers "F.Cu" "F.Mask" "F.Paste")
			(net "GND")
			(solder_mask_margin 0)
			(solder_paste_margin 0)
		)
		(pad "46" smd rect
			(at 2 3.65 180)
			(size 0.3 1.55)
			(layers "F.Cu" "F.Mask" "F.Paste")
			(net "NetJ45_46")
			(solder_mask_margin 0)
			(solder_paste_margin 0)
		)
		(pad "47" smd rect
			(at 2.25 -3.9 180)
			(size 0.3 1.55)
			(layers "F.Cu" "F.Mask" "F.Paste")
			(solder_mask_margin 0)
			(solder_paste_margin 0)
		)
		(pad "48" smd rect
			(at 2.5 3.65 180)
			(size 0.3 1.55)
			(layers "F.Cu" "F.Mask" "F.Paste")
			(net "M2_GPS2_TP2")
			(solder_mask_margin 0)
			(solder_paste_margin 0)
		)
		(pad "49" smd rect
			(at 2.75 -3.9 180)
			(size 0.3 1.55)
			(layers "F.Cu" "F.Mask" "F.Paste")
			(solder_mask_margin 0)
			(solder_paste_margin 0)
		)
		(pad "50" smd rect
			(at 3 3.65 180)
			(size 0.3 1.55)
			(layers "F.Cu" "F.Mask" "F.Paste")
			(net "GPS2_RST")
			(solder_mask_margin 0)
			(solder_paste_margin 0)
		)
		(pad "51" smd rect
			(at 3.25 -3.9 180)
			(size 0.3 1.55)
			(layers "F.Cu" "F.Mask" "F.Paste")
			(net "GND")
			(solder_mask_margin 0)
			(solder_paste_margin 0)
		)
		(pad "52" smd rect
			(at 3.5 3.65 180)
			(size 0.3 1.55)
			(layers "F.Cu" "F.Mask" "F.Paste")
			(solder_mask_margin 0)
			(solder_paste_margin 0)
		)
		(pad "53" smd rect
			(at 3.75 -3.9 180)
			(size 0.3 1.55)
			(layers "F.Cu" "F.Mask" "F.Paste")
			(solder_mask_margin 0)
			(solder_paste_margin 0)
		)
		(pad "54" smd rect
			(at 4 3.65 180)
			(size 0.3 1.55)
			(layers "F.Cu" "F.Mask" "F.Paste")
			(solder_mask_margin 0)
			(solder_paste_margin 0)
		)
		(pad "55" smd rect
			(at 4.25 -3.9 180)
			(size 0.3 1.55)
			(layers "F.Cu" "F.Mask" "F.Paste")
			(solder_mask_margin 0)
			(solder_paste_margin 0)
		)
		(pad "56" smd rect
			(at 4.5 3.65 180)
			(size 0.3 1.55)
			(layers "F.Cu" "F.Mask" "F.Paste")
			(solder_mask_margin 0)
			(solder_paste_margin 0)
		)
		(pad "57" smd rect
			(at 4.75 -3.9 180)
			(size 0.3 1.55)
			(layers "F.Cu" "F.Mask" "F.Paste")
			(net "GND")
			(solder_mask_margin 0)
			(solder_paste_margin 0)
		)
		(pad "58" smd rect
			(at 5 3.65 180)
			(size 0.3 1.55)
			(layers "F.Cu" "F.Mask" "F.Paste")
			(solder_mask_margin 0)
			(solder_paste_margin 0)
		)
		(pad "59" smd rect
			(at 5.25 -3.9 180)
			(size 0.3 1.55)
			(layers "F.Cu" "F.Mask" "F.Paste")
			(solder_mask_margin 0)
			(solder_paste_margin 0)
		)
		(pad "60" smd rect
			(at 5.5 3.65 180)
			(size 0.3 1.55)
			(layers "F.Cu" "F.Mask" "F.Paste")
			(solder_mask_margin 0)
			(solder_paste_margin 0)
		)
		(pad "61" smd rect
			(at 5.75 -3.9 180)
			(size 0.3 1.55)
			(layers "F.Cu" "F.Mask" "F.Paste")
			(solder_mask_margin 0)
			(solder_paste_margin 0)
		)
		(pad "62" smd rect
			(at 6 3.65 180)
			(size 0.3 1.55)
			(layers "F.Cu" "F.Mask" "F.Paste")
			(net "M2_GPS2_RX")
			(solder_mask_margin 0)
			(solder_paste_margin 0)
		)
		(pad "63" smd rect
			(at 6.25 -3.9 180)
			(size 0.3 1.55)
			(layers "F.Cu" "F.Mask" "F.Paste")
			(solder_mask_margin 0)
			(solder_paste_margin 0)
		)
		(pad "64" smd rect
			(at 6.5 3.65 180)
			(size 0.3 1.55)
			(layers "F.Cu" "F.Mask" "F.Paste")
			(net "M2_GPS2_TX")
			(solder_mask_margin 0)
			(solder_paste_margin 0)
		)
		(pad "65" smd rect
			(at 6.75 -3.9 180)
			(size 0.3 1.55)
			(layers "F.Cu" "F.Mask" "F.Paste")
			(solder_mask_margin 0)
			(solder_paste_margin 0)
		)
		(pad "66" smd rect
			(at 7 3.65 180)
			(size 0.3 1.55)
			(layers "F.Cu" "F.Mask" "F.Paste")
			(solder_mask_margin 0)
			(solder_paste_margin 0)
		)
		(pad "67" smd rect
			(at 7.25 -3.9 180)
			(size 0.3 1.55)
			(layers "F.Cu" "F.Mask" "F.Paste")
			(net "GPS2_RST")
			(solder_mask_margin 0)
			(solder_paste_margin 0)
		)
		(pad "68" smd rect
			(at 7.5 3.65 180)
			(size 0.3 1.55)
			(layers "F.Cu" "F.Mask" "F.Paste")
			(solder_mask_margin 0)
			(solder_paste_margin 0)
		)
		(pad "69" smd rect
			(at 7.75 -3.9 180)
			(size 0.3 1.55)
			(layers "F.Cu" "F.Mask" "F.Paste")
			(solder_mask_margin 0)
			(solder_paste_margin 0)
		)
		(pad "70" smd rect
			(at 8 3.65 180)
			(size 0.3 1.55)
			(layers "F.Cu" "F.Mask" "F.Paste")
			(net "GNSS2_P3V3")
			(solder_mask_margin 0)
			(solder_paste_margin 0)
		)
		(pad "71" smd rect
			(at 8.25 -3.9 180)
			(size 0.3 1.55)
			(layers "F.Cu" "F.Mask" "F.Paste")
			(net "GND")
			(solder_mask_margin 0)
			(solder_paste_margin 0)
		)
		(pad "72" smd rect
			(at 8.5 3.65 180)
			(size 0.3 1.55)
			(layers "F.Cu" "F.Mask" "F.Paste")
			(net "GNSS2_P3V3")
			(solder_mask_margin 0)
			(solder_paste_margin 0)
		)
		(pad "73" smd rect
			(at 8.75 -3.9 180)
			(size 0.3 1.55)
			(layers "F.Cu" "F.Mask" "F.Paste")
			(net "GND")
			(solder_mask_margin 0)
			(solder_paste_margin 0)
		)
		(pad "74" smd rect
			(at 9 3.65 180)
			(size 0.3 1.55)
			(layers "F.Cu" "F.Mask" "F.Paste")
			(net "GNSS2_P3V3")
			(solder_mask_margin 0)
			(solder_paste_margin 0)
		)
		(pad "75" smd rect
			(at 9.25 -3.9 180)
			(size 0.3 1.55)
			(layers "F.Cu" "F.Mask" "F.Paste")
			(solder_mask_margin 0)
			(solder_paste_margin 0)
		)
		(pad "76" smd rect
			(at -10.35 -3.125 180)
			(size 1.2 2.75)
			(layers "F.Cu" "F.Mask" "F.Paste")
			(net "GND")
			(solder_mask_margin 0)
			(solder_paste_margin 0)
		)
		(pad "77" smd rect
			(at 10.35 -3.125 180)
			(size 1.2 2.75)
			(layers "F.Cu" "F.Mask" "F.Paste")
			(net "GND")
			(solder_mask_margin 0)
			(solder_paste_margin 0)
		)
	)
	(footprint "Vault:FP-MYMGK-12-MFG"
		(layer "F.Cu")
		(at 87.7216 59.3162 90)
		(property "Reference" "U5"
			(at -4.506655 -0.3 180)
			(unlocked yes)
			(layer "F.SilkS")
			(effects
				(font
					(size 0.762 0.762)
					(thickness 0.2286)
				)
				(justify left bottom)
			)
		)
		(property "Value" "DNI_MYMGK00506ERSR"
			(at -27.796575 6.8959 0)
			(unlocked yes)
			(layer "F.SilkS")
			(hide yes)
			(effects
				(font
					(size 0.762 0.762)
					(thickness 0.2286)
				)
				(justify left bottom)
			)
		)
		(sheetname "03-POWER")
		(sheetfile "03-POWER.kicad_sch")
		(duplicate_pad_numbers_are_jumpers no)
		(fp_line
			(start 3.825 -4.575)
			(end 3.825 4.575)
			(stroke
				(width 0.2)
				(type solid)
			)
			(layer "F.SilkS")
		)
		(fp_line
			(start 3.625 -4.575)
			(end 3.825 -4.575)
			(stroke
				(width 0.2)
				(type solid)
			)
			(layer "F.SilkS")
		)
		(fp_line
			(start -0.325 -4.575)
			(end 0.325 -4.575)
			(stroke
				(width 0.2)
				(type solid)
			)
			(layer "F.SilkS")
		)
		(fp_line
			(start -3.825 -4.575)
			(end -3.625 -4.575)
			(stroke
				(width 0.2)
				(type solid)
			)
			(layer "F.SilkS")
		)
		(fp_line
			(start -3.825 -4.575)
			(end -3.825 4.575)
			(stroke
				(width 0.2)
				(type solid)
			)
			(layer "F.SilkS")
		)
		(fp_line
			(start 3.625 4.575)
			(end 3.825 4.575)
			(stroke
				(width 0.2)
				(type solid)
			)
			(layer "F.SilkS")
		)
		(fp_line
			(start -0.325 4.575)
			(end 0.325 4.575)
			(stroke
				(width 0.2)
				(type solid)
			)
			(layer "F.SilkS")
		)
		(fp_line
			(start -3.825 4.575)
			(end -3.625 4.575)
			(stroke
				(width 0.2)
				(type solid)
			)
			(layer "F.SilkS")
		)
		(fp_circle
			(center -4.575 -3.625)
			(end -4.45 -3.625)
			(stroke
				(width 0.25)
				(type solid)
			)
			(fill no)
			(layer "F.SilkS")
		)
		(fp_line
			(start 4.325 -5.075)
			(end 4.325 5.075)
			(stroke
				(width 0.2)
				(type solid)
			)
			(layer "F.CrtYd")
		)
		(fp_line
			(start -4.325 -5.075)
			(end 4.325 -5.075)
			(stroke
				(width 0.2)
				(type solid)
			)
			(layer "F.CrtYd")
		)
		(fp_line
			(start -4.325 -5.075)
			(end -4.325 5.075)
			(stroke
				(width 0.2)
				(type solid)
			)
			(layer "F.CrtYd")
		)
		(fp_line
			(start -4.325 5.075)
			(end 4.325 5.075)
			(stroke
				(width 0.2)
				(type solid)
			)
			(layer "F.CrtYd")
		)
		(fp_line
			(start 4.325 -5.075)
			(end 4.325 5.075)
			(stroke
				(width 0.2)
				(type solid)
			)
			(layer "F.Fab")
		)
		(fp_line
			(start -4.325 -5.075)
			(end 4.325 -5.075)
			(stroke
				(width 0.2)
				(type solid)
			)
			(layer "F.Fab")
		)
		(fp_line
			(start -4.325 -5.075)
			(end -4.325 5.075)
			(stroke
				(width 0.2)
				(type solid)
			)
			(layer "F.Fab")
		)
		(fp_line
			(start 0 -0.5)
			(end 0 0.5)
			(stroke
				(width 0.1)
				(type solid)
			)
			(layer "F.Fab")
		)
		(fp_line
			(start -0.5 0)
			(end 0.5 0)
			(stroke
				(width 0.1)
				(type solid)
			)
			(layer "F.Fab")
		)
		(fp_line
			(start -4.325 5.075)
			(end 4.325 5.075)
			(stroke
				(width 0.2)
				(type solid)
			)
			(layer "F.Fab")
		)
		(fp_text user "${REFERENCE}"
			(at -0.00001 0.09602 90)
			(unlocked yes)
			(layer "F.Fab")
			(effects
				(font
					(face "Arial")
					(size 0.63 0.63)
					(thickness 0.1)
				)
				(justify left bottom)
			)
		)
		(pad "" smd custom
			(at -1.7 -0.75)
			(size 0.000001 0.000001)
			(layers "F.Cu" "F.Mask" "F.Paste")
			(solder_mask_margin 0)
			(solder_paste_margin 0)
			(thermal_bridge_angle 90)
			(options
				(clearance outline)
				(anchor circle)
			)
			(primitives
				(gr_poly
					(pts
						(xy 0 0) (xy 0 -1) (xy -0.9 -1) (xy -0.9 -0.45) (xy -0.45 0)
					)
					(width 0)
					(fill yes)
				)
			)
		)
		(pad "1" smd rect
			(at -2.75 -3.55 90)
			(size 1 1.4)
			(layers "F.Cu" "F.Mask" "F.Paste")
			(net "+12V")
			(solder_mask_margin 0)
			(solder_paste_margin 0)
		)
		(pad "2" smd rect
			(at -1.2 -3.55 90)
			(size 1 1.4)
			(layers "F.Cu" "F.Mask" "F.Paste")
			(net "+12V")
			(solder_mask_margin 0)
			(solder_paste_margin 0)
		)
		(pad "3" smd rect
			(at -2.75 -1.2 90)
			(size 1 0.9)
			(layers "F.Cu" "F.Mask" "F.Paste")
			(net "GND")
			(solder_mask_margin 0)
			(solder_paste_margin 0)
		)
		(pad "4" smd rect
			(at -2.75 0 90)
			(size 1 0.9)
			(layers "F.Cu" "F.Mask" "F.Paste")
			(net "NetR26_2")
			(solder_mask_margin 0)
			(solder_paste_margin 0)
		)
		(pad "5" smd rect
			(at -2.75 1.2 90)
			(size 1 0.9)
			(layers "F.Cu" "F.Mask" "F.Paste")
			(net "P5V_SENSE")
			(solder_mask_margin 0)
			(solder_paste_margin 0)
		)
		(pad "6" smd rect
			(at -2.75 3.55 90)
			(size 1 1.4)
			(layers "F.Cu" "F.Mask" "F.Paste")
			(net "P5V_SENSE")
			(solder_mask_margin 0)
			(solder_paste_margin 0)
		)
		(pad "7" smd rect
			(at -1.2 3.55 90)
			(size 1 1.4)
			(layers "F.Cu" "F.Mask" "F.Paste")
			(net "P5V_SENSE")
			(solder_mask_margin 0)
			(solder_paste_margin 0)
		)
		(pad "8" smd rect
			(at 1.2 3.55 90)
			(size 1 1.4)
			(layers "F.Cu" "F.Mask" "F.Paste")
			(net "GND")
			(solder_mask_margin 0)
			(solder_paste_margin 0)
		)
		(pad "9" smd rect
			(at 2.75 3.55 90)
			(size 1 1.4)
			(layers "F.Cu" "F.Mask" "F.Paste")
			(net "GND")
			(solder_mask_margin 0)
			(solder_paste_margin 0)
		)
		(pad "10" smd rect
			(at 2.75 1.2 90)
			(size 1 0.9)
			(layers "F.Cu" "F.Mask" "F.Paste")
			(net "GND")
			(solder_mask_margin 0)
			(solder_paste_margin 0)
		)
		(pad "11" smd rect
			(at 2.75 0 90)
			(size 1 0.9)
			(layers "F.Cu" "F.Mask" "F.Paste")
			(net "NetR9_2")
			(solder_mask_margin 0)
			(solder_paste_margin 0)
		)
		(pad "12" smd rect
			(at 2.75 -1.2 90)
			(size 1 0.9)
			(layers "F.Cu" "F.Mask" "F.Paste")
			(net "NetR6_2")
			(solder_mask_margin 0)
			(solder_paste_margin 0)
		)
		(pad "13" smd rect
			(at 2.75 -3.55 90)
			(size 1 1.4)
			(layers "F.Cu" "F.Mask" "F.Paste")
			(net "GND")
			(solder_mask_margin 0)
			(solder_paste_margin 0)
		)
		(pad "14" smd rect
			(at 1.2 -3.55 90)
			(size 1 1.4)
			(layers "F.Cu" "F.Mask" "F.Paste")
			(net "GND")
			(solder_mask_margin 0)
			(solder_paste_margin 0)
		)
		(pad "15" smd circle
			(at -1.15563 -1.16197 90)
			(size 0.74127 0.74127)
			(layers "F.Cu" "F.Mask" "F.Paste")
			(net "GND")
			(solder_mask_margin 0)
			(solder_paste_margin 0)
			(thermal_bridge_angle 90)
		)
		(pad "16" smd rect
			(at -1.2 0 90)
			(size 1 0.9)
			(layers "F.Cu" "F.Mask" "F.Paste")
			(net "GND")
			(solder_mask_margin 0)
			(solder_paste_margin 0)
		)
		(pad "17" smd rect
			(at -1.2 1.2 90)
			(size 1 0.9)
			(layers "F.Cu" "F.Mask" "F.Paste")
			(net "GND")
			(solder_mask_margin 0)
			(solder_paste_margin 0)
		)
		(pad "18" smd rect
			(at 0 -1.2 90)
			(size 1 0.9)
			(layers "F.Cu" "F.Mask" "F.Paste")
			(net "GND")
			(solder_mask_margin 0)
			(solder_paste_margin 0)
		)
		(pad "19" smd rect
			(at 0 0 90)
			(size 1 0.9)
			(layers "F.Cu" "F.Mask" "F.Paste")
			(net "GND")
			(solder_mask_margin 0)
			(solder_paste_margin 0)
		)
		(pad "20" smd rect
			(at 0 1.2 90)
			(size 1 0.9)
			(layers "F.Cu" "F.Mask" "F.Paste")
			(net "GND")
			(solder_mask_margin 0)
			(solder_paste_margin 0)
		)
		(pad "21" smd rect
			(at 1.2 -1.2 90)
			(size 1 0.9)
			(layers "F.Cu" "F.Mask" "F.Paste")
			(net "GND")
			(solder_mask_margin 0)
			(solder_paste_margin 0)
		)
		(pad "22" smd rect
			(at 1.2 0 90)
			(size 1 0.9)
			(layers "F.Cu" "F.Mask" "F.Paste")
			(net "GND")
			(solder_mask_margin 0)
			(solder_paste_margin 0)
		)
		(pad "23" smd rect
			(at 1.2 1.2 90)
			(size 1 0.9)
			(layers "F.Cu" "F.Mask" "F.Paste")
			(net "GND")
			(solder_mask_margin 0)
			(solder_paste_margin 0)
		)
	)
	(footprint "Vault:RESC1005X40X25NL10T10"
		(layer "F.Cu")
		(at 171.4216 118.8162 -90)
		(property "Reference" "R120"
			(at 2.7032 -0.045329 270)
			(unlocked yes)
			(layer "F.SilkS")
			(effects
				(font
					(size 0.762 0.762)
					(thickness 0.2032)
				)
			)
		)
		(property "Value" "4.7K_1%_0402"
			(at -2.732271 8.747475 180)
			(unlocked yes)
			(layer "F.SilkS")
			(hide yes)
			(effects
				(font
					(size 0.762 0.762)
					(thickness 0.2032)
				)
			)
		)
		(sheetname "08-DIPSwitches_I2C")
		(sheetfile "08-DIPSwitches_I2C.kicad_sch")
		(duplicate_pad_numbers_are_jumpers no)
		(pad "1" smd rect
			(at -0.425 0)
			(size 0.6 0.65)
			(layers "F.Cu" "F.Mask" "F.Paste")
			(net "MAC_I2C_SCL")
		)
		(pad "2" smd rect
			(at 0.425 0)
			(size 0.6 0.65)
			(layers "F.Cu" "F.Mask" "F.Paste")
			(net "+3.3V")
		)
	)
	(footprint "PI3A412ZHE:ZH16_PER"
		(layer "F.Cu")
		(at 110.4216 55.0162)
		(property "Reference" "U29"
			(at -1.3968 -2.373079 0)
			(unlocked yes)
			(layer "F.SilkS")
			(effects
				(font
					(size 0.762 0.762)
					(thickness 0.2032)
				)
			)
		)
		(property "Value" "PI3A412ZHE"
			(at 4.684 3.722871 0)
			(unlocked yes)
			(layer "F.SilkS")
			(hide yes)
			(effects
				(font
					(size 0.762 0.762)
					(thickness 0.2032)
				)
			)
		)
		(sheetname "11-M2_RCB_MUX")
		(sheetfile "11-M2_RCB_MUX.kicad_sch")
		(duplicate_pad_numbers_are_jumpers no)
		(fp_line
			(start -1.6764 -1.6764)
			(end -1.20974 -1.6764)
			(stroke
				(width 0.1524)
				(type solid)
			)
			(layer "F.SilkS")
		)
		(fp_line
			(start -1.6764 -1.20974)
			(end -1.6764 -1.6764)
			(stroke
				(width 0.1524)
				(type solid)
			)
			(layer "F.SilkS")
		)
		(fp_line
			(start -1.6764 1.6764)
			(end -1.6764 1.20974)
			(stroke
				(width 0.1524)
				(type solid)
			)
			(layer "F.SilkS")
		)
		(fp_line
			(start -1.6764 1.6764)
			(end -1.20974 1.6764)
			(stroke
				(width 0.1524)
				(type solid)
			)
			(layer "F.SilkS")
		)
		(fp_line
			(start 1.20974 -1.6764)
			(end 1.6764 -1.6764)
			(stroke
				(width 0.1524)
				(type solid)
			)
			(layer "F.SilkS")
		)
		(fp_line
			(start 1.20974 1.6764)
			(end 1.6764 1.6764)
			(stroke
				(width 0.1524)
				(type solid)
			)
			(layer "F.SilkS")
		)
		(fp_line
			(start 1.6764 -1.20974)
			(end 1.6764 -1.6764)
			(stroke
				(width 0.1524)
				(type solid)
			)
			(layer "F.SilkS")
		)
		(fp_line
			(start 1.6764 1.6764)
			(end 1.6764 1.20974)
			(stroke
				(width 0.1524)
				(type solid)
			)
			(layer "F.SilkS")
		)
		(fp_poly
			(pts
				(xy 2.1082 0.0595) (xy 2.3622 0.0595) (xy 2.3622 0.4405) (xy 2.1082 0.4405)
			)
			(stroke
				(width 0)
				(type default)
			)
			(fill yes)
			(layer "F.SilkS")
		)
		(fp_text user "*"
			(at -2.8067 -0.209425 0)
			(unlocked yes)
			(layer "F.SilkS")
			(effects
				(font
					(size 1.27 1.27)
					(thickness 0.0762)
				)
				(justify left bottom)
			)
		)
		(pad "1" smd rect
			(at -1.4478 -0.75 270)
			(size 0.254 0.8128)
			(layers "F.Cu" "F.Mask" "F.Paste")
			(net "RCB_GPS1_TX")
			(solder_mask_margin 0)
			(solder_paste_margin 0)
		)
		(pad "2" smd rect
			(at -1.4478 -0.25 270)
			(size 0.254 0.8128)
			(layers "F.Cu" "F.Mask" "F.Paste")
			(net "DIP_SW_GPS1_SEL")
			(solder_mask_margin 0)
			(solder_paste_margin 0)
		)
		(pad "3" smd rect
			(at -1.4478 0.25 270)
			(size 0.254 0.8128)
			(layers "F.Cu" "F.Mask" "F.Paste")
			(net "M2_GPS1_RX")
			(solder_mask_margin 0)
			(solder_paste_margin 0)
		)
		(pad "4" smd rect
			(at -1.4478 0.75 270)
			(size 0.254 0.8128)
			(layers "F.Cu" "F.Mask" "F.Paste")
			(net "NetR152_1")
			(solder_mask_margin 0)
			(solder_paste_margin 0)
		)
		(pad "5" smd rect
			(at -0.75 1.4478 180)
			(size 0.254 0.8128)
			(layers "F.Cu" "F.Mask" "F.Paste")
			(net "RCB_GPS1_RX")
			(solder_mask_margin 0)
			(solder_paste_margin 0)
		)
		(pad "6" smd rect
			(at -0.25 1.4478 180)
			(size 0.254 0.8128)
			(layers "F.Cu" "F.Mask" "F.Paste")
			(net "GND")
			(solder_mask_margin 0)
			(solder_paste_margin 0)
		)
		(pad "7" smd rect
			(at 0.25 1.4478 180)
			(size 0.254 0.8128)
			(layers "F.Cu" "F.Mask" "F.Paste")
			(net "M2_GPS1_TP1")
			(solder_mask_margin 0)
			(solder_paste_margin 0)
		)
		(pad "8" smd rect
			(at 0.75 1.4478 180)
			(size 0.254 0.8128)
			(layers "F.Cu" "F.Mask" "F.Paste")
			(net "NetR150_1")
			(solder_mask_margin 0)
			(solder_paste_margin 0)
		)
		(pad "9" smd rect
			(at 1.4478 0.75 270)
			(size 0.254 0.8128)
			(layers "F.Cu" "F.Mask" "F.Paste")
			(net "RCB_GPS1_TP1")
			(solder_mask_margin 0)
			(solder_paste_margin 0)
		)
		(pad "10" smd rect
			(at 1.4478 0.25 270)
			(size 0.254 0.8128)
			(layers "F.Cu" "F.Mask" "F.Paste")
			(net "DIP_SW_GPS1_SEL")
			(solder_mask_margin 0)
			(solder_paste_margin 0)
		)
		(pad "11" smd rect
			(at 1.4478 -0.25 270)
			(size 0.254 0.8128)
			(layers "F.Cu" "F.Mask" "F.Paste")
			(net "M2_GPS1_TP2")
			(solder_mask_margin 0)
			(solder_paste_margin 0)
		)
		(pad "12" smd rect
			(at 1.4478 -0.75 270)
			(size 0.254 0.8128)
			(layers "F.Cu" "F.Mask" "F.Paste")
			(net "NetR147_1")
			(solder_mask_margin 0)
			(solder_paste_margin 0)
		)
		(pad "13" smd rect
			(at 0.75 -1.4478 180)
			(size 0.254 0.8128)
			(layers "F.Cu" "F.Mask" "F.Paste")
			(net "RCB_GPS1_TP2")
			(solder_mask_margin 0)
			(solder_paste_margin 0)
		)
		(pad "14" smd rect
			(at 0.25 -1.4478 180)
			(size 0.254 0.8128)
			(layers "F.Cu" "F.Mask" "F.Paste")
			(net "+3.3V")
			(solder_mask_margin 0)
			(solder_paste_margin 0)
		)
		(pad "15" smd rect
			(at -0.25 -1.4478 180)
			(size 0.254 0.8128)
			(layers "F.Cu" "F.Mask" "F.Paste")
			(net "M2_GPS1_TX")
			(solder_mask_margin 0)
			(solder_paste_margin 0)
		)
		(pad "16" smd rect
			(at -0.75 -1.4478 180)
			(size 0.254 0.8128)
			(layers "F.Cu" "F.Mask" "F.Paste")
			(net "NetR144_1")
			(solder_mask_margin 0)
			(solder_paste_margin 0)
		)
		(pad "17" smd rect
			(at 0 0)
			(size 1.8034 1.8034)
			(layers "F.Cu" "F.Mask" "F.Paste")
			(net "GND")
			(solder_mask_margin 0)
			(solder_paste_margin 0)
		)
	)
	(footprint "MUN12AD06-SM:MUN12AD06-SM_CYN"
		(layer "F.Cu")
		(at 179.3216 84.59122 180)
		(property "Reference" "U24"
			(at -1.26218 4.335689 0)
			(unlocked yes)
			(layer "F.SilkS")
			(effects
				(font
					(size 0.762 0.762)
					(thickness 0.2032)
				)
			)
		)
		(property "Value" "MUN12AD06-SM"
			(at 5.027645 -0.734819 180)
			(unlocked yes)
			(layer "F.SilkS")
			(hide yes)
			(effects
				(font
					(size 0.762 0.762)
					(thickness 0.2032)
				)
			)
		)
		(sheetname "03-POWER")
		(sheetfile "03-POWER.kicad_sch")
		(duplicate_pad_numbers_are_jumpers no)
		(fp_line
			(start 3.1242 3.1242)
			(end 2.00688 3.1242)
			(stroke
				(width 0.1524)
				(type solid)
			)
			(layer "F.SilkS")
		)
		(fp_line
			(start 3.1242 2.00688)
			(end 3.1242 3.1242)
			(stroke
				(width 0.1524)
				(type solid)
			)
			(layer "F.SilkS")
		)
		(fp_line
			(start 3.1242 -3.1242)
			(end 3.1242 -2.00687)
			(stroke
				(width 0.1524)
				(type solid)
			)
			(layer "F.SilkS")
		)
		(fp_line
			(start 3.1242 -3.1242)
			(end 2.00688 -3.1242)
			(stroke
				(width 0.1524)
				(type solid)
			)
			(layer "F.SilkS")
		)
		(fp_line
			(start -2.00688 3.1242)
			(end -3.1242 3.1242)
			(stroke
				(width 0.1524)
				(type solid)
			)
			(layer "F.SilkS")
		)
		(fp_line
			(start -2.00688 -3.1242)
			(end -3.1242 -3.1242)
			(stroke
				(width 0.1524)
				(type solid)
			)
			(layer "F.SilkS")
		)
		(fp_line
			(start -3.1242 2.00688)
			(end -3.1242 3.1242)
			(stroke
				(width 0.1524)
				(type solid)
			)
			(layer "F.SilkS")
		)
		(fp_line
			(start -3.1242 -3.1242)
			(end -3.1242 -2.00687)
			(stroke
				(width 0.1524)
				(type solid)
			)
			(layer "F.SilkS")
		)
		(fp_poly
			(pts
				(xy 1.7905 3.1496) (xy 1.4095 3.1496) (xy 1.4095 3.4036) (xy 1.7905 3.4036)
			)
			(stroke
				(width 0)
				(type default)
			)
			(fill yes)
			(layer "F.SilkS")
		)
		(fp_poly
			(pts
				(xy -1.4095 -3.1496) (xy -1.7905 -3.1496) (xy -1.7905 -3.4036) (xy -1.4095 -3.4036)
			)
			(stroke
				(width 0)
				(type default)
			)
			(fill yes)
			(layer "F.SilkS")
		)
		(fp_text user "*"
			(at -3.8481 -0.809415 180)
			(unlocked yes)
			(layer "F.SilkS")
			(effects
				(font
					(size 1.27 1.27)
					(thickness 0.0762)
				)
				(justify left bottom)
			)
		)
		(pad "1" smd rect
			(at -2.6416 -1.59999 90)
			(size 0.3302 0.508)
			(layers "F.Cu" "F.Mask" "F.Paste")
			(net "+12V")
			(solder_mask_margin 0)
			(solder_paste_margin 0)
		)
		(pad "2" smd rect
			(at -2.6416 -0.8 90)
			(size 0.3302 0.508)
			(layers "F.Cu" "F.Mask" "F.Paste")
			(net "P3V3_MUN_PHASE")
			(solder_mask_margin 0)
			(solder_paste_margin 0)
		)
		(pad "3" smd rect
			(at -2.6416 0 90)
			(size 0.3302 0.508)
			(layers "F.Cu" "F.Mask" "F.Paste")
			(net "P3V3_MUN_PHASE")
			(solder_mask_margin 0)
			(solder_paste_margin 0)
		)
		(pad "4" smd rect
			(at -2.6416 0.80001 90)
			(size 0.3302 0.508)
			(layers "F.Cu" "F.Mask" "F.Paste")
			(net "P3V3_MUN_PHASE")
			(solder_mask_margin 0)
			(solder_paste_margin 0)
		)
		(pad "5" smd rect
			(at -2.6416 1.6 90)
			(size 0.3302 0.508)
			(layers "F.Cu" "F.Mask" "F.Paste")
			(net "GND")
			(solder_mask_margin 0)
			(solder_paste_margin 0)
		)
		(pad "6" smd rect
			(at -1.6 2.6416)
			(size 0.3302 0.508)
			(layers "F.Cu" "F.Mask" "F.Paste")
			(net "GND")
			(solder_mask_margin 0)
			(solder_paste_margin 0)
		)
		(pad "7" smd rect
			(at -0.8 2.6416)
			(size 0.3302 0.508)
			(layers "F.Cu" "F.Mask" "F.Paste")
			(net "GND")
			(solder_mask_margin 0)
			(solder_paste_margin 0)
		)
		(pad "8" smd rect
			(at 0 2.6416)
			(size 0.3302 0.508)
			(layers "F.Cu" "F.Mask" "F.Paste")
			(net "NetR69_2")
			(solder_mask_margin 0)
			(solder_paste_margin 0)
		)
		(pad "9" smd rect
			(at 0.8 2.6416)
			(size 0.3302 0.508)
			(layers "F.Cu" "F.Mask" "F.Paste")
			(net "NetR70_1")
			(solder_mask_margin 0)
			(solder_paste_margin 0)
		)
		(pad "10" smd rect
			(at 1.6 2.6416)
			(size 0.3302 0.508)
			(layers "F.Cu" "F.Mask" "F.Paste")
			(net "P3V3_SENSE")
			(solder_mask_margin 0)
			(solder_paste_margin 0)
		)
		(pad "11" smd rect
			(at 2.6416 1.6 90)
			(size 0.3302 0.508)
			(layers "F.Cu" "F.Mask" "F.Paste")
			(net "P3V3_SENSE")
			(solder_mask_margin 0)
			(solder_paste_margin 0)
		)
		(pad "12" smd rect
			(at 2.6416 0.80001 90)
			(size 0.3302 0.508)
			(layers "F.Cu" "F.Mask" "F.Paste")
			(net "P3V3_SENSE")
			(solder_mask_margin 0)
			(solder_paste_margin 0)
		)
		(pad "13" smd rect
			(at 2.6416 0 90)
			(size 0.3302 0.508)
			(layers "F.Cu" "F.Mask" "F.Paste")
			(net "P3V3_SENSE")
			(solder_mask_margin 0)
			(solder_paste_margin 0)
		)
		(pad "14" smd rect
			(at 2.6416 -0.8 90)
			(size 0.3302 0.508)
			(layers "F.Cu" "F.Mask" "F.Paste")
			(net "P3V3_SENSE")
			(solder_mask_margin 0)
			(solder_paste_margin 0)
		)
		(pad "15" smd rect
			(at 2.6416 -1.59999 90)
			(size 0.3302 0.508)
			(layers "F.Cu" "F.Mask" "F.Paste")
			(net "GND")
			(solder_mask_margin 0)
			(solder_paste_margin 0)
		)
		(pad "16" smd rect
			(at 1.6 -2.6416)
			(size 0.3302 0.508)
			(layers "F.Cu" "F.Mask" "F.Paste")
			(net "P3V3_MUN_FB")
			(solder_mask_margin 0)
			(solder_paste_margin 0)
		)
		(pad "17" smd rect
			(at 0.8 -2.6416)
			(size 0.3302 0.508)
			(layers "F.Cu" "F.Mask" "F.Paste")
			(net "P3V3_MUN_VCC")
			(solder_mask_margin 0)
			(solder_paste_margin 0)
		)
		(pad "18" smd rect
			(at 0 -2.6416)
			(size 0.3302 0.508)
			(layers "F.Cu" "F.Mask" "F.Paste")
			(solder_mask_margin 0)
			(solder_paste_margin 0)
		)
		(pad "19" smd rect
			(at -0.8 -2.6416)
			(size 0.3302 0.508)
			(layers "F.Cu" "F.Mask" "F.Paste")
			(net "+12V")
			(solder_mask_margin 0)
			(solder_paste_margin 0)
		)
		(pad "20" smd rect
			(at -1.6 -2.6416)
			(size 0.3302 0.508)
			(layers "F.Cu" "F.Mask" "F.Paste")
			(net "+12V")
			(solder_mask_margin 0)
			(solder_paste_margin 0)
		)
		(pad "21" smd rect
			(at -0.91 -1.66999 180)
			(size 1.8796 0.3556)
			(layers "F.Cu" "F.Mask" "F.Paste")
			(net "+12V")
			(solder_mask_margin 0)
			(solder_paste_margin 0)
		)
		(pad "22" smd rect
			(at -0.91 -0.86 180)
			(size 1.8796 0.6604)
			(layers "F.Cu" "F.Mask" "F.Paste")
			(net "P3V3_MUN_PHASE")
			(solder_mask_margin 0)
			(solder_paste_margin 0)
		)
		(pad "23" smd rect
			(at -0.91 0.80001 180)
			(size 1.8796 2.1082)
			(layers "F.Cu" "F.Mask" "F.Paste")
			(net "GND")
			(solder_mask_margin 0)
			(solder_paste_margin 0)
		)
		(pad "24" smd rect
			(at 1.4 0.80001 180)
			(size 0.889 2.1082)
			(layers "F.Cu" "F.Mask" "F.Paste")
			(net "P3V3_SENSE")
			(solder_mask_margin 0)
			(solder_paste_margin 0)
		)
		(pad "25" smd rect
			(at 1.4 -1.2 180)
			(size 0.889 1.2954)
			(layers "F.Cu" "F.Mask" "F.Paste")
			(net "GND")
			(solder_mask_margin 0)
			(solder_paste_margin 0)
		)
	)
	(footprint "SamacSys:155124M173200"
		(layer "F.Cu")
		(at 67.4466 141.8162 90)
		(property "Reference" "D18"
			(at -0.3286 1.448069 270)
			(unlocked yes)
			(layer "F.SilkS")
			(effects
				(font
					(size 0.762 0.762)
					(thickness 0.2286)
				)
			)
		)
		(property "Value" "155124M173200"
			(at 7.1471 2.605271 90)
			(unlocked yes)
			(layer "F.SilkS")
			(hide yes)
			(effects
				(font
					(size 0.762 0.762)
					(thickness 0.2286)
				)
			)
		)
		(sheetname "02-USER_IO_STATUS")
		(sheetfile "02-USER_IO_STATUS.kicad_sch")
		(duplicate_pad_numbers_are_jumpers no)
		(fp_line
			(start -0.8 0.5)
			(end 0.8 0.5)
			(stroke
				(width 0.1)
				(type solid)
			)
			(layer "F.SilkS")
		)
		(fp_arc
			(start -2 -0.1)
			(mid -1.95 -0.05)
			(end -2 0)
			(stroke
				(width 0.381)
				(type solid)
			)
			(layer "F.SilkS")
		)
		(fp_arc
			(start -2 0)
			(mid -2.05 -0.05)
			(end -2 -0.1)
			(stroke
				(width 0.381)
				(type solid)
			)
			(layer "F.SilkS")
		)
		(pad "1" smd rect
			(at -1.4 0 180)
			(size 0.9 0.6)
			(layers "F.Cu" "F.Mask" "F.Paste")
			(net "+3.3V")
		)
		(pad "2" smd rect
			(at -0.45 -0.325 90)
			(size 0.6 0.55)
			(layers "F.Cu" "F.Mask" "F.Paste")
			(net "NetD18_2")
		)
		(pad "3" smd rect
			(at 0.45 -0.325 90)
			(size 0.6 0.55)
			(layers "F.Cu" "F.Mask" "F.Paste")
			(net "NetD18_3")
		)
		(pad "4" smd rect
			(at 1.4 0 180)
			(size 0.9 0.6)
			(layers "F.Cu" "F.Mask" "F.Paste")
			(net "NetD18_4")
		)
	)
	(footprint "Vault:RESC3216X89X64NL25T25"
		(layer "F.Cu")
		(at 93.0216 65.3162)
		(property "Reference" "R8"
			(at -0.4 -1.206655 0)
			(unlocked yes)
			(layer "F.SilkS")
			(effects
				(font
					(size 0.762 0.762)
					(thickness 0.2286)
				)
				(justify left bottom)
			)
		)
		(property "Value" "2mOhm_1%_1206"
			(at 16.2553 6.763245 0)
			(unlocked yes)
			(layer "F.SilkS")
			(hide yes)
			(effects
				(font
					(size 0.762 0.762)
					(thickness 0.2286)
				)
				(justify left bottom)
			)
		)
		(sheetname "03-POWER")
		(sheetfile "03-POWER.kicad_sch")
		(duplicate_pad_numbers_are_jumpers no)
		(fp_line
			(start -0.2 -0.825)
			(end 0.2 -0.825)
			(stroke
				(width 0.2)
				(type solid)
			)
			(layer "F.SilkS")
		)
		(fp_line
			(start -0.2 0.825)
			(end 0.2 0.825)
			(stroke
				(width 0.2)
				(type solid)
			)
			(layer "F.SilkS")
		)
		(pad "1" smd rect
			(at -1.325 0 90)
			(size 1.85 1.5)
			(layers "F.Cu" "F.Mask" "F.Paste")
			(net "P5V_SENSE")
		)
		(pad "2" smd rect
			(at 1.325 0 90)
			(size 1.85 1.5)
			(layers "F.Cu" "F.Mask" "F.Paste")
			(net "+5.0V")
		)
	)
	(footprint "Vault:RESC1005X40X25LL05T10"
		(layer "F.Cu")
		(at 227.3216 119.3162 180)
		(property "Reference" "R82"
			(at 2.2714 -0.126931 0)
			(unlocked yes)
			(layer "F.SilkS")
			(effects
				(font
					(size 0.762 0.762)
					(thickness 0.2286)
				)
			)
		)
		(property "Value" "10K_1%_0402"
			(at -2.579871 8.061915 90)
			(unlocked yes)
			(layer "F.SilkS")
			(hide yes)
			(effects
				(font
					(size 0.762 0.762)
					(thickness 0.2286)
				)
			)
		)
		(sheetname "09-USBUart_PPSMUX_UARTMUX")
		(sheetfile "09-USBUart_PPSMUX_UARTMUX.kicad_sch")
		(duplicate_pad_numbers_are_jumpers no)
		(pad "1" smd rect
			(at -0.375 0 270)
			(size 0.45 0.5)
			(layers "F.Cu" "F.Mask" "F.Paste")
			(net "NetC91_1")
		)
		(pad "2" smd rect
			(at 0.375 0 270)
			(size 0.45 0.5)
			(layers "F.Cu" "F.Mask" "F.Paste")
			(net "FTDI_VBUS")
		)
	)
	(footprint "SamacSys:SOP50P310X90-8N"
		(layer "F.Cu")
		(at 77.4216 101.9162 180)
		(property "Reference" "U8"
			(at -0.228595 1.773079 0)
			(unlocked yes)
			(layer "F.SilkS")
			(effects
				(font
					(size 0.762 0.762)
					(thickness 0.2286)
				)
			)
		)
		(property "Value" "NC7WV125K8X"
			(at 6.207715 2.884671 180)
			(unlocked yes)
			(layer "F.SilkS")
			(hide yes)
			(effects
				(font
					(size 0.762 0.762)
					(thickness 0.2286)
				)
			)
		)
		(sheetname "01-USER_IO")
		(sheetfile "01-USER_IO.kicad_sch")
		(duplicate_pad_numbers_are_jumpers no)
		(fp_line
			(start 0.8 1)
			(end -0.8 1)
			(stroke
				(width 0.2)
				(type solid)
			)
			(layer "F.SilkS")
		)
		(fp_line
			(start 0.8 -1)
			(end 0.8 1)
			(stroke
				(width 0.2)
				(type solid)
			)
			(layer "F.SilkS")
		)
		(fp_line
			(start 0.8 -1)
			(end -0.8 -1)
			(stroke
				(width 0.2)
				(type solid)
			)
			(layer "F.SilkS")
		)
		(fp_line
			(start -0.8 -1)
			(end -0.8 1)
			(stroke
				(width 0.2)
				(type solid)
			)
			(layer "F.SilkS")
		)
		(fp_line
			(start -1.15 -1.25)
			(end -2 -1.25)
			(stroke
				(width 0.2)
				(type solid)
			)
			(layer "F.SilkS")
		)
		(pad "1" smd rect
			(at -1.575 -0.75 180)
			(size 0.85 0.3)
			(layers "F.Cu" "F.Mask" "F.Paste")
			(net "ANT1_IO_OUT")
		)
		(pad "2" smd rect
			(at -1.575 -0.25 180)
			(size 0.85 0.3)
			(layers "F.Cu" "F.Mask" "F.Paste")
			(net "ANT1_OUT")
		)
		(pad "3" smd rect
			(at -1.575 0.25 180)
			(size 0.85 0.3)
			(layers "F.Cu" "F.Mask" "F.Paste")
			(net "ANT1_IN")
		)
		(pad "4" smd rect
			(at -1.575 0.75 180)
			(size 0.85 0.3)
			(layers "F.Cu" "F.Mask" "F.Paste")
			(net "GND")
		)
		(pad "5" smd rect
			(at 1.575 0.75 180)
			(size 0.85 0.3)
			(layers "F.Cu" "F.Mask" "F.Paste")
			(net "NetR25_1")
		)
		(pad "6" smd rect
			(at 1.575 0.25 180)
			(size 0.85 0.3)
			(layers "F.Cu" "F.Mask" "F.Paste")
			(net "NetR25_1")
		)
		(pad "7" smd rect
			(at 1.575 -0.25 180)
			(size 0.85 0.3)
			(layers "F.Cu" "F.Mask" "F.Paste")
			(net "ANT1_IO_IN")
		)
		(pad "8" smd rect
			(at 1.575 -0.75 180)
			(size 0.85 0.3)
			(layers "F.Cu" "F.Mask" "F.Paste")
			(net "+3.3V")
		)
	)
	(footprint "PI3A412ZHE:ZH16_PER"
		(layer "F.Cu")
		(at 193.6216 132.3162)
		(property "Reference" "U28"
			(at -0.39436 -3.693929 0)
			(unlocked yes)
			(layer "F.SilkS")
			(effects
				(font
					(size 0.762 0.762)
					(thickness 0.2032)
				)
			)
		)
		(property "Value" "PI3A412ZHE"
			(at 4.684 3.722871 0)
			(unlocked yes)
			(layer "F.SilkS")
			(hide yes)
			(effects
				(font
					(size 0.762 0.762)
					(thickness 0.2032)
				)
			)
		)
		(sheetname "11-M2_RCB_MUX")
		(sheetfile "11-M2_RCB_MUX.kicad_sch")
		(duplicate_pad_numbers_are_jumpers no)
		(fp_line
			(start -1.6764 -1.6764)
			(end -1.20974 -1.6764)
			(stroke
				(width 0.1524)
				(type solid)
			)
			(layer "F.SilkS")
		)
		(fp_line
			(start -1.6764 -1.20974)
			(end -1.6764 -1.6764)
			(stroke
				(width 0.1524)
				(type solid)
			)
			(layer "F.SilkS")
		)
		(fp_line
			(start -1.6764 1.6764)
			(end -1.6764 1.20974)
			(stroke
				(width 0.1524)
				(type solid)
			)
			(layer "F.SilkS")
		)
		(fp_line
			(start -1.6764 1.6764)
			(end -1.20974 1.6764)
			(stroke
				(width 0.1524)
				(type solid)
			)
			(layer "F.SilkS")
		)
		(fp_line
			(start 1.20974 -1.6764)
			(end 1.6764 -1.6764)
			(stroke
				(width 0.1524)
				(type solid)
			)
			(layer "F.SilkS")
		)
		(fp_line
			(start 1.20974 1.6764)
			(end 1.6764 1.6764)
			(stroke
				(width 0.1524)
				(type solid)
			)
			(layer "F.SilkS")
		)
		(fp_line
			(start 1.6764 -1.20974)
			(end 1.6764 -1.6764)
			(stroke
				(width 0.1524)
				(type solid)
			)
			(layer "F.SilkS")
		)
		(fp_line
			(start 1.6764 1.6764)
			(end 1.6764 1.20974)
			(stroke
				(width 0.1524)
				(type solid)
			)
			(layer "F.SilkS")
		)
		(fp_poly
			(pts
				(xy 2.1082 0.0595) (xy 2.3622 0.0595) (xy 2.3622 0.4405) (xy 2.1082 0.4405)
			)
			(stroke
				(width 0)
				(type default)
			)
			(fill yes)
			(layer "F.SilkS")
		)
		(fp_text user "*"
			(at -2.8067 -0.209425 0)
			(unlocked yes)
			(layer "F.SilkS")
			(effects
				(font
					(size 1.27 1.27)
					(thickness 0.0762)
				)
				(justify left bottom)
			)
		)
		(pad "1" smd rect
			(at -1.4478 -0.75 270)
			(size 0.254 0.8128)
			(layers "F.Cu" "F.Mask" "F.Paste")
			(net "RCB_GPS2_TX")
			(solder_mask_margin 0)
			(solder_paste_margin 0)
		)
		(pad "2" smd rect
			(at -1.4478 -0.25 270)
			(size 0.254 0.8128)
			(layers "F.Cu" "F.Mask" "F.Paste")
			(net "DIP_SW_GPS2_SEL")
			(solder_mask_margin 0)
			(solder_paste_margin 0)
		)
		(pad "3" smd rect
			(at -1.4478 0.25 270)
			(size 0.254 0.8128)
			(layers "F.Cu" "F.Mask" "F.Paste")
			(net "M2_GPS2_RX")
			(solder_mask_margin 0)
			(solder_paste_margin 0)
		)
		(pad "4" smd rect
			(at -1.4478 0.75 270)
			(size 0.254 0.8128)
			(layers "F.Cu" "F.Mask" "F.Paste")
			(net "NetR146_1")
			(solder_mask_margin 0)
			(solder_paste_margin 0)
		)
		(pad "5" smd rect
			(at -0.75 1.4478 180)
			(size 0.254 0.8128)
			(layers "F.Cu" "F.Mask" "F.Paste")
			(net "RCB_GPS2_RX")
			(solder_mask_margin 0)
			(solder_paste_margin 0)
		)
		(pad "6" smd rect
			(at -0.25 1.4478 180)
			(size 0.254 0.8128)
			(layers "F.Cu" "F.Mask" "F.Paste")
			(net "GND")
			(solder_mask_margin 0)
			(solder_paste_margin 0)
		)
		(pad "7" smd rect
			(at 0.25 1.4478 180)
			(size 0.254 0.8128)
			(layers "F.Cu" "F.Mask" "F.Paste")
			(net "M2_GPS2_TP1")
			(solder_mask_margin 0)
			(solder_paste_margin 0)
		)
		(pad "8" smd rect
			(at 0.75 1.4478 180)
			(size 0.254 0.8128)
			(layers "F.Cu" "F.Mask" "F.Paste")
			(net "NetR145_1")
			(solder_mask_margin 0)
			(solder_paste_margin 0)
		)
		(pad "9" smd rect
			(at 1.4478 0.75 270)
			(size 0.254 0.8128)
			(layers "F.Cu" "F.Mask" "F.Paste")
			(net "RCB_GPS2_TP1")
			(solder_mask_margin 0)
			(solder_paste_margin 0)
		)
		(pad "10" smd rect
			(at 1.4478 0.25 270)
			(size 0.254 0.8128)
			(layers "F.Cu" "F.Mask" "F.Paste")
			(net "DIP_SW_GPS2_SEL")
			(solder_mask_margin 0)
			(solder_paste_margin 0)
		)
		(pad "11" smd rect
			(at 1.4478 -0.25 270)
			(size 0.254 0.8128)
			(layers "F.Cu" "F.Mask" "F.Paste")
			(net "M2_GPS2_TP2")
			(solder_mask_margin 0)
			(solder_paste_margin 0)
		)
		(pad "12" smd rect
			(at 1.4478 -0.75 270)
			(size 0.254 0.8128)
			(layers "F.Cu" "F.Mask" "F.Paste")
			(net "NetR143_1")
			(solder_mask_margin 0)
			(solder_paste_margin 0)
		)
		(pad "13" smd rect
			(at 0.75 -1.4478 180)
			(size 0.254 0.8128)
			(layers "F.Cu" "F.Mask" "F.Paste")
			(net "RCB_GPS2_TP2")
			(solder_mask_margin 0)
			(solder_paste_margin 0)
		)
		(pad "14" smd rect
			(at 0.25 -1.4478 180)
			(size 0.254 0.8128)
			(layers "F.Cu" "F.Mask" "F.Paste")
			(net "+3.3V")
			(solder_mask_margin 0)
			(solder_paste_margin 0)
		)
		(pad "15" smd rect
			(at -0.25 -1.4478 180)
			(size 0.254 0.8128)
			(layers "F.Cu" "F.Mask" "F.Paste")
			(net "M2_GPS2_TX")
			(solder_mask_margin 0)
			(solder_paste_margin 0)
		)
		(pad "16" smd rect
			(at -0.75 -1.4478 180)
			(size 0.254 0.8128)
			(layers "F.Cu" "F.Mask" "F.Paste")
			(net "NetR142_1")
			(solder_mask_margin 0)
			(solder_paste_margin 0)
		)
		(pad "17" smd rect
			(at 0 0)
			(size 1.8034 1.8034)
			(layers "F.Cu" "F.Mask" "F.Paste")
			(net "GND")
			(solder_mask_margin 0)
			(solder_paste_margin 0)
		)
	)
	(footprint "Vault:RESC1005X40X25LL05T10"
		(layer "F.Cu")
		(at 109.4216 51.1162 90)
		(property "Reference" "R144"
			(at -0.4968 8.326921 90)
			(unlocked yes)
			(layer "F.SilkS")
			(effects
				(font
					(size 0.762 0.762)
					(thickness 0.2032)
				)
			)
		)
		(property "Value" "49.9_1%_0402"
			(at -2.579871 8.798265 0)
			(unlocked yes)
			(layer "F.SilkS")
			(hide yes)
			(effects
				(font
					(size 0.762 0.762)
					(thickness 0.2032)
				)
			)
		)
		(sheetname "11-M2_RCB_MUX")
		(sheetfile "11-M2_RCB_MUX.kicad_sch")
		(duplicate_pad_numbers_are_jumpers no)
		(pad "1" smd rect
			(at -0.375 0 180)
			(size 0.45 0.5)
			(layers "F.Cu" "F.Mask" "F.Paste")
			(net "NetR144_1")
		)
		(pad "2" smd rect
			(at 0.375 0 180)
			(size 0.45 0.5)
			(layers "F.Cu" "F.Mask" "F.Paste")
			(net "GPS1_TX")
		)
	)
	(footprint "Vault:TECO-1909763-1_V"
		(layer "F.Cu")
		(at 77.19563 135.6162 -90)
		(property "Reference" "J4"
			(at -2.873079 -1.254575 0)
			(unlocked yes)
			(layer "F.SilkS")
			(effects
				(font
					(size 0.762 0.762)
					(thickness 0.2286)
				)
			)
		)
		(property "Value" "1909763-1"
			(at 4.582685 3.722871 270)
			(unlocked yes)
			(layer "F.SilkS")
			(hide yes)
			(effects
				(font
					(size 0.762 0.762)
					(thickness 0.2286)
				)
			)
		)
		(sheetname "01-USER_IO")
		(sheetfile "01-USER_IO.kicad_sch")
		(duplicate_pad_numbers_are_jumpers no)
		(fp_line
			(start 0.55 -1.3)
			(end -0.55 -1.3)
			(stroke
				(width 0.2)
				(type solid)
			)
			(layer "F.SilkS")
		)
		(fp_circle
			(center -1.778 1.65)
			(end -1.903 1.65)
			(stroke
				(width 0.25)
				(type solid)
			)
			(fill no)
			(layer "F.SilkS")
		)
		(pad "1" smd rect
			(at -1.475 0 270)
			(size 1.05 2.2)
			(layers "F.Cu" "F.Mask" "F.Paste")
			(net "GND")
		)
		(pad "2" smd rect
			(at 0 1.525 270)
			(size 1 1.05)
			(layers "F.Cu" "F.Mask" "F.Paste")
			(net "NetAN4_1")
		)
		(pad "3" smd rect
			(at 1.475 0 270)
			(size 1.05 2.2)
			(layers "F.Cu" "F.Mask" "F.Paste")
			(net "GND")
		)
	)
	(footprint "Vault:RESC1005X40X25LL05T10"
		(layer "F.Cu")
		(at 142.8216 102.2162 -90)
		(property "Reference" "R96"
			(at -2.3286 0.073069 90)
			(unlocked yes)
			(layer "F.SilkS")
			(effects
				(font
					(size 0.762 0.762)
					(thickness 0.2286)
				)
			)
		)
		(property "Value" "49.9_1%_0402"
			(at -2.579871 8.823675 180)
			(unlocked yes)
			(layer "F.SilkS")
			(hide yes)
			(effects
				(font
					(size 0.762 0.762)
					(thickness 0.2286)
				)
			)
		)
		(sheetname "09-USBUart_PPSMUX_UARTMUX")
		(sheetfile "09-USBUart_PPSMUX_UARTMUX.kicad_sch")
		(duplicate_pad_numbers_are_jumpers no)
		(pad "1" smd rect
			(at -0.375 0)
			(size 0.45 0.5)
			(layers "F.Cu" "F.Mask" "F.Paste")
			(net "MAC_PPS_OUT")
		)
		(pad "2" smd rect
			(at 0.375 0)
			(size 0.45 0.5)
			(layers "F.Cu" "F.Mask" "F.Paste")
			(net "NetR96_2")
		)
	)
	(footprint "Vault:RESC1005X40X25NL05T05"
		(layer "F.Cu")
		(at 223.8216 91.8162 180)
		(property "Reference" "R179"
			(at 2.3968 0.173069 0)
			(unlocked yes)
			(layer "F.SilkS")
			(effects
				(font
					(size 0.762 0.762)
					(thickness 0.2032)
				)
			)
		)
		(property "Value" "200_1%_0402"
			(at -2.732271 8.112675 90)
			(unlocked yes)
			(layer "F.SilkS")
			(hide yes)
			(effects
				(font
					(size 0.762 0.762)
					(thickness 0.2032)
				)
			)
		)
		(sheetname "08-DIPSwitches_I2C")
		(sheetfile "08-DIPSwitches_I2C.kicad_sch")
		(duplicate_pad_numbers_are_jumpers no)
		(pad "1" smd rect
			(at -0.45 0 270)
			(size 0.55 0.55)
			(layers "F.Cu" "F.Mask" "F.Paste")
			(net "NetD19_1")
		)
		(pad "2" smd rect
			(at 0.45 0 270)
			(size 0.55 0.55)
			(layers "F.Cu" "F.Mask" "F.Paste")
			(net "DIP_SW_GPS1_SEL")
		)
	)
	(footprint "Vault:FP-C1005-050-0_05-IPC_A"
		(layer "F.Cu")
		(at 162.25767 83.8662 180)
		(property "Reference" "C81"
			(at 2.107465 -0.076931 0)
			(unlocked yes)
			(layer "F.SilkS")
			(effects
				(font
					(size 0.762 0.762)
					(thickness 0.2286)
				)
			)
		)
		(property "Value" "2.2uF_16V_0402"
			(at 9.509015 2.440151 180)
			(unlocked yes)
			(layer "F.SilkS")
			(hide yes)
			(effects
				(font
					(size 0.762 0.762)
					(thickness 0.2286)
				)
			)
		)
		(sheetname "03-POWER")
		(sheetfile "03-POWER.kicad_sch")
		(duplicate_pad_numbers_are_jumpers no)
		(fp_line
			(start 0.83623 0.73624)
			(end -0.83624 0.73624)
			(stroke
				(width 0.2)
				(type solid)
			)
			(layer "F.SilkS")
		)
		(fp_line
			(start 0.83623 -0.73624)
			(end -0.83624 -0.73624)
			(stroke
				(width 0.2)
				(type solid)
			)
			(layer "F.SilkS")
		)
		(fp_line
			(start 1.03623 0.53624)
			(end -1.03624 0.53624)
			(stroke
				(width 0.2)
				(type solid)
			)
			(layer "F.CrtYd")
		)
		(fp_line
			(start 1.03623 -0.53624)
			(end 1.03623 0.53624)
			(stroke
				(width 0.2)
				(type solid)
			)
			(layer "F.CrtYd")
		)
		(fp_line
			(start 1.03623 -0.53624)
			(end -1.03624 -0.53624)
			(stroke
				(width 0.2)
				(type solid)
			)
			(layer "F.CrtYd")
		)
		(fp_line
			(start -1.03624 -0.53624)
			(end -1.03624 0.53624)
			(stroke
				(width 0.2)
				(type solid)
			)
			(layer "F.CrtYd")
		)
		(fp_line
			(start 1.03623 0.53624)
			(end -1.03624 0.53624)
			(stroke
				(width 0.2)
				(type solid)
			)
			(layer "F.Fab")
		)
		(fp_line
			(start 1.03623 -0.53624)
			(end 1.03623 0.53624)
			(stroke
				(width 0.2)
				(type solid)
			)
			(layer "F.Fab")
		)
		(fp_line
			(start 1.03623 -0.53624)
			(end -1.03624 -0.53624)
			(stroke
				(width 0.2)
				(type solid)
			)
			(layer "F.Fab")
		)
		(fp_line
			(start 0.5 0)
			(end -0.5 0)
			(stroke
				(width 0.1)
				(type solid)
			)
			(layer "F.Fab")
		)
		(fp_line
			(start 0 -0.5)
			(end 0 0.5)
			(stroke
				(width 0.1)
				(type solid)
			)
			(layer "F.Fab")
		)
		(fp_line
			(start -1.03624 -0.53624)
			(end -1.03624 0.53624)
			(stroke
				(width 0.2)
				(type solid)
			)
			(layer "F.Fab")
		)
		(fp_text user "${REFERENCE}"
			(at -0.00001 0.09601 180)
			(unlocked yes)
			(layer "F.Fab")
			(effects
				(font
					(face "Arial")
					(size 0.63 0.63)
					(thickness 0.1)
				)
				(justify left bottom)
			)
		)
		(pad "1" smd rect
			(at -0.46658 0 180)
			(size 0.73933 0.67248)
			(layers "F.Cu" "F.Mask" "F.Paste")
			(net "+3.3V")
			(solder_mask_margin 0)
			(solder_paste_margin 0)
		)
		(pad "2" smd rect
			(at 0.46657 0 180)
			(size 0.73933 0.67248)
			(layers "F.Cu" "F.Mask" "F.Paste")
			(net "GND")
			(solder_mask_margin 0)
			(solder_paste_margin 0)
		)
	)
	(footprint "SamacSys:155124M173200"
		(layer "F.Cu")
		(at 67.4466 82.6662 90)
		(property "Reference" "D14"
			(at -4.7 -0.231655 90)
			(unlocked yes)
			(layer "F.SilkS")
			(effects
				(font
					(size 0.762 0.762)
					(thickness 0.2286)
				)
				(justify left bottom)
			)
		)
		(property "Value" "155124M173200"
			(at -4.043045 -0.5715 0)
			(unlocked yes)
			(layer "F.SilkS")
			(hide yes)
			(effects
				(font
					(size 0.762 0.762)
					(thickness 0.2286)
				)
				(justify left bottom)
			)
		)
		(sheetname "02-USER_IO_STATUS")
		(sheetfile "02-USER_IO_STATUS.kicad_sch")
		(duplicate_pad_numbers_are_jumpers no)
		(fp_line
			(start -0.8 0.5)
			(end 0.8 0.5)
			(stroke
				(width 0.1)
				(type solid)
			)
			(layer "F.SilkS")
		)
		(fp_arc
			(start -2 -0.1008)
			(mid -1.9492 -0.05)
			(end -2 0.0008)
			(stroke
				(width 0.381)
				(type solid)
			)
			(layer "F.SilkS")
		)
		(fp_arc
			(start -2 0.0008)
			(mid -2.0508 -0.05)
			(end -2 -0.1008)
			(stroke
				(width 0.381)
				(type solid)
			)
			(layer "F.SilkS")
		)
		(pad "1" smd rect
			(at -1.4 0 180)
			(size 0.9 0.6)
			(layers "F.Cu" "F.Mask" "F.Paste")
			(net "+3.3V")
		)
		(pad "2" smd rect
			(at -0.45 -0.325 90)
			(size 0.6 0.55)
			(layers "F.Cu" "F.Mask" "F.Paste")
			(net "NetD14_2")
		)
		(pad "3" smd rect
			(at 0.45 -0.325 90)
			(size 0.6 0.55)
			(layers "F.Cu" "F.Mask" "F.Paste")
			(net "NetD14_3")
		)
		(pad "4" smd rect
			(at 1.4 0 180)
			(size 0.9 0.6)
			(layers "F.Cu" "F.Mask" "F.Paste")
			(net "NetD14_4")
		)
	)
	(footprint "SA53:SolderSocket"
		(locked yes)
		(layer "F.Cu")
		(at 86.9216 117.0162 90)
		(property "Reference" "SKT6"
			(at -0.126921 -6.9714 0)
			(unlocked yes)
			(layer "F.SilkS")
			(effects
				(font
					(size 0.762 0.762)
					(thickness 0.2286)
				)
			)
		)
		(property "Value" "0332-0-43-80-18-27-10-0"
			(at -2.910071 16.1362 0)
			(unlocked yes)
			(layer "F.SilkS")
			(hide yes)
			(effects
				(font
					(size 0.762 0.762)
					(thickness 0.2286)
				)
			)
		)
		(sheetname "06-MAC")
		(sheetfile "06-MAC.kicad_sch")
		(duplicate_pad_numbers_are_jumpers no)
		(pad "1" thru_hole circle
			(at 0 0 90)
			(size 2.54 2.54)
			(drill 2.0066)
			(layers "*.Cu" "*.Mask")
			(remove_unused_layers no)
			(net "GND")
			(thermal_bridge_angle 90)
		)
	)
	(footprint "Vault:FP-T495D107K016ATE125-MFG"
		(layer "F.Cu")
		(at 96.4216 74.7162 180)
		(property "Reference" "C14"
			(at 4.206655 0.7 90)
			(unlocked yes)
			(layer "F.SilkS")
			(effects
				(font
					(size 0.762 0.762)
					(thickness 0.2286)
				)
				(justify left bottom)
			)
		)
		(property "Value" "100uF_16V_2917"
			(at -5.7281 -15.597845 0)
			(unlocked yes)
			(layer "F.SilkS")
			(hide yes)
			(effects
				(font
					(size 0.762 0.762)
					(thickness 0.2286)
				)
				(justify left bottom)
			)
		)
		(sheetname "03-POWER")
		(sheetfile "03-POWER.kicad_sch")
		(duplicate_pad_numbers_are_jumpers no)
		(fp_line
			(start 5 0)
			(end 4.4 0)
			(stroke
				(width 0.2)
				(type solid)
			)
			(layer "F.SilkS")
		)
		(fp_line
			(start 4.7 -0.3)
			(end 4.7 0.3)
			(stroke
				(width 0.2)
				(type solid)
			)
			(layer "F.SilkS")
		)
		(fp_line
			(start 3.8 2.3)
			(end -3.8 2.3)
			(stroke
				(width 0.2)
				(type solid)
			)
			(layer "F.SilkS")
		)
		(fp_line
			(start 3.8 1.54)
			(end 3.8 2.3)
			(stroke
				(width 0.2)
				(type solid)
			)
			(layer "F.SilkS")
		)
		(fp_line
			(start 3.8 -2.3)
			(end 3.8 -1.54)
			(stroke
				(width 0.2)
				(type solid)
			)
			(layer "F.SilkS")
		)
		(fp_line
			(start 3.8 -2.3)
			(end -3.8 -2.3)
			(stroke
				(width 0.2)
				(type solid)
			)
			(layer "F.SilkS")
		)
		(fp_line
			(start -3.8 1.54)
			(end -3.8 2.3)
			(stroke
				(width 0.2)
				(type solid)
			)
			(layer "F.SilkS")
		)
		(fp_line
			(start -3.8 -2.3)
			(end -3.8 -1.54)
			(stroke
				(width 0.2)
				(type solid)
			)
			(layer "F.SilkS")
		)
		(fp_line
			(start 4.105 2.4)
			(end -4.105 2.4)
			(stroke
				(width 0.2)
				(type solid)
			)
			(layer "F.CrtYd")
		)
		(fp_line
			(start 4.105 -2.4)
			(end 4.105 2.4)
			(stroke
				(width 0.2)
				(type solid)
			)
			(layer "F.CrtYd")
		)
		(fp_line
			(start 4.105 -2.4)
			(end -4.105 -2.4)
			(stroke
				(width 0.2)
				(type solid)
			)
			(layer "F.CrtYd")
		)
		(fp_line
			(start -4.105 -2.4)
			(end -4.105 2.4)
			(stroke
				(width 0.2)
				(type solid)
			)
			(layer "F.CrtYd")
		)
		(fp_line
			(start 4.105 2.4)
			(end -4.105 2.4)
			(stroke
				(width 0.2)
				(type solid)
			)
			(layer "F.Fab")
		)
		(fp_line
			(start 4.105 -2.4)
			(end 4.105 2.4)
			(stroke
				(width 0.2)
				(type solid)
			)
			(layer "F.Fab")
		)
		(fp_line
			(start 4.105 -2.4)
			(end -4.105 -2.4)
			(stroke
				(width 0.2)
				(type solid)
			)
			(layer "F.Fab")
		)
		(fp_line
			(start 0.5 0)
			(end -0.5 0)
			(stroke
				(width 0.1)
				(type solid)
			)
			(layer "F.Fab")
		)
		(fp_line
			(start 0 -0.5)
			(end 0 0.5)
			(stroke
				(width 0.1)
				(type solid)
			)
			(layer "F.Fab")
		)
		(fp_line
			(start -4.105 -2.4)
			(end -4.105 2.4)
			(stroke
				(width 0.2)
				(type solid)
			)
			(layer "F.Fab")
		)
		(fp_text user "${REFERENCE}"
			(at 0 0.28425 180)
			(unlocked yes)
			(layer "F.Fab")
			(effects
				(font
					(face "Arial")
					(size 0.63 0.63)
					(thickness 0.1)
				)
				(justify left bottom)
			)
		)
		(pad "1" smd rect
			(at -3.01 0 180)
			(size 1.99 2.33)
			(layers "F.Cu" "F.Mask" "F.Paste")
			(net "GND")
			(solder_mask_margin 0)
			(solder_paste_margin 0)
		)
		(pad "2" smd rect
			(at 3.01 0 180)
			(size 1.99 2.33)
			(layers "F.Cu" "F.Mask" "F.Paste")
			(net "+5.0V")
			(solder_mask_margin 0)
			(solder_paste_margin 0)
		)
	)
	(footprint "Vault:RESC1005X40X25NL05T05"
		(layer "F.Cu")
		(at 112.7216 52.2162 90)
		(property "Reference" "R161"
			(at -0.0968 7.726921 90)
			(unlocked yes)
			(layer "F.SilkS")
			(effects
				(font
					(size 0.762 0.762)
					(thickness 0.2032)
				)
			)
		)
		(property "Value" "DNI_27_1%_0402"
			(at -2.732271 10.270975 0)
			(unlocked yes)
			(layer "F.SilkS")
			(hide yes)
			(effects
				(font
					(size 0.762 0.762)
					(thickness 0.2032)
				)
			)
		)
		(sheetname "11-M2_RCB_MUX")
		(sheetfile "11-M2_RCB_MUX.kicad_sch")
		(duplicate_pad_numbers_are_jumpers no)
		(pad "1" smd rect
			(at -0.45 0 180)
			(size 0.55 0.55)
			(layers "F.Cu" "F.Mask" "F.Paste")
			(net "RCB_GPS1_TP2")
		)
		(pad "2" smd rect
			(at 0.45 0 180)
			(size 0.55 0.55)
			(layers "F.Cu" "F.Mask" "F.Paste")
			(net "GPS1_TP2")
		)
	)
	(footprint "Resistors:RESC2012X50N"
		(layer "F.Cu")
		(at 205.5416 145.61546)
		(property "Reference" "R21"
			(at -1.25 -1.406655 0)
			(unlocked yes)
			(layer "F.SilkS")
			(effects
				(font
					(size 0.762 0.762)
					(thickness 0.2286)
				)
				(justify left bottom)
			)
		)
		(property "Value" "CRCW080533R0FKEA"
			(at 7.20584 2.241585 0)
			(unlocked yes)
			(layer "F.SilkS")
			(hide yes)
			(effects
				(font
					(size 0.762 0.762)
					(thickness 0.2286)
				)
				(justify left bottom)
			)
		)
		(sheetname "04-PCIe_JTAG")
		(sheetfile "04-PCIe_JTAG.kicad_sch")
		(duplicate_pad_numbers_are_jumpers no)
		(fp_line
			(start 0 0.762)
			(end 0 -0.762)
			(stroke
				(width 0.1524)
				(type solid)
			)
			(layer "F.SilkS")
		)
		(pad "1" smd rect
			(at -1 0 90)
			(size 1.45 0.95)
			(layers "F.Cu" "F.Mask" "F.Paste")
			(net "FPGA_TDI")
		)
		(pad "2" smd rect
			(at 1 0 90)
			(size 1.45 0.95)
			(layers "F.Cu" "F.Mask" "F.Paste")
			(net "NetP4_9")
		)
	)
	(footprint "Vault:RESC3116X65X50ML20T20"
		(layer "F.Cu")
		(at 224.3216 63.8162 -90)
		(property "Reference" "R44"
			(at 0.3286 -1.573069 270)
			(unlocked yes)
			(layer "F.SilkS")
			(effects
				(font
					(size 0.762 0.762)
					(thickness 0.2286)
				)
			)
		)
		(property "Value" "DNI_0_5%_1206"
			(at 7.27402 3.291071 270)
			(unlocked yes)
			(layer "F.SilkS")
			(hide yes)
			(effects
				(font
					(size 0.762 0.762)
					(thickness 0.2286)
				)
			)
		)
		(sheetname "03-POWER")
		(sheetfile "03-POWER.kicad_sch")
		(duplicate_pad_numbers_are_jumpers no)
		(fp_line
			(start 0.35 0.85)
			(end -0.35 0.85)
			(stroke
				(width 0.2)
				(type solid)
			)
			(layer "F.SilkS")
		)
		(fp_line
			(start 0.35 -0.85)
			(end -0.35 -0.85)
			(stroke
				(width 0.2)
				(type solid)
			)
			(layer "F.SilkS")
		)
		(pad "1" smd rect
			(at -1.475 0)
			(size 1.9 1.45)
			(layers "F.Cu" "F.Mask" "F.Paste")
			(net "+12V_PCIE")
		)
		(pad "2" smd rect
			(at 1.475 0)
			(size 1.9 1.45)
			(layers "F.Cu" "F.Mask" "F.Paste")
			(net "+12V_SENS")
		)
	)
	(footprint "SA53:SolderSocket"
		(locked yes)
		(layer "F.Cu")
		(at 127.5216 96.7162 90)
		(property "Reference" "SKT7"
			(at -2.726921 7.1286 0)
			(unlocked yes)
			(layer "F.SilkS")
			(effects
				(font
					(size 0.762 0.762)
					(thickness 0.2286)
				)
			)
		)
		(property "Value" "0332-0-43-80-18-27-10-0"
			(at -2.910071 16.1362 0)
			(unlocked yes)
			(layer "F.SilkS")
			(hide yes)
			(effects
				(font
					(size 0.762 0.762)
					(thickness 0.2286)
				)
			)
		)
		(sheetname "06-MAC")
		(sheetfile "06-MAC.kicad_sch")
		(duplicate_pad_numbers_are_jumpers no)
		(pad "1" thru_hole circle
			(at 0 0 90)
			(size 2.54 2.54)
			(drill 2.0066)
			(layers "*.Cu" "*.Mask")
			(remove_unused_layers no)
			(net "MAC_VCC")
			(thermal_bridge_angle 90)
		)
	)
	(footprint "Vault:RESC1005X40X25LL05T05"
		(layer "F.Cu")
		(at 118.58072 88.8662)
		(property "Reference" "R73"
			(at -0.13052 1.076921 0)
			(unlocked yes)
			(layer "F.SilkS")
			(effects
				(font
					(size 0.762 0.762)
					(thickness 0.2286)
				)
			)
		)
		(property "Value" "DNI_0_1%_0402"
			(at -2.579871 8.56975 270)
			(unlocked yes)
			(layer "F.SilkS")
			(hide yes)
			(effects
				(font
					(size 0.762 0.762)
					(thickness 0.2286)
				)
			)
		)
		(sheetname "05-GPS_IMU_SENSORS")
		(sheetfile "05-GPS_IMU_SENSORS.kicad_sch")
		(duplicate_pad_numbers_are_jumpers no)
		(pad "1" smd rect
			(at -0.4 0 90)
			(size 0.45 0.45)
			(layers "F.Cu" "F.Mask" "F.Paste")
			(net "BNO_XOUT32")
		)
		(pad "2" smd rect
			(at 0.40001 0 90)
			(size 0.45 0.45)
			(layers "F.Cu" "F.Mask" "F.Paste")
			(net "FPGA_BNO_XOUT32")
		)
	)
	(footprint "SamacSys:SOP50P310X90-8N"
		(layer "F.Cu")
		(at 77.42159 128.5162 180)
		(property "Reference" "U11"
			(at -0.303605 1.973069 0)
			(unlocked yes)
			(layer "F.SilkS")
			(effects
				(font
					(size 0.762 0.762)
					(thickness 0.2286)
				)
			)
		)
		(property "Value" "NC7WV125K8X"
			(at 6.207715 2.884671 180)
			(unlocked yes)
			(layer "F.SilkS")
			(hide yes)
			(effects
				(font
					(size 0.762 0.762)
					(thickness 0.2286)
				)
			)
		)
		(sheetname "01-USER_IO")
		(sheetfile "01-USER_IO.kicad_sch")
		(duplicate_pad_numbers_are_jumpers no)
		(fp_line
			(start 0.8 1)
			(end -0.8 1)
			(stroke
				(width 0.2)
				(type solid)
			)
			(layer "F.SilkS")
		)
		(fp_line
			(start 0.8 -1)
			(end 0.8 1)
			(stroke
				(width 0.2)
				(type solid)
			)
			(layer "F.SilkS")
		)
		(fp_line
			(start 0.8 -1)
			(end -0.8 -1)
			(stroke
				(width 0.2)
				(type solid)
			)
			(layer "F.SilkS")
		)
		(fp_line
			(start -0.8 -1)
			(end -0.8 1)
			(stroke
				(width 0.2)
				(type solid)
			)
			(layer "F.SilkS")
		)
		(fp_line
			(start -1.15 -1.25)
			(end -2 -1.25)
			(stroke
				(width 0.2)
				(type solid)
			)
			(layer "F.SilkS")
		)
		(pad "1" smd rect
			(at -1.575 -0.75 180)
			(size 0.85 0.3)
			(layers "F.Cu" "F.Mask" "F.Paste")
			(net "ANT3_IO_OUT")
		)
		(pad "2" smd rect
			(at -1.575 -0.25 180)
			(size 0.85 0.3)
			(layers "F.Cu" "F.Mask" "F.Paste")
			(net "ANT3_OUT")
		)
		(pad "3" smd rect
			(at -1.575 0.25 180)
			(size 0.85 0.3)
			(layers "F.Cu" "F.Mask" "F.Paste")
			(net "ANT3_IN")
		)
		(pad "4" smd rect
			(at -1.575 0.75 180)
			(size 0.85 0.3)
			(layers "F.Cu" "F.Mask" "F.Paste")
			(net "GND")
		)
		(pad "5" smd rect
			(at 1.575 0.75 180)
			(size 0.85 0.3)
			(layers "F.Cu" "F.Mask" "F.Paste")
			(net "NetR28_1")
		)
		(pad "6" smd rect
			(at 1.575 0.25 180)
			(size 0.85 0.3)
			(layers "F.Cu" "F.Mask" "F.Paste")
			(net "NetR28_1")
		)
		(pad "7" smd rect
			(at 1.575 -0.25 180)
			(size 0.85 0.3)
			(layers "F.Cu" "F.Mask" "F.Paste")
			(net "ANT3_IO_IN")
		)
		(pad "8" smd rect
			(at 1.575 -0.75 180)
			(size 0.85 0.3)
			(layers "F.Cu" "F.Mask" "F.Paste")
			(net "+3.3V")
		)
	)
	(footprint "Resistors:RESC2012X50N"
		(layer "F.Cu")
		(at 195.40761 145.69763)
		(property "Reference" "R19"
			(at -1.28527 -1.268085 0)
			(unlocked yes)
			(layer "F.SilkS")
			(effects
				(font
					(size 0.762 0.762)
					(thickness 0.2286)
				)
				(justify left bottom)
			)
		)
		(property "Value" "CRCW080533R0FKEA"
			(at -3.02491 -6.429165 0)
			(unlocked yes)
			(layer "F.SilkS")
			(hide yes)
			(effects
				(font
					(size 0.762 0.762)
					(thickness 0.2286)
				)
				(justify left bottom)
			)
		)
		(sheetname "04-PCIe_JTAG")
		(sheetfile "04-PCIe_JTAG.kicad_sch")
		(duplicate_pad_numbers_are_jumpers no)
		(fp_line
			(start 0 0.762)
			(end 0 -0.762)
			(stroke
				(width 0.1524)
				(type solid)
			)
			(layer "F.SilkS")
		)
		(pad "1" smd rect
			(at -1 0 90)
			(size 1.45 0.95)
			(layers "F.Cu" "F.Mask" "F.Paste")
			(net "FPGA_TDO")
		)
		(pad "2" smd rect
			(at 1 0 90)
			(size 1.45 0.95)
			(layers "F.Cu" "F.Mask" "F.Paste")
			(net "NetP4_3")
		)
	)
	(footprint "Passives:SOT65P210X110-3N"
		(layer "F.Cu")
		(at 200.9416 145.61546)
		(property "Reference" "D8"
			(at -0.22 -1.605915 0)
			(unlocked yes)
			(layer "F.SilkS")
			(effects
				(font
					(size 0.762 0.762)
					(thickness 0.2286)
				)
				(justify left bottom)
			)
		)
		(property "Value" "BAT54SW"
			(at 3.33084 8.222185 0)
			(unlocked yes)
			(layer "F.SilkS")
			(hide yes)
			(effects
				(font
					(size 0.762 0.762)
					(thickness 0.2286)
				)
				(justify left bottom)
			)
		)
		(sheetname "04-PCIe_JTAG")
		(sheetfile "04-PCIe_JTAG.kicad_sch")
		(duplicate_pad_numbers_are_jumpers no)
		(fp_line
			(start -0.325 -1.1)
			(end 0.675 -1.1)
			(stroke
				(width 0.2)
				(type solid)
			)
			(layer "F.SilkS")
		)
		(fp_line
			(start -0.325 1.09999)
			(end 0.675 1.09999)
			(stroke
				(width 0.2)
				(type solid)
			)
			(layer "F.SilkS")
		)
		(fp_line
			(start 0.675 -0.65)
			(end 0.675 -1.1)
			(stroke
				(width 0.2)
				(type solid)
			)
			(layer "F.SilkS")
		)
		(fp_line
			(start 0.675 1.09999)
			(end 0.675 0.65)
			(stroke
				(width 0.2)
				(type solid)
			)
			(layer "F.SilkS")
		)
		(fp_circle
			(center -1.125 -1.45001)
			(end -1.125 -1.57501)
			(stroke
				(width 0.25)
				(type solid)
			)
			(fill no)
			(layer "F.SilkS")
		)
		(pad "1" smd rect
			(at -1.125 -0.65 90)
			(size 0.5 0.9)
			(layers "F.Cu" "F.Mask" "F.Paste")
			(net "GND")
		)
		(pad "2" smd rect
			(at -1.125 0.65 90)
			(size 0.5 0.9)
			(layers "F.Cu" "F.Mask" "F.Paste")
			(net "+3.3V")
		)
		(pad "3" smd rect
			(at 1.125 0 90)
			(size 0.5 0.9)
			(layers "F.Cu" "F.Mask" "F.Paste")
			(net "FPGA_TDI")
		)
	)
	(footprint "Vault:FP-711AT-MFG"
		(layer "F.Cu")
		(at 113.1216 80.91363)
		(property "Reference" "U25"
			(at -0.2968 -1.570509 0)
			(unlocked yes)
			(layer "F.SilkS")
			(effects
				(font
					(size 0.762 0.762)
					(thickness 0.2032)
				)
			)
		)
		(property "Value" "NCP176AMX330TCG"
			(at 10.016735 2.579871 0)
			(unlocked yes)
			(layer "F.SilkS")
			(hide yes)
			(effects
				(font
					(size 0.762 0.762)
					(thickness 0.2032)
				)
			)
		)
		(sheetname "05-GPS_IMU_SENSORS")
		(sheetfile "05-GPS_IMU_SENSORS.kicad_sch")
		(duplicate_pad_numbers_are_jumpers no)
		(fp_line
			(start -0.625 -0.925)
			(end 0.625 -0.925)
			(stroke
				(width 0.2)
				(type solid)
			)
			(layer "F.SilkS")
		)
		(fp_line
			(start -0.615 0.925)
			(end 0.635 0.925)
			(stroke
				(width 0.2)
				(type solid)
			)
			(layer "F.SilkS")
		)
		(fp_circle
			(center -1.225 -0.4)
			(end -1.225 -0.525)
			(stroke
				(width 0.25)
				(type solid)
			)
			(fill no)
			(layer "F.SilkS")
		)
		(fp_line
			(start -0.8 -0.725)
			(end 0.8 -0.725)
			(stroke
				(width 0.2)
				(type solid)
			)
			(layer "F.CrtYd")
		)
		(fp_line
			(start -0.8 0.725)
			(end -0.8 -0.725)
			(stroke
				(width 0.2)
				(type solid)
			)
			(layer "F.CrtYd")
		)
		(fp_line
			(start -0.8 0.725)
			(end 0.8 0.725)
			(stroke
				(width 0.2)
				(type solid)
			)
			(layer "F.CrtYd")
		)
		(fp_line
			(start 0.8 0.725)
			(end 0.8 -0.725)
			(stroke
				(width 0.2)
				(type solid)
			)
			(layer "F.CrtYd")
		)
		(fp_line
			(start -0.8 -0.725)
			(end 0.8 -0.725)
			(stroke
				(width 0.2)
				(type solid)
			)
			(layer "F.Fab")
		)
		(fp_line
			(start -0.8 0.725)
			(end -0.8 -0.725)
			(stroke
				(width 0.2)
				(type solid)
			)
			(layer "F.Fab")
		)
		(fp_line
			(start -0.8 0.725)
			(end 0.8 0.725)
			(stroke
				(width 0.2)
				(type solid)
			)
			(layer "F.Fab")
		)
		(fp_line
			(start -0.5 0)
			(end 0.5 0)
			(stroke
				(width 0.1)
				(type solid)
			)
			(layer "F.Fab")
		)
		(fp_line
			(start 0 0.49999)
			(end 0 -0.5)
			(stroke
				(width 0.1)
				(type solid)
			)
			(layer "F.Fab")
		)
		(fp_line
			(start 0.8 0.725)
			(end 0.8 -0.725)
			(stroke
				(width 0.2)
				(type solid)
			)
			(layer "F.Fab")
		)
		(fp_text user "${REFERENCE}"
			(at 0 0.28425 0)
			(unlocked yes)
			(layer "F.Fab")
			(effects
				(font
					(face "Arial")
					(size 0.63 0.63)
					(thickness 0.1)
				)
				(justify left bottom)
			)
		)
		(pad "1" smd rect
			(at -0.515 -0.4)
			(size 0.37 0.24)
			(layers "F.Cu" "F.Mask" "F.Paste")
			(net "BNO_P3V3")
			(solder_mask_margin 0)
			(solder_paste_margin 0)
		)
		(pad "2" smd rect
			(at -0.515 0)
			(size 0.37 0.24)
			(layers "F.Cu" "F.Mask" "F.Paste")
			(net "BNO_P3V3")
			(solder_mask_margin 0)
			(solder_paste_margin 0)
		)
		(pad "3" smd rect
			(at -0.515 0.39999)
			(size 0.37 0.24)
			(layers "F.Cu" "F.Mask" "F.Paste")
			(net "GND")
			(solder_mask_margin 0)
			(solder_paste_margin 0)
		)
		(pad "4" smd rect
			(at 0.515 0.39999)
			(size 0.37 0.24)
			(layers "F.Cu" "F.Mask" "F.Paste")
			(net "+5.0V")
			(solder_mask_margin 0)
			(solder_paste_margin 0)
		)
		(pad "5" smd rect
			(at 0.515 0)
			(size 0.37 0.24)
			(layers "F.Cu" "F.Mask" "F.Paste")
			(solder_mask_margin 0)
			(solder_paste_margin 0)
		)
		(pad "6" smd rect
			(at 0.515 -0.4)
			(size 0.37 0.24)
			(layers "F.Cu" "F.Mask" "F.Paste")
			(net "+5.0V")
			(solder_mask_margin 0)
			(solder_paste_margin 0)
		)
		(pad "7" smd rect
			(at 0 0)
			(size 0.4 1.08)
			(layers "F.Cu" "F.Mask" "F.Paste")
			(net "GND")
			(solder_mask_margin 0)
			(solder_paste_margin 0)
		)
	)
	(footprint "Vault:FP-GRM31C-0_2-e0_3_0_8-IPC_C"
		(layer "F.Cu")
		(at 79.9216 57.6162 180)
		(property "Reference" "C12"
			(at 4.1 -0.493345 0)
			(unlocked yes)
			(layer "F.SilkS")
			(effects
				(font
					(size 0.762 0.762)
					(thickness 0.2286)
				)
				(justify left bottom)
			)
		)
		(property "Value" "4.7uF_50V_1206"
			(at -1.9013 -25.814045 0)
			(unlocked yes)
			(layer "F.SilkS")
			(hide yes)
			(effects
				(font
					(size 0.762 0.762)
					(thickness 0.2286)
				)
				(justify left bottom)
			)
		)
		(sheetname "03-POWER")
		(sheetfile "03-POWER.kicad_sch")
		(duplicate_pad_numbers_are_jumpers no)
		(fp_line
			(start 0.39847 0.9)
			(end -0.39846 0.9)
			(stroke
				(width 0.2)
				(type solid)
			)
			(layer "F.SilkS")
		)
		(fp_line
			(start 0.39847 -0.9)
			(end -0.39846 -0.9)
			(stroke
				(width 0.2)
				(type solid)
			)
			(layer "F.SilkS")
		)
		(fp_line
			(start 1.9531 1)
			(end -1.9531 1)
			(stroke
				(width 0.2)
				(type solid)
			)
			(layer "F.CrtYd")
		)
		(fp_line
			(start 1.9531 -1)
			(end 1.9531 1)
			(stroke
				(width 0.2)
				(type solid)
			)
			(layer "F.CrtYd")
		)
		(fp_line
			(start 1.9531 -1)
			(end -1.9531 -1)
			(stroke
				(width 0.2)
				(type solid)
			)
			(layer "F.CrtYd")
		)
		(fp_line
			(start -1.9531 -1)
			(end -1.9531 1)
			(stroke
				(width 0.2)
				(type solid)
			)
			(layer "F.CrtYd")
		)
		(fp_line
			(start 1.9531 1)
			(end -1.9531 1)
			(stroke
				(width 0.2)
				(type solid)
			)
			(layer "F.Fab")
		)
		(fp_line
			(start 1.9531 -1)
			(end 1.9531 1)
			(stroke
				(width 0.2)
				(type solid)
			)
			(layer "F.Fab")
		)
		(fp_line
			(start 1.9531 -1)
			(end -1.9531 -1)
			(stroke
				(width 0.2)
				(type solid)
			)
			(layer "F.Fab")
		)
		(fp_line
			(start 0.5 0)
			(end -0.5 0)
			(stroke
				(width 0.1)
				(type solid)
			)
			(layer "F.Fab")
		)
		(fp_line
			(start 0 -0.5)
			(end 0 0.5)
			(stroke
				(width 0.1)
				(type solid)
			)
			(layer "F.Fab")
		)
		(fp_line
			(start -1.9531 -1)
			(end -1.9531 1)
			(stroke
				(width 0.2)
				(type solid)
			)
			(layer "F.Fab")
		)
		(fp_text user "${REFERENCE}"
			(at -0.00001 0.09601 180)
			(unlocked yes)
			(layer "F.Fab")
			(effects
				(font
					(face "Arial")
					(size 0.63 0.63)
					(thickness 0.1)
				)
				(justify left bottom)
			)
		)
		(pad "1" smd rect
			(at -1.27578 0 180)
			(size 1.15464 1.7062)
			(layers "F.Cu" "F.Mask" "F.Paste")
			(net "+12V")
			(solder_mask_margin 0)
			(solder_paste_margin 0)
		)
		(pad "2" smd rect
			(at 1.27578 0 180)
			(size 1.15464 1.7062)
			(layers "F.Cu" "F.Mask" "F.Paste")
			(net "GND")
			(solder_mask_margin 0)
			(solder_paste_margin 0)
		)
	)
	(footprint "Vault:FP-LTST-C191KGKT-MFG"
		(layer "F.Cu")
		(at 225.2716 102.38745)
		(property "Reference" "D12"
			(at -3.90792 -0.155439 0)
			(unlocked yes)
			(layer "F.SilkS")
			(effects
				(font
					(size 0.762 0.762)
					(thickness 0.2032)
				)
			)
		)
		(property "Value" "LTST-C191KGKT"
			(at -3.494271 8.97586 270)
			(unlocked yes)
			(layer "F.SilkS")
			(hide yes)
			(effects
				(font
					(size 0.762 0.762)
					(thickness 0.2032)
				)
			)
		)
		(sheetname "08-DIPSwitches_I2C")
		(sheetfile "08-DIPSwitches_I2C.kicad_sch")
		(duplicate_pad_numbers_are_jumpers no)
		(fp_line
			(start -0.85 -0.775)
			(end 0.85 -0.775)
			(stroke
				(width 0.2)
				(type solid)
			)
			(layer "F.SilkS")
		)
		(fp_line
			(start -0.85 0.775)
			(end 0.85 0.775)
			(stroke
				(width 0.2)
				(type solid)
			)
			(layer "F.SilkS")
		)
		(fp_circle
			(center -1.7 0)
			(end -1.7 -0.125)
			(stroke
				(width 0.25)
				(type solid)
			)
			(fill no)
			(layer "F.SilkS")
		)
		(fp_line
			(start -1.25 -0.55)
			(end 1.25 -0.55)
			(stroke
				(width 0.2)
				(type solid)
			)
			(layer "F.CrtYd")
		)
		(fp_line
			(start -1.25 0.55)
			(end -1.25 -0.55)
			(stroke
				(width 0.2)
				(type solid)
			)
			(layer "F.CrtYd")
		)
		(fp_line
			(start -1.25 0.55)
			(end 1.25 0.55)
			(stroke
				(width 0.2)
				(type solid)
			)
			(layer "F.CrtYd")
		)
		(fp_line
			(start 1.25 0.55)
			(end 1.25 -0.55)
			(stroke
				(width 0.2)
				(type solid)
			)
			(layer "F.CrtYd")
		)
		(fp_line
			(start -1.25 -0.55)
			(end 1.25 -0.55)
			(stroke
				(width 0.2)
				(type solid)
			)
			(layer "F.Fab")
		)
		(fp_line
			(start -1.25 0.55)
			(end -1.25 -0.55)
			(stroke
				(width 0.2)
				(type solid)
			)
			(layer "F.Fab")
		)
		(fp_line
			(start -1.25 0.55)
			(end 1.25 0.55)
			(stroke
				(width 0.2)
				(type solid)
			)
			(layer "F.Fab")
		)
		(fp_line
			(start -0.5 0)
			(end 0.5 0)
			(stroke
				(width 0.1)
				(type solid)
			)
			(layer "F.Fab")
		)
		(fp_line
			(start 0 0.5)
			(end 0 -0.5)
			(stroke
				(width 0.1)
				(type solid)
			)
			(layer "F.Fab")
		)
		(fp_line
			(start 1.25 0.55)
			(end 1.25 -0.55)
			(stroke
				(width 0.2)
				(type solid)
			)
			(layer "F.Fab")
		)
		(fp_text user "${REFERENCE}"
			(at 0 0.29534 360)
			(unlocked yes)
			(layer "F.Fab")
			(effects
				(font
					(face "Arial")
					(size 0.63 0.63)
					(thickness 0.1)
				)
				(justify left bottom)
			)
		)
		(pad "1" smd rect
			(at -0.75 0)
			(size 0.8 0.8)
			(layers "F.Cu" "F.Mask" "F.Paste")
			(net "NetD12_1")
			(solder_mask_margin 0)
			(solder_paste_margin 0)
		)
		(pad "2" smd rect
			(at 0.75 0)
			(size 0.8 0.8)
			(layers "F.Cu" "F.Mask" "F.Paste")
			(net "+3.3V")
			(solder_mask_margin 0)
			(solder_paste_margin 0)
		)
	)
	(footprint "Vault:FP-0402-L_1_0_0_05-W_0_5-IPC_A"
		(layer "F.Cu")
		(at 162.25767 85.5662 180)
		(property "Reference" "C82"
			(at 2.00747 0.023069 0)
			(unlocked yes)
			(layer "F.SilkS")
			(effects
				(font
					(size 0.762 0.762)
					(thickness 0.2286)
				)
			)
		)
		(property "Value" "1uF_16V_0402"
			(at -2.744951 8.290315 90)
			(unlocked yes)
			(layer "F.SilkS")
			(hide yes)
			(effects
				(font
					(size 0.762 0.762)
					(thickness 0.2286)
				)
			)
		)
		(sheetname "03-POWER")
		(sheetfile "03-POWER.kicad_sch")
		(duplicate_pad_numbers_are_jumpers no)
		(fp_line
			(start 0.83623 0.73624)
			(end -0.83624 0.73624)
			(stroke
				(width 0.2)
				(type solid)
			)
			(layer "F.SilkS")
		)
		(fp_line
			(start 0.83623 -0.73624)
			(end -0.83624 -0.73624)
			(stroke
				(width 0.2)
				(type solid)
			)
			(layer "F.SilkS")
		)
		(fp_line
			(start 1.03623 0.53624)
			(end -1.03624 0.53624)
			(stroke
				(width 0.2)
				(type solid)
			)
			(layer "F.CrtYd")
		)
		(fp_line
			(start 1.03623 -0.53624)
			(end 1.03623 0.53624)
			(stroke
				(width 0.2)
				(type solid)
			)
			(layer "F.CrtYd")
		)
		(fp_line
			(start 1.03623 -0.53624)
			(end -1.03624 -0.53624)
			(stroke
				(width 0.2)
				(type solid)
			)
			(layer "F.CrtYd")
		)
		(fp_line
			(start -1.03624 -0.53624)
			(end -1.03624 0.53624)
			(stroke
				(width 0.2)
				(type solid)
			)
			(layer "F.CrtYd")
		)
		(fp_line
			(start 1.03623 0.53624)
			(end -1.03624 0.53624)
			(stroke
				(width 0.2)
				(type solid)
			)
			(layer "F.Fab")
		)
		(fp_line
			(start 1.03623 -0.53624)
			(end 1.03623 0.53624)
			(stroke
				(width 0.2)
				(type solid)
			)
			(layer "F.Fab")
		)
		(fp_line
			(start 1.03623 -0.53624)
			(end -1.03624 -0.53624)
			(stroke
				(width 0.2)
				(type solid)
			)
			(layer "F.Fab")
		)
		(fp_line
			(start 0.5 0)
			(end -0.5 0)
			(stroke
				(width 0.1)
				(type solid)
			)
			(layer "F.Fab")
		)
		(fp_line
			(start 0 -0.5)
			(end 0 0.5)
			(stroke
				(width 0.1)
				(type solid)
			)
			(layer "F.Fab")
		)
		(fp_line
			(start -1.03624 -0.53624)
			(end -1.03624 0.53624)
			(stroke
				(width 0.2)
				(type solid)
			)
			(layer "F.Fab")
		)
		(fp_text user "${REFERENCE}"
			(at -0.00001 0.09602 180)
			(unlocked yes)
			(layer "F.Fab")
			(effects
				(font
					(face "Arial")
					(size 0.63 0.63)
					(thickness 0.1)
				)
				(justify left bottom)
			)
		)
		(pad "1" smd rect
			(at -0.47856 0 180)
			(size 0.71535 0.67248)
			(layers "F.Cu" "F.Mask" "F.Paste")
			(net "+3.3V")
			(solder_mask_margin 0)
			(solder_paste_margin 0)
		)
		(pad "2" smd rect
			(at 0.47856 0 180)
			(size 0.71535 0.67248)
			(layers "F.Cu" "F.Mask" "F.Paste")
			(net "GND")
			(solder_mask_margin 0)
			(solder_paste_margin 0)
		)
	)
	(footprint "Vault:RESC1005X40X25NL05T05"
		(layer "F.Cu")
		(at 172.4216 110.8162 180)
		(property "Reference" "R126"
			(at -0.50888 1.454769 0)
			(unlocked yes)
			(layer "F.SilkS")
			(effects
				(font
					(size 0.762 0.762)
					(thickness 0.2032)
				)
			)
		)
		(property "Value" "27_1%_0402"
			(at -2.732271 7.35092 90)
			(unlocked yes)
			(layer "F.SilkS")
			(hide yes)
			(effects
				(font
					(size 0.762 0.762)
					(thickness 0.2032)
				)
			)
		)
		(sheetname "08-DIPSwitches_I2C")
		(sheetfile "08-DIPSwitches_I2C.kicad_sch")
		(duplicate_pad_numbers_are_jumpers no)
		(pad "1" smd rect
			(at -0.45 0 270)
			(size 0.55 0.55)
			(layers "F.Cu" "F.Mask" "F.Paste")
			(net "GND")
		)
		(pad "2" smd rect
			(at 0.45 0 270)
			(size 0.55 0.55)
			(layers "F.Cu" "F.Mask" "F.Paste")
			(net "NetR126_2")
		)
	)
	(footprint "SA53:SolderSocket"
		(locked yes)
		(layer "F.Cu")
		(at 119.4216 140.0162 90)
		(property "Reference" "SKT1"
			(at -3.426921 1.2286 0)
			(unlocked yes)
			(layer "F.SilkS")
			(effects
				(font
					(size 0.762 0.762)
					(thickness 0.2286)
				)
			)
		)
		(property "Value" "0332-0-43-80-18-27-10-0"
			(at -2.910071 16.1362 0)
			(unlocked yes)
			(layer "F.SilkS")
			(hide yes)
			(effects
				(font
					(size 0.762 0.762)
					(thickness 0.2286)
				)
			)
		)
		(sheetname "06-MAC")
		(sheetfile "06-MAC.kicad_sch")
		(duplicate_pad_numbers_are_jumpers no)
		(pad "1" thru_hole circle
			(at 0 0 90)
			(size 2.54 2.54)
			(drill 2.0066)
			(layers "*.Cu" "*.Mask")
			(remove_unused_layers no)
			(net "MAC_TX")
			(thermal_bridge_angle 90)
		)
	)
	(footprint "Vault:FP-RUT0012A-MFG"
		(layer "F.Cu")
		(at 154.8216 116.0162)
		(property "Reference" "U26"
			(at 2.3032 -2.273079 0)
			(unlocked yes)
			(layer "F.SilkS")
			(effects
				(font
					(size 0.762 0.762)
					(thickness 0.2032)
				)
			)
		)
		(property "Value" "TMUX1072RUTR"
			(at 7.401265 3.164071 0)
			(unlocked yes)
			(layer "F.SilkS")
			(hide yes)
			(effects
				(font
					(size 0.762 0.762)
					(thickness 0.2032)
				)
			)
		)
		(sheetname "08-DIPSwitches_I2C")
		(sheetfile "08-DIPSwitches_I2C.kicad_sch")
		(duplicate_pad_numbers_are_jumpers no)
		(fp_line
			(start -0.9 -1.525)
			(end 0.9 -1.525)
			(stroke
				(width 0.2)
				(type solid)
			)
			(layer "F.SilkS")
		)
		(fp_line
			(start -0.9 1.525)
			(end 0.9 1.525)
			(stroke
				(width 0.2)
				(type solid)
			)
			(layer "F.SilkS")
		)
		(fp_circle
			(center -1.575 -0.8)
			(end -1.575 -0.925)
			(stroke
				(width 0.25)
				(type solid)
			)
			(fill no)
			(layer "F.SilkS")
		)
		(fp_rect
			(start -0.85 -0.3)
			(end -0.35 -0.5)
			(stroke
				(width 0)
				(type default)
			)
			(fill yes)
			(layer "F.Paste")
		)
		(fp_rect
			(start -0.85 0.1)
			(end -0.35 -0.1)
			(stroke
				(width 0)
				(type default)
			)
			(fill yes)
			(layer "F.Paste")
		)
		(fp_rect
			(start -0.85 0.5)
			(end -0.35 0.3)
			(stroke
				(width 0)
				(type default)
			)
			(fill yes)
			(layer "F.Paste")
		)
		(fp_rect
			(start -0.85 0.9)
			(end -0.35 0.7)
			(stroke
				(width 0)
				(type default)
			)
			(fill yes)
			(layer "F.Paste")
		)
		(fp_rect
			(start -0.1 -0.5)
			(end 0.1 -1)
			(stroke
				(width 0)
				(type default)
			)
			(fill yes)
			(layer "F.Paste")
		)
		(fp_rect
			(start -0.1 1)
			(end 0.1 0.5)
			(stroke
				(width 0)
				(type default)
			)
			(fill yes)
			(layer "F.Paste")
		)
		(fp_rect
			(start 0.35 -0.7)
			(end 0.85 -0.9)
			(stroke
				(width 0)
				(type default)
			)
			(fill yes)
			(layer "F.Paste")
		)
		(fp_rect
			(start 0.35 -0.3)
			(end 0.85 -0.5)
			(stroke
				(width 0)
				(type default)
			)
			(fill yes)
			(layer "F.Paste")
		)
		(fp_rect
			(start 0.35 0.1)
			(end 0.85 -0.1)
			(stroke
				(width 0)
				(type default)
			)
			(fill yes)
			(layer "F.Paste")
		)
		(fp_rect
			(start 0.35 0.5)
			(end 0.85 0.3)
			(stroke
				(width 0)
				(type default)
			)
			(fill yes)
			(layer "F.Paste")
		)
		(fp_rect
			(start 0.35 0.9)
			(end 0.85 0.7)
			(stroke
				(width 0)
				(type default)
			)
			(fill yes)
			(layer "F.Paste")
		)
		(fp_poly
			(pts
				(xy -0.5 -1) (xy -0.35 -1) (xy -0.35 -0.7) (xy -0.85 -0.7) (xy -0.85 -0.9) (xy -0.5 -0.9)
			)
			(stroke
				(width 0)
				(type default)
			)
			(fill yes)
			(layer "F.Paste")
		)
		(fp_line
			(start -1.05 -1.2)
			(end 1.05 -1.2)
			(stroke
				(width 0.2)
				(type solid)
			)
			(layer "F.CrtYd")
		)
		(fp_line
			(start -1.05 1.2)
			(end -1.05 -1.2)
			(stroke
				(width 0.2)
				(type solid)
			)
			(layer "F.CrtYd")
		)
		(fp_line
			(start -1.05 1.2)
			(end 1.05 1.2)
			(stroke
				(width 0.2)
				(type solid)
			)
			(layer "F.CrtYd")
		)
		(fp_line
			(start 1.05 1.2)
			(end 1.05 -1.2)
			(stroke
				(width 0.2)
				(type solid)
			)
			(layer "F.CrtYd")
		)
		(fp_line
			(start -1.05 -1.2)
			(end 1.05 -1.2)
			(stroke
				(width 0.2)
				(type solid)
			)
			(layer "F.Fab")
		)
		(fp_line
			(start -1.05 1.2)
			(end -1.05 -1.2)
			(stroke
				(width 0.2)
				(type solid)
			)
			(layer "F.Fab")
		)
		(fp_line
			(start -1.05 1.2)
			(end 1.05 1.2)
			(stroke
				(width 0.2)
				(type solid)
			)
			(layer "F.Fab")
		)
		(fp_line
			(start -0.5 0)
			(end 0.5 0)
			(stroke
				(width 0.1)
				(type solid)
			)
			(layer "F.Fab")
		)
		(fp_line
			(start 0 0.5)
			(end 0 -0.5)
			(stroke
				(width 0.1)
				(type solid)
			)
			(layer "F.Fab")
		)
		(fp_line
			(start 1.05 1.2)
			(end 1.05 -1.2)
			(stroke
				(width 0.2)
				(type solid)
			)
			(layer "F.Fab")
		)
		(fp_text user "${REFERENCE}"
			(at -0.00001 0.09602 0)
			(unlocked yes)
			(layer "F.Fab")
			(effects
				(font
					(face "Arial")
					(size 0.63 0.63)
					(thickness 0.1)
				)
				(justify left bottom)
			)
		)
		(pad "" smd custom
			(at -0.5 -1.1)
			(size 0.000001 0.000001)
			(layers "F.Cu" "F.Mask")
			(solder_mask_margin 0)
			(thermal_bridge_angle 90)
			(options
				(clearance outline)
				(anchor circle)
			)
			(primitives
				(gr_poly
					(pts
						(xy 0 0) (xy 0.15 0) (xy 0.15 0.4) (xy -0.45 0.4) (xy -0.45 0.2) (xy 0 0.2)
					)
					(width 0)
					(fill yes)
				)
			)
		)
		(pad "1" smd circle
			(at -0.45 -0.8)
			(size 0.18 0.18)
			(layers "F.Cu" "F.Mask" "F.Paste")
			(net "DIP_SW_MACSER_SEL")
			(solder_mask_margin 0)
			(solder_paste_margin -1000)
			(thermal_bridge_angle 90)
		)
		(pad "2" smd rect
			(at -0.65 -0.4)
			(size 0.6 0.2)
			(layers "F.Cu" "F.Mask" "F.Paste")
			(net "NetR94_2")
			(solder_mask_margin 0)
			(solder_paste_margin -1000)
		)
		(pad "3" smd rect
			(at -0.65 0)
			(size 0.6 0.2)
			(layers "F.Cu" "F.Mask" "F.Paste")
			(net "GND")
			(solder_mask_margin 0)
			(solder_paste_margin -1000)
		)
		(pad "4" smd rect
			(at -0.65 0.4)
			(size 0.6 0.2)
			(layers "F.Cu" "F.Mask" "F.Paste")
			(net "NetR111_2")
			(solder_mask_margin 0)
			(solder_paste_margin -1000)
		)
		(pad "5" smd rect
			(at -0.65 0.8)
			(size 0.6 0.2)
			(layers "F.Cu" "F.Mask" "F.Paste")
			(net "DIP_SW_MACSER_SEL")
			(solder_mask_margin 0)
			(solder_paste_margin -1000)
		)
		(pad "6" smd rect
			(at 0 0.8)
			(size 0.2 0.6)
			(layers "F.Cu" "F.Mask" "F.Paste")
			(net "GND")
			(solder_mask_margin 0)
			(solder_paste_margin -1000)
		)
		(pad "7" smd rect
			(at 0.65 0.8)
			(size 0.6 0.2)
			(layers "F.Cu" "F.Mask" "F.Paste")
			(net "MAC_RX")
			(solder_mask_margin 0)
			(solder_paste_margin -1000)
		)
		(pad "8" smd rect
			(at 0.65 0.4)
			(size 0.6 0.2)
			(layers "F.Cu" "F.Mask" "F.Paste")
			(net "NetR95_2")
			(solder_mask_margin 0)
			(solder_paste_margin -1000)
		)
		(pad "9" smd rect
			(at 0.65 0)
			(size 0.6 0.2)
			(layers "F.Cu" "F.Mask" "F.Paste")
			(net "+3.3V")
			(solder_mask_margin 0)
			(solder_paste_margin -1000)
		)
		(pad "10" smd rect
			(at 0.65 -0.4)
			(size 0.6 0.2)
			(layers "F.Cu" "F.Mask" "F.Paste")
			(net "NetR76_2")
			(solder_mask_margin 0)
			(solder_paste_margin -1000)
		)
		(pad "11" smd rect
			(at 0.65 -0.8)
			(size 0.6 0.2)
			(layers "F.Cu" "F.Mask" "F.Paste")
			(net "MAC_TX")
			(solder_mask_margin 0)
			(solder_paste_margin -1000)
		)
		(pad "12" smd rect
			(at 0 -0.8)
			(size 0.2 0.6)
			(layers "F.Cu" "F.Mask" "F.Paste")
			(net "GND")
			(solder_mask_margin 0)
			(solder_paste_margin -1000)
		)
	)
	(footprint "SamacSys:155124M173200"
		(layer "F.Cu")
		(at 67.4466 71.6662 90)
		(property "Reference" "D13"
			(at -4.7 -0.231655 90)
			(unlocked yes)
			(layer "F.SilkS")
			(effects
				(font
					(size 0.762 0.762)
					(thickness 0.2286)
				)
				(justify left bottom)
			)
		)
		(property "Value" "155124M173200"
			(at -4.043045 -0.5715 0)
			(unlocked yes)
			(layer "F.SilkS")
			(hide yes)
			(effects
				(font
					(size 0.762 0.762)
					(thickness 0.2286)
				)
				(justify left bottom)
			)
		)
		(sheetname "02-USER_IO_STATUS")
		(sheetfile "02-USER_IO_STATUS.kicad_sch")
		(duplicate_pad_numbers_are_jumpers no)
		(fp_line
			(start -0.8 0.5)
			(end 0.8 0.5)
			(stroke
				(width 0.1)
				(type solid)
			)
			(layer "F.SilkS")
		)
		(fp_arc
			(start -2 -0.0754)
			(mid -1.9746 -0.05)
			(end -2 -0.0246)
			(stroke
				(width 0.381)
				(type solid)
			)
			(layer "F.SilkS")
		)
		(fp_arc
			(start -2 -0.0246)
			(mid -2.0254 -0.05)
			(end -2 -0.0754)
			(stroke
				(width 0.381)
				(type solid)
			)
			(layer "F.SilkS")
		)
		(pad "1" smd rect
			(at -1.4 0 180)
			(size 0.9 0.6)
			(layers "F.Cu" "F.Mask" "F.Paste")
			(net "+3.3V")
		)
		(pad "2" smd rect
			(at -0.45 -0.325 90)
			(size 0.6 0.55)
			(layers "F.Cu" "F.Mask" "F.Paste")
			(net "NetD13_2")
		)
		(pad "3" smd rect
			(at 0.45 -0.325 90)
			(size 0.6 0.55)
			(layers "F.Cu" "F.Mask" "F.Paste")
			(net "NetD13_3")
		)
		(pad "4" smd rect
			(at 1.4 0 180)
			(size 0.9 0.6)
			(layers "F.Cu" "F.Mask" "F.Paste")
			(net "NetD13_4")
		)
	)
	(footprint "Vault:FP-GRM31C-0_2-e0_3_0_8-IPC_C"
		(layer "F.Cu")
		(at 79.9216 59.9162 180)
		(property "Reference" "C11"
			(at 4 -0.493345 0)
			(unlocked yes)
			(layer "F.SilkS")
			(effects
				(font
					(size 0.762 0.762)
					(thickness 0.2286)
				)
				(justify left bottom)
			)
		)
		(property "Value" "4.7uF_50V_1206"
			(at 0.1957 -23.717045 0)
			(unlocked yes)
			(layer "F.SilkS")
			(hide yes)
			(effects
				(font
					(size 0.762 0.762)
					(thickness 0.2286)
				)
				(justify left bottom)
			)
		)
		(sheetname "03-POWER")
		(sheetfile "03-POWER.kicad_sch")
		(duplicate_pad_numbers_are_jumpers no)
		(fp_line
			(start 0.39847 0.9)
			(end -0.39846 0.9)
			(stroke
				(width 0.2)
				(type solid)
			)
			(layer "F.SilkS")
		)
		(fp_line
			(start 0.39847 -0.9)
			(end -0.39846 -0.9)
			(stroke
				(width 0.2)
				(type solid)
			)
			(layer "F.SilkS")
		)
		(fp_line
			(start 1.9531 1)
			(end -1.9531 1)
			(stroke
				(width 0.2)
				(type solid)
			)
			(layer "F.CrtYd")
		)
		(fp_line
			(start 1.9531 -1)
			(end 1.9531 1)
			(stroke
				(width 0.2)
				(type solid)
			)
			(layer "F.CrtYd")
		)
		(fp_line
			(start 1.9531 -1)
			(end -1.9531 -1)
			(stroke
				(width 0.2)
				(type solid)
			)
			(layer "F.CrtYd")
		)
		(fp_line
			(start -1.9531 -1)
			(end -1.9531 1)
			(stroke
				(width 0.2)
				(type solid)
			)
			(layer "F.CrtYd")
		)
		(fp_line
			(start 1.9531 1)
			(end -1.9531 1)
			(stroke
				(width 0.2)
				(type solid)
			)
			(layer "F.Fab")
		)
		(fp_line
			(start 1.9531 -1)
			(end 1.9531 1)
			(stroke
				(width 0.2)
				(type solid)
			)
			(layer "F.Fab")
		)
		(fp_line
			(start 1.9531 -1)
			(end -1.9531 -1)
			(stroke
				(width 0.2)
				(type solid)
			)
			(layer "F.Fab")
		)
		(fp_line
			(start 0.5 0)
			(end -0.5 0)
			(stroke
				(width 0.1)
				(type solid)
			)
			(layer "F.Fab")
		)
		(fp_line
			(start 0 -0.5)
			(end 0 0.5)
			(stroke
				(width 0.1)
				(type solid)
			)
			(layer "F.Fab")
		)
		(fp_line
			(start -1.9531 -1)
			(end -1.9531 1)
			(stroke
				(width 0.2)
				(type solid)
			)
			(layer "F.Fab")
		)
		(fp_text user "${REFERENCE}"
			(at -0.00001 0.09601 180)
			(unlocked yes)
			(layer "F.Fab")
			(effects
				(font
					(face "Arial")
					(size 0.63 0.63)
					(thickness 0.1)
				)
				(justify left bottom)
			)
		)
		(pad "1" smd rect
			(at -1.27578 0 180)
			(size 1.15464 1.7062)
			(layers "F.Cu" "F.Mask" "F.Paste")
			(net "+12V")
			(solder_mask_margin 0)
			(solder_paste_margin 0)
		)
		(pad "2" smd rect
			(at 1.27578 0 180)
			(size 1.15464 1.7062)
			(layers "F.Cu" "F.Mask" "F.Paste")
			(net "GND")
			(solder_mask_margin 0)
			(solder_paste_margin 0)
		)
	)
	(footprint "Vault:FP-1571983-4-MFG"
		(layer "F.Cu")
		(at 227.05584 106.89495 90)
		(property "Reference" "SW1"
			(at 2.328605 4.126931 90)
			(unlocked yes)
			(layer "F.SilkS")
			(effects
				(font
					(size 0.762 0.762)
					(thickness 0.2286)
				)
			)
		)
		(property "Value" "1571983-4"
			(at 3.998655 6.085081 90)
			(unlocked yes)
			(layer "F.SilkS")
			(hide yes)
			(effects
				(font
					(size 0.762 0.762)
					(thickness 0.2286)
				)
			)
		)
		(sheetname "08-DIPSwitches_I2C")
		(sheetfile "08-DIPSwitches_I2C.kicad_sch")
		(duplicate_pad_numbers_are_jumpers no)
		(fp_line
			(start 3.355 -3.225)
			(end 3.355 3.225)
			(stroke
				(width 0.2)
				(type solid)
			)
			(layer "F.SilkS")
		)
		(fp_line
			(start 2.66 -3.225)
			(end 3.355 -3.225)
			(stroke
				(width 0.2)
				(type solid)
			)
			(layer "F.SilkS")
		)
		(fp_line
			(start -3.355 -3.225)
			(end -2.66 -3.225)
			(stroke
				(width 0.2)
				(type solid)
			)
			(layer "F.SilkS")
		)
		(fp_line
			(start -3.355 -3.225)
			(end -3.355 3.225)
			(stroke
				(width 0.2)
				(type solid)
			)
			(layer "F.SilkS")
		)
		(fp_line
			(start 2.66 3.225)
			(end 3.355 3.225)
			(stroke
				(width 0.2)
				(type solid)
			)
			(layer "F.SilkS")
		)
		(fp_line
			(start -3.355 3.225)
			(end -2.66 3.225)
			(stroke
				(width 0.2)
				(type solid)
			)
			(layer "F.SilkS")
		)
		(fp_circle
			(center -3.22125 3.86576)
			(end -3.09625 3.86576)
			(stroke
				(width 0.25)
				(type solid)
			)
			(fill no)
			(layer "F.SilkS")
		)
		(fp_line
			(start 3.455 -4.53)
			(end 3.455 4.53)
			(stroke
				(width 0.2)
				(type solid)
			)
			(layer "F.CrtYd")
		)
		(fp_line
			(start -3.455 -4.53)
			(end 3.455 -4.53)
			(stroke
				(width 0.2)
				(type solid)
			)
			(layer "F.CrtYd")
		)
		(fp_line
			(start -3.455 -4.53)
			(end -3.455 4.53)
			(stroke
				(width 0.2)
				(type solid)
			)
			(layer "F.CrtYd")
		)
		(fp_line
			(start -3.455 4.53)
			(end 3.455 4.53)
			(stroke
				(width 0.2)
				(type solid)
			)
			(layer "F.CrtYd")
		)
		(fp_line
			(start 3.455 -4.53)
			(end 3.455 4.53)
			(stroke
				(width 0.2)
				(type solid)
			)
			(layer "F.Fab")
		)
		(fp_line
			(start -3.455 -4.53)
			(end 3.455 -4.53)
			(stroke
				(width 0.2)
				(type solid)
			)
			(layer "F.Fab")
		)
		(fp_line
			(start -3.455 -4.53)
			(end -3.455 4.53)
			(stroke
				(width 0.2)
				(type solid)
			)
			(layer "F.Fab")
		)
		(fp_line
			(start 0 -0.5)
			(end 0 0.5)
			(stroke
				(width 0.1)
				(type solid)
			)
			(layer "F.Fab")
		)
		(fp_line
			(start -0.5 0)
			(end 0.5 0)
			(stroke
				(width 0.1)
				(type solid)
			)
			(layer "F.Fab")
		)
		(fp_line
			(start -3.455 4.53)
			(end 3.455 4.53)
			(stroke
				(width 0.2)
				(type solid)
			)
			(layer "F.Fab")
		)
		(fp_text user "${REFERENCE}"
			(at -0.00001 0.09602 90)
			(unlocked yes)
			(layer "F.Fab")
			(effects
				(font
					(face "Arial")
					(size 0.63 0.63)
					(thickness 0.1)
				)
				(justify left bottom)
			)
		)
		(pad "1" smd rect
			(at -1.905 3.795 90)
			(size 0.76 1.27)
			(layers "F.Cu" "F.Mask" "F.Paste")
			(net "GND")
			(solder_mask_margin 0)
			(solder_paste_margin 0)
		)
		(pad "2" smd rect
			(at -0.635 3.795 90)
			(size 0.76 1.27)
			(layers "F.Cu" "F.Mask" "F.Paste")
			(net "GND")
			(solder_mask_margin 0)
			(solder_paste_margin 0)
		)
		(pad "3" smd rect
			(at 0.635 3.795 90)
			(size 0.76 1.27)
			(layers "F.Cu" "F.Mask" "F.Paste")
			(net "GND")
			(solder_mask_margin 0)
			(solder_paste_margin 0)
		)
		(pad "4" smd rect
			(at 1.905 3.795 90)
			(size 0.76 1.27)
			(layers "F.Cu" "F.Mask" "F.Paste")
			(net "GND")
			(solder_mask_margin 0)
			(solder_paste_margin 0)
		)
		(pad "5" smd rect
			(at 1.905 -3.795 90)
			(size 0.76 1.27)
			(layers "F.Cu" "F.Mask" "F.Paste")
			(solder_mask_margin 0)
			(solder_paste_margin 0)
		)
		(pad "6" smd rect
			(at 0.635 -3.795 90)
			(size 0.76 1.27)
			(layers "F.Cu" "F.Mask" "F.Paste")
			(net "DIP_SW_MACSER_SEL")
			(solder_mask_margin 0)
			(solder_paste_margin 0)
		)
		(pad "7" smd rect
			(at -0.635 -3.795 90)
			(size 0.76 1.27)
			(layers "F.Cu" "F.Mask" "F.Paste")
			(net "DIP_SW_PPS_SEL")
			(solder_mask_margin 0)
			(solder_paste_margin 0)
		)
		(pad "8" smd rect
			(at -1.905 -3.795 90)
			(size 0.76 1.27)
			(layers "F.Cu" "F.Mask" "F.Paste")
			(net "DIP_SW_UART_SEL")
			(solder_mask_margin 0)
			(solder_paste_margin 0)
		)
	)
	(footprint "Vault:FP-LTST-C191KGKT-MFG"
		(layer "F.Cu")
		(at 79.4216 52.1162)
		(property "Reference" "D9"
			(at -4.171405 -0.373079 0)
			(unlocked yes)
			(layer "F.SilkS")
			(effects
				(font
					(size 0.762 0.762)
					(thickness 0.2286)
				)
			)
		)
		(property "Value" "LTST-C191KGKT"
			(at 1.2818 2.452871 0)
			(unlocked yes)
			(layer "F.SilkS")
			(hide yes)
			(effects
				(font
					(size 0.762 0.762)
					(thickness 0.2286)
				)
			)
		)
		(sheetname "02-USER_IO_STATUS")
		(sheetfile "02-USER_IO_STATUS.kicad_sch")
		(duplicate_pad_numbers_are_jumpers no)
		(fp_line
			(start -0.85 -0.775)
			(end 0.85 -0.775)
			(stroke
				(width 0.2)
				(type solid)
			)
			(layer "F.SilkS")
		)
		(fp_line
			(start -0.85 0.775)
			(end 0.85 0.775)
			(stroke
				(width 0.2)
				(type solid)
			)
			(layer "F.SilkS")
		)
		(fp_circle
			(center -1.7 0)
			(end -1.7 -0.125)
			(stroke
				(width 0.25)
				(type solid)
			)
			(fill no)
			(layer "F.SilkS")
		)
		(fp_line
			(start -1.25 -0.55)
			(end 1.25 -0.55)
			(stroke
				(width 0.2)
				(type solid)
			)
			(layer "F.CrtYd")
		)
		(fp_line
			(start -1.25 0.55)
			(end -1.25 -0.55)
			(stroke
				(width 0.2)
				(type solid)
			)
			(layer "F.CrtYd")
		)
		(fp_line
			(start -1.25 0.55)
			(end 1.25 0.55)
			(stroke
				(width 0.2)
				(type solid)
			)
			(layer "F.CrtYd")
		)
		(fp_line
			(start 1.25 0.55)
			(end 1.25 -0.55)
			(stroke
				(width 0.2)
				(type solid)
			)
			(layer "F.CrtYd")
		)
		(fp_line
			(start -1.25 -0.55)
			(end 1.25 -0.55)
			(stroke
				(width 0.2)
				(type solid)
			)
			(layer "F.Fab")
		)
		(fp_line
			(start -1.25 0.55)
			(end -1.25 -0.55)
			(stroke
				(width 0.2)
				(type solid)
			)
			(layer "F.Fab")
		)
		(fp_line
			(start -1.25 0.55)
			(end 1.25 0.55)
			(stroke
				(width 0.2)
				(type solid)
			)
			(layer "F.Fab")
		)
		(fp_line
			(start -0.5 0)
			(end 0.5 0)
			(stroke
				(width 0.1)
				(type solid)
			)
			(layer "F.Fab")
		)
		(fp_line
			(start 0 0.5)
			(end 0 -0.5)
			(stroke
				(width 0.1)
				(type solid)
			)
			(layer "F.Fab")
		)
		(fp_line
			(start 1.25 0.55)
			(end 1.25 -0.55)
			(stroke
				(width 0.2)
				(type solid)
			)
			(layer "F.Fab")
		)
		(fp_text user "${REFERENCE}"
			(at 0 0.28425 360)
			(unlocked yes)
			(layer "F.Fab")
			(effects
				(font
					(face "Arial")
					(size 0.63 0.63)
					(thickness 0.1)
				)
				(justify left bottom)
			)
		)
		(pad "1" smd rect
			(at -0.75 0)
			(size 0.8 0.8)
			(layers "F.Cu" "F.Mask" "F.Paste")
			(net "NetD9_1")
			(solder_mask_margin 0)
			(solder_paste_margin 0)
		)
		(pad "2" smd rect
			(at 0.75 0)
			(size 0.8 0.8)
			(layers "F.Cu" "F.Mask" "F.Paste")
			(net "+3.3V")
			(solder_mask_margin 0)
			(solder_paste_margin 0)
		)
	)
	(footprint "Vault:RESC1005X40X25NL05T05"
		(layer "F.Cu")
		(at 151.9216 116.9162)
		(property "Reference" "R111"
			(at -2.2666 -0.102389 0)
			(unlocked yes)
			(layer "F.SilkS")
			(effects
				(font
					(size 0.762 0.762)
					(thickness 0.2032)
				)
			)
		)
		(property "Value" "27_1%_0402"
			(at -2.732271 7.35092 270)
			(unlocked yes)
			(layer "F.SilkS")
			(hide yes)
			(effects
				(font
					(size 0.762 0.762)
					(thickness 0.2032)
				)
			)
		)
		(sheetname "08-DIPSwitches_I2C")
		(sheetfile "08-DIPSwitches_I2C.kicad_sch")
		(duplicate_pad_numbers_are_jumpers no)
		(pad "1" smd rect
			(at -0.45 0 90)
			(size 0.55 0.55)
			(layers "F.Cu" "F.Mask" "F.Paste")
			(net "MAC_FPGA_UART_RX")
		)
		(pad "2" smd rect
			(at 0.45 0 90)
			(size 0.55 0.55)
			(layers "F.Cu" "F.Mask" "F.Paste")
			(net "NetR111_2")
		)
	)
	(footprint "Vault:FP-RUT0012A-MFG"
		(layer "F.Cu")
		(at 120.3216 79.1162 90)
		(property "Reference" "U31"
			(at 1.573069 0.203205 0)
			(unlocked yes)
			(layer "F.SilkS")
			(effects
				(font
					(size 0.762 0.762)
					(thickness 0.2032)
				)
			)
		)
		(property "Value" "TMUX1072RUTR"
			(at 7.401265 3.164071 90)
			(unlocked yes)
			(layer "F.SilkS")
			(hide yes)
			(effects
				(font
					(size 0.762 0.762)
					(thickness 0.2032)
				)
			)
		)
		(sheetname "11-M2_RCB_MUX")
		(sheetfile "11-M2_RCB_MUX.kicad_sch")
		(duplicate_pad_numbers_are_jumpers no)
		(fp_line
			(start -0.9 -1.525)
			(end 0.9 -1.525)
			(stroke
				(width 0.2)
				(type solid)
			)
			(layer "F.SilkS")
		)
		(fp_line
			(start -0.9 1.525)
			(end 0.9 1.525)
			(stroke
				(width 0.2)
				(type solid)
			)
			(layer "F.SilkS")
		)
		(fp_circle
			(center -1.575 -0.8)
			(end -1.45 -0.8)
			(stroke
				(width 0.25)
				(type solid)
			)
			(fill no)
			(layer "F.SilkS")
		)
		(fp_rect
			(start 0.350035 -0.699955)
			(end 0.850045 -0.899955)
			(stroke
				(width 0)
				(type default)
			)
			(fill yes)
			(layer "F.Paste")
		)
		(fp_rect
			(start -0.10003 -0.49997)
			(end 0.09997 -0.99997)
			(stroke
				(width 0)
				(type default)
			)
			(fill yes)
			(layer "F.Paste")
		)
		(fp_rect
			(start 0.34996 -0.30004)
			(end 0.84996 -0.50004)
			(stroke
				(width 0)
				(type default)
			)
			(fill yes)
			(layer "F.Paste")
		)
		(fp_rect
			(start -0.849965 -0.299955)
			(end -0.349955 -0.499955)
			(stroke
				(width 0)
				(type default)
			)
			(fill yes)
			(layer "F.Paste")
		)
		(fp_rect
			(start 0.34996 0.09996)
			(end 0.84996 -0.10004)
			(stroke
				(width 0)
				(type default)
			)
			(fill yes)
			(layer "F.Paste")
		)
		(fp_rect
			(start -0.84996 0.10004)
			(end -0.34996 -0.09996)
			(stroke
				(width 0)
				(type default)
			)
			(fill yes)
			(layer "F.Paste")
		)
		(fp_rect
			(start 0.34996 0.49996)
			(end 0.84996 0.29996)
			(stroke
				(width 0)
				(type default)
			)
			(fill yes)
			(layer "F.Paste")
		)
		(fp_rect
			(start -0.84996 0.50004)
			(end -0.34996 0.30004)
			(stroke
				(width 0)
				(type default)
			)
			(fill yes)
			(layer "F.Paste")
		)
		(fp_rect
			(start -0.85004 0.89996)
			(end -0.35004 0.69996)
			(stroke
				(width 0)
				(type default)
			)
			(fill yes)
			(layer "F.Paste")
		)
		(fp_rect
			(start 0.35004 0.90005)
			(end 0.85004 0.70005)
			(stroke
				(width 0)
				(type default)
			)
			(fill yes)
			(layer "F.Paste")
		)
		(fp_rect
			(start -0.099965 0.999975)
			(end 0.100035 0.499965)
			(stroke
				(width 0)
				(type default)
			)
			(fill yes)
			(layer "F.Paste")
		)
		(fp_poly
			(pts
				(xy -0.5 -1) (xy -0.35 -1) (xy -0.35 -0.7) (xy -0.85 -0.7) (xy -0.85 -0.9) (xy -0.5 -0.9)
			)
			(stroke
				(width 0)
				(type default)
			)
			(fill yes)
			(layer "F.Paste")
		)
		(fp_line
			(start 1.05 -1.2)
			(end 1.05 1.2)
			(stroke
				(width 0.2)
				(type solid)
			)
			(layer "F.CrtYd")
		)
		(fp_line
			(start -1.05 -1.2)
			(end 1.05 -1.2)
			(stroke
				(width 0.2)
				(type solid)
			)
			(layer "F.CrtYd")
		)
		(fp_line
			(start -1.05 -1.2)
			(end -1.05 1.2)
			(stroke
				(width 0.2)
				(type solid)
			)
			(layer "F.CrtYd")
		)
		(fp_line
			(start -1.05 1.2)
			(end 1.05 1.2)
			(stroke
				(width 0.2)
				(type solid)
			)
			(layer "F.CrtYd")
		)
		(fp_line
			(start 1.05 -1.2)
			(end 1.05 1.2)
			(stroke
				(width 0.2)
				(type solid)
			)
			(layer "F.Fab")
		)
		(fp_line
			(start -1.05 -1.2)
			(end 1.05 -1.2)
			(stroke
				(width 0.2)
				(type solid)
			)
			(layer "F.Fab")
		)
		(fp_line
			(start -1.05 -1.2)
			(end -1.05 1.2)
			(stroke
				(width 0.2)
				(type solid)
			)
			(layer "F.Fab")
		)
		(fp_line
			(start 0 -0.5)
			(end 0 0.5)
			(stroke
				(width 0.1)
				(type solid)
			)
			(layer "F.Fab")
		)
		(fp_line
			(start -0.5 0)
			(end 0.5 0)
			(stroke
				(width 0.1)
				(type solid)
			)
			(layer "F.Fab")
		)
		(fp_line
			(start -1.05 1.2)
			(end 1.05 1.2)
			(stroke
				(width 0.2)
				(type solid)
			)
			(layer "F.Fab")
		)
		(fp_text user "${REFERENCE}"
			(at -0.00001 0.09602 90)
			(unlocked yes)
			(layer "F.Fab")
			(effects
				(font
					(face "Arial")
					(size 0.63 0.63)
					(thickness 0.1)
				)
				(justify left bottom)
			)
		)
		(pad "" smd custom
			(at -0.5 -1.1)
			(size 0.000001 0.000001)
			(layers "F.Cu" "F.Mask")
			(solder_mask_margin 0)
			(thermal_bridge_angle 90)
			(options
				(clearance outline)
				(anchor circle)
			)
			(primitives
				(gr_poly
					(pts
						(xy 0 0) (xy 0 -0.15) (xy 0.4 -0.15) (xy 0.4 0.45) (xy 0.2 0.45) (xy 0.2 0)
					)
					(width 0)
					(fill yes)
				)
			)
		)
		(pad "1" smd circle
			(at -0.45 -0.8 90)
			(size 0.18 0.18)
			(layers "F.Cu" "F.Mask" "F.Paste")
			(net "DIP_SW_GPS1_SEL")
			(solder_mask_margin 0)
			(solder_paste_margin -1000)
			(thermal_bridge_angle 90)
		)
		(pad "2" smd rect
			(at -0.65 -0.4 90)
			(size 0.6 0.2)
			(layers "F.Cu" "F.Mask" "F.Paste")
			(net "M2_GPS1_PIN11")
			(solder_mask_margin 0)
			(solder_paste_margin -1000)
		)
		(pad "3" smd rect
			(at -0.65 0 90)
			(size 0.6 0.2)
			(layers "F.Cu" "F.Mask" "F.Paste")
			(net "GND")
			(solder_mask_margin 0)
			(solder_paste_margin -1000)
		)
		(pad "4" smd rect
			(at -0.65 0.4 90)
			(size 0.6 0.2)
			(layers "F.Cu" "F.Mask" "F.Paste")
			(net "M2_GPS1_PIN12")
			(solder_mask_margin 0)
			(solder_paste_margin -1000)
		)
		(pad "5" smd rect
			(at -0.65 0.8 90)
			(size 0.6 0.2)
			(layers "F.Cu" "F.Mask" "F.Paste")
			(net "DIP_SW_GPS1_SEL")
			(solder_mask_margin 0)
			(solder_paste_margin -1000)
		)
		(pad "6" smd rect
			(at 0 0.8 90)
			(size 0.2 0.6)
			(layers "F.Cu" "F.Mask" "F.Paste")
			(net "GND")
			(solder_mask_margin 0)
			(solder_paste_margin -1000)
		)
		(pad "7" smd rect
			(at 0.65 0.8 90)
			(size 0.6 0.2)
			(layers "F.Cu" "F.Mask" "F.Paste")
			(net "NetR177_1")
			(solder_mask_margin 0)
			(solder_paste_margin -1000)
		)
		(pad "8" smd rect
			(at 0.65 0.4 90)
			(size 0.6 0.2)
			(layers "F.Cu" "F.Mask" "F.Paste")
			(net "RCB_GPS1_PIN12")
			(solder_mask_margin 0)
			(solder_paste_margin -1000)
		)
		(pad "9" smd rect
			(at 0.65 0 90)
			(size 0.6 0.2)
			(layers "F.Cu" "F.Mask" "F.Paste")
			(net "+3.3V")
			(solder_mask_margin 0)
			(solder_paste_margin -1000)
		)
		(pad "10" smd rect
			(at 0.65 -0.4 90)
			(size 0.6 0.2)
			(layers "F.Cu" "F.Mask" "F.Paste")
			(net "RCB_GPS1_PIN11")
			(solder_mask_margin 0)
			(solder_paste_margin -1000)
		)
		(pad "11" smd rect
			(at 0.65 -0.8 90)
			(size 0.6 0.2)
			(layers "F.Cu" "F.Mask" "F.Paste")
			(net "NetR176_1")
			(solder_mask_margin 0)
			(solder_paste_margin -1000)
		)
		(pad "12" smd rect
			(at 0 -0.8 90)
			(size 0.2 0.6)
			(layers "F.Cu" "F.Mask" "F.Paste")
			(net "GND")
			(solder_mask_margin 0)
			(solder_paste_margin -1000)
		)
	)
	(footprint "Vault:TECO-1909763-1_V"
		(layer "F.Cu")
		(at 77.19563 108.6162 -90)
		(property "Reference" "J2"
			(at -2.773069 0.445435 0)
			(unlocked yes)
			(layer "F.SilkS")
			(effects
				(font
					(size 0.762 0.762)
					(thickness 0.2286)
				)
			)
		)
		(property "Value" "1909763-1"
			(at 4.582685 3.722871 270)
			(unlocked yes)
			(layer "F.SilkS")
			(hide yes)
			(effects
				(font
					(size 0.762 0.762)
					(thickness 0.2286)
				)
			)
		)
		(sheetname "01-USER_IO")
		(sheetfile "01-USER_IO.kicad_sch")
		(duplicate_pad_numbers_are_jumpers no)
		(fp_line
			(start 0.55 -1.3)
			(end -0.55 -1.3)
			(stroke
				(width 0.2)
				(type solid)
			)
			(layer "F.SilkS")
		)
		(fp_circle
			(center -1.778 1.65)
			(end -1.903 1.65)
			(stroke
				(width 0.25)
				(type solid)
			)
			(fill no)
			(layer "F.SilkS")
		)
		(pad "1" smd rect
			(at -1.475 0 270)
			(size 1.05 2.2)
			(layers "F.Cu" "F.Mask" "F.Paste")
			(net "GND")
		)
		(pad "2" smd rect
			(at 0 1.525 270)
			(size 1 1.05)
			(layers "F.Cu" "F.Mask" "F.Paste")
			(net "NetAN2_1")
		)
		(pad "3" smd rect
			(at 1.475 0 270)
			(size 1.05 2.2)
			(layers "F.Cu" "F.Mask" "F.Paste")
			(net "GND")
		)
	)
	(footprint "Vault:RESC3116X65X50ML20T20"
		(layer "F.Cu")
		(at 140.7716 90.9662)
		(property "Reference" "R45"
			(at 4.0786 -0.023079 0)
			(unlocked yes)
			(layer "F.SilkS")
			(effects
				(font
					(size 0.762 0.762)
					(thickness 0.2286)
				)
			)
		)
		(property "Value" "0_5%_1206"
			(at 4.35396 3.291071 0)
			(unlocked yes)
			(layer "F.SilkS")
			(hide yes)
			(effects
				(font
					(size 0.762 0.762)
					(thickness 0.2286)
				)
			)
		)
		(sheetname "06-MAC")
		(sheetfile "06-MAC.kicad_sch")
		(duplicate_pad_numbers_are_jumpers no)
		(fp_line
			(start -0.35 -0.85)
			(end 0.35 -0.85)
			(stroke
				(width 0.2)
				(type solid)
			)
			(layer "F.SilkS")
		)
		(fp_line
			(start -0.35 0.85)
			(end 0.35 0.85)
			(stroke
				(width 0.2)
				(type solid)
			)
			(layer "F.SilkS")
		)
		(pad "1" smd rect
			(at -1.475 0 90)
			(size 1.9 1.45)
			(layers "F.Cu" "F.Mask" "F.Paste")
			(net "MAC_VCC")
		)
		(pad "2" smd rect
			(at 1.475 0 90)
			(size 1.9 1.45)
			(layers "F.Cu" "F.Mask" "F.Paste")
			(net "+5.0V")
		)
	)
	(footprint "Vault:RESC1005X40X25NL10T10"
		(layer "F.Cu")
		(at 172.9216 118.8162 -90)
		(property "Reference" "R117"
			(at 2.7032 0.045011 270)
			(unlocked yes)
			(layer "F.SilkS")
			(effects
				(font
					(size 0.762 0.762)
					(thickness 0.2032)
				)
			)
		)
		(property "Value" "4.7K_1%_0402"
			(at -2.732271 8.747465 180)
			(unlocked yes)
			(layer "F.SilkS")
			(hide yes)
			(effects
				(font
					(size 0.762 0.762)
					(thickness 0.2032)
				)
			)
		)
		(sheetname "08-DIPSwitches_I2C")
		(sheetfile "08-DIPSwitches_I2C.kicad_sch")
		(duplicate_pad_numbers_are_jumpers no)
		(pad "1" smd rect
			(at -0.425 0)
			(size 0.6 0.65)
			(layers "F.Cu" "F.Mask" "F.Paste")
			(net "SENS_I2C_SDA")
		)
		(pad "2" smd rect
			(at 0.425 0)
			(size 0.6 0.65)
			(layers "F.Cu" "F.Mask" "F.Paste")
			(net "+3.3V")
		)
	)
	(footprint "SamacSys:155124M173200"
		(layer "F.Cu")
		(at 67.4466 101.4162 90)
		(property "Reference" "D15"
			(at -0.8286 1.248069 270)
			(unlocked yes)
			(layer "F.SilkS")
			(effects
				(font
					(size 0.762 0.762)
					(thickness 0.2286)
				)
			)
		)
		(property "Value" "155124M173200"
			(at 7.1471 2.605271 90)
			(unlocked yes)
			(layer "F.SilkS")
			(hide yes)
			(effects
				(font
					(size 0.762 0.762)
					(thickness 0.2286)
				)
			)
		)
		(sheetname "02-USER_IO_STATUS")
		(sheetfile "02-USER_IO_STATUS.kicad_sch")
		(duplicate_pad_numbers_are_jumpers no)
		(fp_line
			(start -0.8 0.5)
			(end 0.8 0.5)
			(stroke
				(width 0.1)
				(type solid)
			)
			(layer "F.SilkS")
		)
		(fp_arc
			(start -2 -0.1)
			(mid -1.95 -0.05)
			(end -2 0)
			(stroke
				(width 0.381)
				(type solid)
			)
			(layer "F.SilkS")
		)
		(fp_arc
			(start -2 0)
			(mid -2.05 -0.05)
			(end -2 -0.1)
			(stroke
				(width 0.381)
				(type solid)
			)
			(layer "F.SilkS")
		)
		(pad "1" smd rect
			(at -1.4 0 180)
			(size 0.9 0.6)
			(layers "F.Cu" "F.Mask" "F.Paste")
			(net "+3.3V")
		)
		(pad "2" smd rect
			(at -0.45 -0.325 90)
			(size 0.6 0.55)
			(layers "F.Cu" "F.Mask" "F.Paste")
			(net "NetD15_2")
		)
		(pad "3" smd rect
			(at 0.45 -0.325 90)
			(size 0.6 0.55)
			(layers "F.Cu" "F.Mask" "F.Paste")
			(net "NetD15_3")
		)
		(pad "4" smd rect
			(at 1.4 0 180)
			(size 0.9 0.6)
			(layers "F.Cu" "F.Mask" "F.Paste")
			(net "NetD15_4")
		)
	)
	(footprint "Vault:FP-CC0402-MFG"
		(layer "F.Cu")
		(at 227.2216 121.4162 180)
		(property "Reference" "C91"
			(at 2.171395 -0.426931 0)
			(unlocked yes)
			(layer "F.SilkS")
			(effects
				(font
					(size 0.762 0.762)
					(thickness 0.2286)
				)
			)
		)
		(property "Value" "10nF_50V_0402"
			(at 9.02662 2.389351 180)
			(unlocked yes)
			(layer "F.SilkS")
			(hide yes)
			(effects
				(font
					(size 0.762 0.762)
					(thickness 0.2286)
				)
			)
		)
		(sheetname "09-USBUart_PPSMUX_UARTMUX")
		(sheetfile "09-USBUart_PPSMUX_UARTMUX.kicad_sch")
		(duplicate_pad_numbers_are_jumpers no)
		(fp_line
			(start 0.525 -0.675)
			(end -0.525 -0.675)
			(stroke
				(width 0.2)
				(type solid)
			)
			(layer "F.SilkS")
		)
		(fp_line
			(start 0.51967 0.68067)
			(end -0.53033 0.68067)
			(stroke
				(width 0.2)
				(type solid)
			)
			(layer "F.SilkS")
		)
		(fp_line
			(start 0.875 0.475)
			(end -0.875 0.475)
			(stroke
				(width 0.2)
				(type solid)
			)
			(layer "F.CrtYd")
		)
		(fp_line
			(start 0.875 -0.475)
			(end 0.875 0.475)
			(stroke
				(width 0.2)
				(type solid)
			)
			(layer "F.CrtYd")
		)
		(fp_line
			(start 0.875 -0.475)
			(end -0.875 -0.475)
			(stroke
				(width 0.2)
				(type solid)
			)
			(layer "F.CrtYd")
		)
		(fp_line
			(start -0.875 -0.475)
			(end -0.875 0.475)
			(stroke
				(width 0.2)
				(type solid)
			)
			(layer "F.CrtYd")
		)
		(fp_line
			(start 0.875 0.475)
			(end -0.875 0.475)
			(stroke
				(width 0.2)
				(type solid)
			)
			(layer "F.Fab")
		)
		(fp_line
			(start 0.875 -0.475)
			(end 0.875 0.475)
			(stroke
				(width 0.2)
				(type solid)
			)
			(layer "F.Fab")
		)
		(fp_line
			(start 0.875 -0.475)
			(end -0.875 -0.475)
			(stroke
				(width 0.2)
				(type solid)
			)
			(layer "F.Fab")
		)
		(fp_line
			(start 0.5 0)
			(end -0.5 0)
			(stroke
				(width 0.1)
				(type solid)
			)
			(layer "F.Fab")
		)
		(fp_line
			(start 0 -0.5)
			(end 0 0.5)
			(stroke
				(width 0.1)
				(type solid)
			)
			(layer "F.Fab")
		)
		(fp_line
			(start -0.875 -0.475)
			(end -0.875 0.475)
			(stroke
				(width 0.2)
				(type solid)
			)
			(layer "F.Fab")
		)
		(fp_text user "${REFERENCE}"
			(at -0.00001 0.09601 180)
			(unlocked yes)
			(layer "F.Fab")
			(effects
				(font
					(face "Arial")
					(size 0.63 0.63)
					(thickness 0.1)
				)
				(justify left bottom)
			)
		)
		(pad "1" smd rect
			(at -0.5 0 180)
			(size 0.5 0.5)
			(layers "F.Cu" "F.Mask" "F.Paste")
			(net "NetC91_1")
			(solder_mask_margin 0)
			(solder_paste_margin 0)
		)
		(pad "2" smd rect
			(at 0.5 0 180)
			(size 0.5 0.5)
			(layers "F.Cu" "F.Mask" "F.Paste")
			(net "GND")
			(solder_mask_margin 0)
			(solder_paste_margin 0)
		)
	)
	(footprint "Vault:CAPC1005X55X25ML05T05"
		(layer "F.Cu")
		(at 120.18072 87.9662 90)
		(property "Reference" "C68"
			(at -2.0214 0.067811 90)
			(unlocked yes)
			(layer "F.SilkS")
			(effects
				(font
					(size 0.762 0.762)
					(thickness 0.2286)
				)
			)
		)
		(property "Value" "22pF_50V_0402"
			(at -3.011671 9.68682 0)
			(unlocked yes)
			(layer "F.SilkS")
			(hide yes)
			(effects
				(font
					(size 0.762 0.762)
					(thickness 0.2286)
				)
			)
		)
		(sheetname "05-GPS_IMU_SENSORS")
		(sheetfile "05-GPS_IMU_SENSORS.kicad_sch")
		(duplicate_pad_numbers_are_jumpers no)
		(pad "1" smd rect
			(at -0.51 0 180)
			(size 0.72 0.72)
			(layers "F.Cu" "F.Mask" "F.Paste")
			(net "GND")
		)
		(pad "2" smd rect
			(at 0.51 0 180)
			(size 0.72 0.72)
			(layers "F.Cu" "F.Mask" "F.Paste")
			(net "BNO_XOUT32")
		)
	)
	(footprint "Vault:RESC1005X40X25LL05T10"
		(layer "F.Cu")
		(at 146.6216 104.4162)
		(property "Reference" "R106"
			(at 2.5286 0.226931 0)
			(unlocked yes)
			(layer "F.SilkS")
			(effects
				(font
					(size 0.762 0.762)
					(thickness 0.2286)
				)
			)
		)
		(property "Value" "DNI_49.9_1%_0402"
			(at -2.579871 11.74372 270)
			(unlocked yes)
			(layer "F.SilkS")
			(hide yes)
			(effects
				(font
					(size 0.762 0.762)
					(thickness 0.2286)
				)
			)
		)
		(sheetname "09-USBUart_PPSMUX_UARTMUX")
		(sheetfile "09-USBUart_PPSMUX_UARTMUX.kicad_sch")
		(duplicate_pad_numbers_are_jumpers no)
		(pad "1" smd rect
			(at -0.375 0 90)
			(size 0.45 0.5)
			(layers "F.Cu" "F.Mask" "F.Paste")
			(net "FPGA_MAC_PPS_IN0-")
		)
		(pad "2" smd rect
			(at 0.375 0 90)
			(size 0.45 0.5)
			(layers "F.Cu" "F.Mask" "F.Paste")
			(net "MAC_PPS_IN")
		)
	)
	(footprint "Vault:RGV0016A_V"
		(layer "F.Cu")
		(at 170.3216 114.6162 90)
		(property "Reference" "U27"
			(at 2.973079 -1.6968 0)
			(unlocked yes)
			(layer "F.SilkS")
			(effects
				(font
					(size 0.762 0.762)
					(thickness 0.2032)
				)
			)
		)
		(property "Value" "PCA9546ARGVR"
			(at 7.020225 3.875271 90)
			(unlocked yes)
			(layer "F.SilkS")
			(hide yes)
			(effects
				(font
					(size 0.762 0.762)
					(thickness 0.2032)
				)
			)
		)
		(sheetname "08-DIPSwitches_I2C")
		(sheetfile "08-DIPSwitches_I2C.kicad_sch")
		(duplicate_pad_numbers_are_jumpers no)
		(fp_line
			(start 2.225 -2.225)
			(end 2.225 -1.925)
			(stroke
				(width 0.2)
				(type solid)
			)
			(layer "F.SilkS")
		)
		(fp_line
			(start 1.925 -2.225)
			(end 2.225 -2.225)
			(stroke
				(width 0.2)
				(type solid)
			)
			(layer "F.SilkS")
		)
		(fp_line
			(start -2.225 -2.225)
			(end -1.525 -2.225)
			(stroke
				(width 0.2)
				(type solid)
			)
			(layer "F.SilkS")
		)
		(fp_line
			(start -2.225 -2.225)
			(end -2.225 -1.525)
			(stroke
				(width 0.2)
				(type solid)
			)
			(layer "F.SilkS")
		)
		(fp_line
			(start 2.225 1.925)
			(end 2.225 2.225)
			(stroke
				(width 0.2)
				(type solid)
			)
			(layer "F.SilkS")
		)
		(fp_line
			(start -2.225 1.925)
			(end -2.225 2.225)
			(stroke
				(width 0.2)
				(type solid)
			)
			(layer "F.SilkS")
		)
		(fp_line
			(start 1.925 2.225)
			(end 2.225 2.225)
			(stroke
				(width 0.2)
				(type solid)
			)
			(layer "F.SilkS")
		)
		(fp_line
			(start -2.225 2.225)
			(end -1.925 2.225)
			(stroke
				(width 0.2)
				(type solid)
			)
			(layer "F.SilkS")
		)
		(fp_poly
			(pts
				(xy -0.987355 -0.987355) (xy -0.987355 -0.151645) (xy -0.151645 -0.151645) (xy -0.151645 -0.987355)
			)
			(stroke
				(width 0.10329)
				(type solid)
			)
			(fill yes)
			(layer "F.Paste")
		)
		(fp_poly
			(pts
				(xy 0.987355 -0.151645) (xy 0.987355 -0.987355) (xy 0.151645 -0.987355) (xy 0.151645 -0.151645)
			)
			(stroke
				(width 0.10329)
				(type solid)
			)
			(fill yes)
			(layer "F.Paste")
		)
		(fp_poly
			(pts
				(xy -0.987355 0.151645) (xy -0.987355 0.987355) (xy -0.151645 0.987355) (xy -0.151645 0.151645)
			)
			(stroke
				(width 0.10329)
				(type solid)
			)
			(fill yes)
			(layer "F.Paste")
		)
		(fp_poly
			(pts
				(xy 0.987355 0.987355) (xy 0.987355 0.151645) (xy 0.151645 0.151645) (xy 0.151645 0.987355)
			)
			(stroke
				(width 0.10329)
				(type solid)
			)
			(fill yes)
			(layer "F.Paste")
		)
		(pad "1" smd roundrect
			(at -1.825 -0.975 180)
			(size 0.3 0.75)
			(layers "F.Cu" "F.Mask" "F.Paste")
			(roundrect_rratio 0.165)
			(net "NetR121_2")
		)
		(pad "2" smd roundrect
			(at -1.825 -0.325 180)
			(size 0.3 0.75)
			(layers "F.Cu" "F.Mask" "F.Paste")
			(roundrect_rratio 0.165)
			(net "MAC_I2C_SDA")
		)
		(pad "3" smd roundrect
			(at -1.825 0.325 180)
			(size 0.3 0.75)
			(layers "F.Cu" "F.Mask" "F.Paste")
			(roundrect_rratio 0.165)
			(net "MAC_I2C_SCL")
		)
		(pad "4" smd roundrect
			(at -1.825 0.975 180)
			(size 0.3 0.75)
			(layers "F.Cu" "F.Mask" "F.Paste")
			(roundrect_rratio 0.165)
			(net "SENS_I2C_SDA")
		)
		(pad "5" smd roundrect
			(at -0.975 1.825 90)
			(size 0.3 0.75)
			(layers "F.Cu" "F.Mask" "F.Paste")
			(roundrect_rratio 0.165)
			(net "SENS_I2C_SCL")
		)
		(pad "6" smd roundrect
			(at -0.325 1.825 90)
			(size 0.3 0.75)
			(layers "F.Cu" "F.Mask" "F.Paste")
			(roundrect_rratio 0.165)
			(net "GND")
		)
		(pad "7" smd roundrect
			(at 0.325 1.825 90)
			(size 0.3 0.75)
			(layers "F.Cu" "F.Mask" "F.Paste")
			(roundrect_rratio 0.165)
			(net "ANADC_I2C_SDA")
		)
		(pad "8" smd roundrect
			(at 0.975 1.825 90)
			(size 0.3 0.75)
			(layers "F.Cu" "F.Mask" "F.Paste")
			(roundrect_rratio 0.165)
			(net "ANADC_I2C_SCL")
		)
		(pad "9" smd roundrect
			(at 1.825 0.975 180)
			(size 0.3 0.75)
			(layers "F.Cu" "F.Mask" "F.Paste")
			(roundrect_rratio 0.165)
			(net "DC_I2C_SDA")
		)
		(pad "10" smd roundrect
			(at 1.825 0.325 180)
			(size 0.3 0.75)
			(layers "F.Cu" "F.Mask" "F.Paste")
			(roundrect_rratio 0.165)
			(net "DC_I2C_SCL")
		)
		(pad "11" smd roundrect
			(at 1.825 -0.325 180)
			(size 0.3 0.75)
			(layers "F.Cu" "F.Mask" "F.Paste")
			(roundrect_rratio 0.165)
			(net "NetR126_2")
		)
		(pad "12" smd roundrect
			(at 1.825 -0.975 180)
			(size 0.3 0.75)
			(layers "F.Cu" "F.Mask" "F.Paste")
			(roundrect_rratio 0.165)
			(net "SCL")
		)
		(pad "13" smd roundrect
			(at 0.975 -1.825 90)
			(size 0.3 0.75)
			(layers "F.Cu" "F.Mask" "F.Paste")
			(roundrect_rratio 0.165)
			(net "SDA")
		)
		(pad "14" smd roundrect
			(at 0.325 -1.825 90)
			(size 0.3 0.75)
			(layers "F.Cu" "F.Mask" "F.Paste")
			(roundrect_rratio 0.165)
			(net "+3.3V")
		)
		(pad "15" smd roundrect
			(at -0.325 -1.825 90)
			(size 0.3 0.75)
			(layers "F.Cu" "F.Mask" "F.Paste")
			(roundrect_rratio 0.165)
			(net "NetR128_2")
		)
		(pad "16" smd roundrect
			(at -0.975 -1.825 90)
			(size 0.3 0.75)
			(layers "F.Cu" "F.Mask" "F.Paste")
			(roundrect_rratio 0.165)
			(net "NetR127_2")
		)
		(pad "17" smd roundrect
			(at 0 0 90)
			(size 2.1 2.1)
			(layers "F.Cu" "F.Mask" "F.Paste")
			(roundrect_rratio 0.025)
			(net "GND")
			(solder_paste_margin -1.08)
		)
	)
	(footprint "Vault:RESC1005X40X25NL05T05"
		(layer "F.Cu")
		(at 108.3216 51.3162 90)
		(property "Reference" "R155"
			(at -0.2968 8.226921 90)
			(unlocked yes)
			(layer "F.SilkS")
			(effects
				(font
					(size 0.762 0.762)
					(thickness 0.2032)
				)
			)
		)
		(property "Value" "DNI_27_1%_0402"
			(at -2.732271 10.270975 0)
			(unlocked yes)
			(layer "F.SilkS")
			(hide yes)
			(effects
				(font
					(size 0.762 0.762)
					(thickness 0.2032)
				)
			)
		)
		(sheetname "11-M2_RCB_MUX")
		(sheetfile "11-M2_RCB_MUX.kicad_sch")
		(duplicate_pad_numbers_are_jumpers no)
		(pad "1" smd rect
			(at -0.45 0 180)
			(size 0.55 0.55)
			(layers "F.Cu" "F.Mask" "F.Paste")
			(net "RCB_GPS1_TX")
		)
		(pad "2" smd rect
			(at 0.45 0 180)
			(size 0.55 0.55)
			(layers "F.Cu" "F.Mask" "F.Paste")
			(net "GPS1_TX")
		)
	)
	(footprint "SA53:SolderSocket"
		(locked yes)
		(layer "F.Cu")
		(at 86.9216 96.7162 90)
		(property "Reference" "SKT2"
			(at -0.226921 -6.7714 0)
			(unlocked yes)
			(layer "F.SilkS")
			(effects
				(font
					(size 0.762 0.762)
					(thickness 0.2286)
				)
			)
		)
		(property "Value" "0332-0-43-80-18-27-10-0"
			(at -2.910071 16.1362 0)
			(unlocked yes)
			(layer "F.SilkS")
			(hide yes)
			(effects
				(font
					(size 0.762 0.762)
					(thickness 0.2286)
				)
			)
		)
		(sheetname "06-MAC")
		(sheetfile "06-MAC.kicad_sch")
		(duplicate_pad_numbers_are_jumpers no)
		(pad "1" thru_hole circle
			(at 0 0 90)
			(size 2.54 2.54)
			(drill 2.0066)
			(layers "*.Cu" "*.Mask")
			(remove_unused_layers no)
			(net "MAC_FREQ_CTRL")
			(thermal_bridge_angle 90)
		)
	)
	(footprint "SamacSys:SOP50P310X90-8N"
		(layer "F.Cu")
		(at 77.42159 114.0162 180)
		(property "Reference" "U12"
			(at -0.92861 1.773069 0)
			(unlocked yes)
			(layer "F.SilkS")
			(effects
				(font
					(size 0.762 0.762)
					(thickness 0.2286)
				)
			)
		)
		(property "Value" "NC7WV125K8X"
			(at 6.207715 2.884671 180)
			(unlocked yes)
			(layer "F.SilkS")
			(hide yes)
			(effects
				(font
					(size 0.762 0.762)
					(thickness 0.2286)
				)
			)
		)
		(sheetname "01-USER_IO")
		(sheetfile "01-USER_IO.kicad_sch")
		(duplicate_pad_numbers_are_jumpers no)
		(fp_line
			(start 0.8 1)
			(end -0.8 1)
			(stroke
				(width 0.2)
				(type solid)
			)
			(layer "F.SilkS")
		)
		(fp_line
			(start 0.8 -1)
			(end 0.8 1)
			(stroke
				(width 0.2)
				(type solid)
			)
			(layer "F.SilkS")
		)
		(fp_line
			(start 0.8 -1)
			(end -0.8 -1)
			(stroke
				(width 0.2)
				(type solid)
			)
			(layer "F.SilkS")
		)
		(fp_line
			(start -0.8 -1)
			(end -0.8 1)
			(stroke
				(width 0.2)
				(type solid)
			)
			(layer "F.SilkS")
		)
		(fp_line
			(start -1.15 -1.25)
			(end -2 -1.25)
			(stroke
				(width 0.2)
				(type solid)
			)
			(layer "F.SilkS")
		)
		(pad "1" smd rect
			(at -1.575 -0.75 180)
			(size 0.85 0.3)
			(layers "F.Cu" "F.Mask" "F.Paste")
			(net "ANT2_IO_OUT")
		)
		(pad "2" smd rect
			(at -1.575 -0.25 180)
			(size 0.85 0.3)
			(layers "F.Cu" "F.Mask" "F.Paste")
			(net "ANT2_OUT")
		)
		(pad "3" smd rect
			(at -1.575 0.25 180)
			(size 0.85 0.3)
			(layers "F.Cu" "F.Mask" "F.Paste")
			(net "ANT2_IN")
		)
		(pad "4" smd rect
			(at -1.575 0.75 180)
			(size 0.85 0.3)
			(layers "F.Cu" "F.Mask" "F.Paste")
			(net "GND")
		)
		(pad "5" smd rect
			(at 1.575 0.75 180)
			(size 0.85 0.3)
			(layers "F.Cu" "F.Mask" "F.Paste")
			(net "NetR33_1")
		)
		(pad "6" smd rect
			(at 1.575 0.25 180)
			(size 0.85 0.3)
			(layers "F.Cu" "F.Mask" "F.Paste")
			(net "NetR33_1")
		)
		(pad "7" smd rect
			(at 1.575 -0.25 180)
			(size 0.85 0.3)
			(layers "F.Cu" "F.Mask" "F.Paste")
			(net "ANT2_IO_IN")
		)
		(pad "8" smd rect
			(at 1.575 -0.75 180)
			(size 0.85 0.3)
			(layers "F.Cu" "F.Mask" "F.Paste")
			(net "+3.3V")
		)
	)
	(footprint "Vault:FP-DFN-12-IPC_B"
		(layer "F.Cu")
		(at 228.3966 116.3317 90)
		(property "Reference" "U20"
			(at -0.3131 2.698069 270)
			(unlocked yes)
			(layer "F.SilkS")
			(effects
				(font
					(size 0.762 0.762)
					(thickness 0.2286)
				)
			)
		)
		(property "Value" "FT234XD-R"
			(at 4.45556 3.392671 90)
			(unlocked yes)
			(layer "F.SilkS")
			(hide yes)
			(effects
				(font
					(size 0.762 0.762)
					(thickness 0.2286)
				)
			)
		)
		(sheetname "09-USBUart_PPSMUX_UARTMUX")
		(sheetfile "09-USBUart_PPSMUX_UARTMUX.kicad_sch")
		(duplicate_pad_numbers_are_jumpers no)
		(fp_line
			(start -1.5 -1.625)
			(end 1.5 -1.625)
			(stroke
				(width 0.2)
				(type solid)
			)
			(layer "F.SilkS")
		)
		(fp_line
			(start -1.5 1.625)
			(end 1.5 1.625)
			(stroke
				(width 0.2)
				(type solid)
			)
			(layer "F.SilkS")
		)
		(fp_circle
			(center -2.38536 -1.125)
			(end -2.26036 -1.125)
			(stroke
				(width 0.25)
				(type solid)
			)
			(fill no)
			(layer "F.SilkS")
		)
		(fp_rect
			(start -0.46147 0.91168)
			(end 0.46167 -0.91146)
			(stroke
				(width 0)
				(type default)
			)
			(fill yes)
			(layer "F.Paste")
		)
		(fp_line
			(start 2.08535 -1.75)
			(end 2.08535 1.75)
			(stroke
				(width 0.2)
				(type solid)
			)
			(layer "F.CrtYd")
		)
		(fp_line
			(start -2.08536 -1.75)
			(end 2.08535 -1.75)
			(stroke
				(width 0.2)
				(type solid)
			)
			(layer "F.CrtYd")
		)
		(fp_line
			(start -2.08536 -1.75)
			(end -2.08536 1.75)
			(stroke
				(width 0.2)
				(type solid)
			)
			(layer "F.CrtYd")
		)
		(fp_line
			(start -2.08536 1.75)
			(end 2.08535 1.75)
			(stroke
				(width 0.2)
				(type solid)
			)
			(layer "F.CrtYd")
		)
		(fp_line
			(start 2.08535 -1.75)
			(end 2.08535 1.75)
			(stroke
				(width 0.2)
				(type solid)
			)
			(layer "F.Fab")
		)
		(fp_line
			(start -2.08536 -1.75)
			(end 2.08535 -1.75)
			(stroke
				(width 0.2)
				(type solid)
			)
			(layer "F.Fab")
		)
		(fp_line
			(start -2.08536 -1.75)
			(end -2.08536 1.75)
			(stroke
				(width 0.2)
				(type solid)
			)
			(layer "F.Fab")
		)
		(fp_line
			(start 0 -0.5)
			(end 0 0.5)
			(stroke
				(width 0.1)
				(type solid)
			)
			(layer "F.Fab")
		)
		(fp_line
			(start -0.5 0)
			(end 0.5 0)
			(stroke
				(width 0.1)
				(type solid)
			)
			(layer "F.Fab")
		)
		(fp_line
			(start -2.08536 1.75)
			(end 2.08535 1.75)
			(stroke
				(width 0.2)
				(type solid)
			)
			(layer "F.Fab")
		)
		(fp_text user "${REFERENCE}"
			(at 0 0.28425 90)
			(unlocked yes)
			(layer "F.Fab")
			(effects
				(font
					(face "Arial")
					(size 0.63 0.63)
					(thickness 0.1)
				)
				(justify left bottom)
			)
		)
		(pad "1" smd rect
			(at -1.4155 -1.125 90)
			(size 0.83971 0.22247)
			(layers "F.Cu" "F.Mask" "F.Paste")
			(net "FTDI_USB_N")
			(solder_mask_margin 0)
			(solder_paste_margin 0)
		)
		(pad "2" smd roundrect
			(at -1.4155 -0.675 90)
			(size 0.83971 0.22247)
			(layers "F.Cu" "F.Mask" "F.Paste")
			(roundrect_rratio 0.5)
			(net "NetC91_1")
			(solder_mask_margin 0)
			(solder_paste_margin 0)
		)
		(pad "3" smd roundrect
			(at -1.4155 -0.225 90)
			(size 0.83971 0.22247)
			(layers "F.Cu" "F.Mask" "F.Paste")
			(roundrect_rratio 0.5)
			(net "NetC92_1")
			(solder_mask_margin 0)
			(solder_paste_margin 0)
		)
		(pad "4" smd roundrect
			(at -1.4155 0.225 90)
			(size 0.83971 0.22247)
			(layers "F.Cu" "F.Mask" "F.Paste")
			(roundrect_rratio 0.5)
			(net "FTDI_VBUS")
			(solder_mask_margin 0)
			(solder_paste_margin 0)
		)
		(pad "5" smd roundrect
			(at -1.4155 0.675 90)
			(size 0.83971 0.22247)
			(layers "F.Cu" "F.Mask" "F.Paste")
			(roundrect_rratio 0.5)
			(net "GND")
			(solder_mask_margin 0)
			(solder_paste_margin 0)
		)
		(pad "6" smd roundrect
			(at -1.4155 1.125 90)
			(size 0.83971 0.22247)
			(layers "F.Cu" "F.Mask" "F.Paste")
			(roundrect_rratio 0.5)
			(solder_mask_margin 0)
			(solder_paste_margin 0)
		)
		(pad "7" smd roundrect
			(at 1.4155 1.125 90)
			(size 0.83971 0.22247)
			(layers "F.Cu" "F.Mask" "F.Paste")
			(roundrect_rratio 0.5)
			(net "NetR13_1")
			(solder_mask_margin 0)
			(solder_paste_margin 0)
		)
		(pad "8" smd roundrect
			(at 1.4155 0.675 90)
			(size 0.83971 0.22247)
			(layers "F.Cu" "F.Mask" "F.Paste")
			(roundrect_rratio 0.5)
			(solder_mask_margin 0)
			(solder_paste_margin 0)
		)
		(pad "9" smd roundrect
			(at 1.4155 0.225 90)
			(size 0.83971 0.22247)
			(layers "F.Cu" "F.Mask" "F.Paste")
			(roundrect_rratio 0.5)
			(net "NetC92_1")
			(solder_mask_margin 0)
			(solder_paste_margin 0)
		)
		(pad "10" smd roundrect
			(at 1.4155 -0.225 90)
			(size 0.83971 0.22247)
			(layers "F.Cu" "F.Mask" "F.Paste")
			(roundrect_rratio 0.5)
			(net "NetR42_1")
			(solder_mask_margin 0)
			(solder_paste_margin 0)
		)
		(pad "11" smd roundrect
			(at 1.4155 -0.675 90)
			(size 0.83971 0.22247)
			(layers "F.Cu" "F.Mask" "F.Paste")
			(roundrect_rratio 0.5)
			(solder_mask_margin 0)
			(solder_paste_margin 0)
		)
		(pad "12" smd roundrect
			(at 1.4155 -1.125 90)
			(size 0.83971 0.22247)
			(layers "F.Cu" "F.Mask" "F.Paste")
			(roundrect_rratio 0.5)
			(net "FTDI_USB_P")
			(solder_mask_margin 0)
			(solder_paste_margin 0)
		)
		(pad "13" smd rect
			(at 0 0 90)
			(size 1.65 2.55)
			(layers "F.Cu" "F.Mask" "F.Paste")
			(net "GND")
			(solder_mask_margin 0)
			(solder_paste_margin -1000)
		)
	)
	(footprint "Passives:SOT65P210X110-3N"
		(layer "F.Cu")
		(at 179.80761 145.49763)
		(property "Reference" "D5"
			(at -3.38526 -0.968085 0)
			(unlocked yes)
			(layer "F.SilkS")
			(effects
				(font
					(size 0.762 0.762)
					(thickness 0.2286)
				)
				(justify left bottom)
			)
		)
		(property "Value" "BAT54SW"
			(at -10.77491 -6.323555 0)
			(unlocked yes)
			(layer "F.SilkS")
			(hide yes)
			(effects
				(font
					(size 0.762 0.762)
					(thickness 0.2286)
				)
				(justify left bottom)
			)
		)
		(sheetname "04-PCIe_JTAG")
		(sheetfile "04-PCIe_JTAG.kicad_sch")
		(duplicate_pad_numbers_are_jumpers no)
		(fp_line
			(start -0.325 -1.1)
			(end 0.675 -1.1)
			(stroke
				(width 0.2)
				(type solid)
			)
			(layer "F.SilkS")
		)
		(fp_line
			(start -0.325 1.1)
			(end 0.675 1.1)
			(stroke
				(width 0.2)
				(type solid)
			)
			(layer "F.SilkS")
		)
		(fp_line
			(start 0.675 -0.65)
			(end 0.675 -1.1)
			(stroke
				(width 0.2)
				(type solid)
			)
			(layer "F.SilkS")
		)
		(fp_line
			(start 0.675 1.1)
			(end 0.675 0.65)
			(stroke
				(width 0.2)
				(type solid)
			)
			(layer "F.SilkS")
		)
		(fp_circle
			(center -1.125 -1.45)
			(end -1.125 -1.575)
			(stroke
				(width 0.25)
				(type solid)
			)
			(fill no)
			(layer "F.SilkS")
		)
		(pad "1" smd rect
			(at -1.125 -0.65 90)
			(size 0.5 0.9)
			(layers "F.Cu" "F.Mask" "F.Paste")
			(net "GND")
		)
		(pad "2" smd rect
			(at -1.125 0.65 90)
			(size 0.5 0.9)
			(layers "F.Cu" "F.Mask" "F.Paste")
			(net "+3.3V")
		)
		(pad "3" smd rect
			(at 1.125 0 90)
			(size 0.5 0.9)
			(layers "F.Cu" "F.Mask" "F.Paste")
			(net "FPGA_TCK")
		)
	)
	(footprint "Vault:RESC1005X40X25NL05T05"
		(layer "F.Cu")
		(at 190.5216 130.4162 90)
		(property "Reference" "R148"
			(at -0.5968 -0.973079 90)
			(unlocked yes)
			(layer "F.SilkS")
			(effects
				(font
					(size 0.762 0.762)
					(thickness 0.2032)
				)
			)
		)
		(property "Value" "DNI_27_1%_0402"
			(at -2.732271 10.270965 0)
			(unlocked yes)
			(layer "F.SilkS")
			(hide yes)
			(effects
				(font
					(size 0.762 0.762)
					(thickness 0.2032)
				)
			)
		)
		(sheetname "11-M2_RCB_MUX")
		(sheetfile "11-M2_RCB_MUX.kicad_sch")
		(duplicate_pad_numbers_are_jumpers no)
		(pad "1" smd rect
			(at -0.45 0 180)
			(size 0.55 0.55)
			(layers "F.Cu" "F.Mask" "F.Paste")
			(net "RCB_GPS2_TX")
		)
		(pad "2" smd rect
			(at 0.45 0 180)
			(size 0.55 0.55)
			(layers "F.Cu" "F.Mask" "F.Paste")
			(net "GPS2_TX")
		)
	)
	(footprint "Vault:RESC1005X40X25NL05T05"
		(layer "F.Cu")
		(at 225.1466 115.8162)
		(property "Reference" "R81"
			(at -3.496395 -0.073069 0)
			(unlocked yes)
			(layer "F.SilkS")
			(effects
				(font
					(size 0.762 0.762)
					(thickness 0.2286)
				)
			)
		)
		(property "Value" "27_1%_0402"
			(at -2.732271 7.37632 270)
			(unlocked yes)
			(layer "F.SilkS")
			(hide yes)
			(effects
				(font
					(size 0.762 0.762)
					(thickness 0.2286)
				)
			)
		)
		(sheetname "09-USBUart_PPSMUX_UARTMUX")
		(sheetfile "09-USBUart_PPSMUX_UARTMUX.kicad_sch")
		(duplicate_pad_numbers_are_jumpers no)
		(pad "1" smd rect
			(at -0.45 0 90)
			(size 0.55 0.55)
			(layers "F.Cu" "F.Mask" "F.Paste")
			(net "FTDI_USB_R_P")
		)
		(pad "2" smd rect
			(at 0.45 0 90)
			(size 0.55 0.55)
			(layers "F.Cu" "F.Mask" "F.Paste")
			(net "FTDI_USB_P")
		)
	)
	(footprint "Vault:RESC1005X40X25NL05T05"
		(layer "F.Cu")
		(at 108.4216 58.1162 180)
		(property "Reference" "R157"
			(at 3.05685 -0.473971 0)
			(unlocked yes)
			(layer "F.SilkS")
			(effects
				(font
					(size 0.762 0.762)
					(thickness 0.2032)
				)
			)
		)
		(property "Value" "DNI_27_1%_0402"
			(at -2.732271 10.270975 90)
			(unlocked yes)
			(layer "F.SilkS")
			(hide yes)
			(effects
				(font
					(size 0.762 0.762)
					(thickness 0.2032)
				)
			)
		)
		(sheetname "11-M2_RCB_MUX")
		(sheetfile "11-M2_RCB_MUX.kicad_sch")
		(duplicate_pad_numbers_are_jumpers no)
		(pad "1" smd rect
			(at -0.45 0 270)
			(size 0.55 0.55)
			(layers "F.Cu" "F.Mask" "F.Paste")
			(net "RCB_GPS1_RX")
		)
		(pad "2" smd rect
			(at 0.45 0 270)
			(size 0.55 0.55)
			(layers "F.Cu" "F.Mask" "F.Paste")
			(net "GPS1_RX")
		)
	)
	(footprint "Vault:FP-0402-L_1_0_1-W_0_5_0_1-IPC_C"
		(layer "F.Cu")
		(at 74.6216 115.5162 180)
		(property "Reference" "C29"
			(at 2.1714 -0.326931 0)
			(unlocked yes)
			(layer "F.SilkS")
			(effects
				(font
					(size 0.762 0.762)
					(thickness 0.2286)
				)
			)
		)
		(property "Value" "0.1uF_25V_0402"
			(at 2.069035 2.567191 180)
			(unlocked yes)
			(layer "F.SilkS")
			(hide yes)
			(effects
				(font
					(size 0.762 0.762)
					(thickness 0.2286)
				)
			)
		)
		(sheetname "01-USER_IO")
		(sheetfile "01-USER_IO.kicad_sch")
		(duplicate_pad_numbers_are_jumpers no)
		(fp_line
			(start 0.65607 0.7)
			(end -0.65607 0.7)
			(stroke
				(width 0.2)
				(type solid)
			)
			(layer "F.SilkS")
		)
		(fp_line
			(start 0.65607 -0.7)
			(end -0.65607 -0.7)
			(stroke
				(width 0.2)
				(type solid)
			)
			(layer "F.SilkS")
		)
		(fp_line
			(start 0.75607 0.4)
			(end -0.75607 0.4)
			(stroke
				(width 0.2)
				(type solid)
			)
			(layer "F.CrtYd")
		)
		(fp_line
			(start 0.75607 -0.4)
			(end 0.75607 0.4)
			(stroke
				(width 0.2)
				(type solid)
			)
			(layer "F.CrtYd")
		)
		(fp_line
			(start 0.75607 -0.4)
			(end -0.75607 -0.4)
			(stroke
				(width 0.2)
				(type solid)
			)
			(layer "F.CrtYd")
		)
		(fp_line
			(start -0.75607 -0.4)
			(end -0.75607 0.4)
			(stroke
				(width 0.2)
				(type solid)
			)
			(layer "F.CrtYd")
		)
		(fp_line
			(start 0.75607 0.4)
			(end -0.75607 0.4)
			(stroke
				(width 0.2)
				(type solid)
			)
			(layer "F.Fab")
		)
		(fp_line
			(start 0.75607 -0.4)
			(end 0.75607 0.4)
			(stroke
				(width 0.2)
				(type solid)
			)
			(layer "F.Fab")
		)
		(fp_line
			(start 0.75607 -0.4)
			(end -0.75607 -0.4)
			(stroke
				(width 0.2)
				(type solid)
			)
			(layer "F.Fab")
		)
		(fp_line
			(start 0.5 0)
			(end -0.5 0)
			(stroke
				(width 0.1)
				(type solid)
			)
			(layer "F.Fab")
		)
		(fp_line
			(start 0 -0.5)
			(end 0 0.5)
			(stroke
				(width 0.1)
				(type solid)
			)
			(layer "F.Fab")
		)
		(fp_line
			(start -0.75607 -0.4)
			(end -0.75607 0.4)
			(stroke
				(width 0.2)
				(type solid)
			)
			(layer "F.Fab")
		)
		(fp_text user "${REFERENCE}"
			(at -0.00001 0.09601 180)
			(unlocked yes)
			(layer "F.Fab")
			(effects
				(font
					(face "Arial")
					(size 0.63 0.63)
					(thickness 0.1)
				)
				(justify left bottom)
			)
		)
		(pad "1" smd rect
			(at -0.36554 0 180)
			(size 0.58106 0.51213)
			(layers "F.Cu" "F.Mask" "F.Paste")
			(net "+3.3V")
			(solder_mask_margin 0)
			(solder_paste_margin 0)
		)
		(pad "2" smd rect
			(at 0.36554 0 180)
			(size 0.58106 0.51213)
			(layers "F.Cu" "F.Mask" "F.Paste")
			(net "GND")
			(solder_mask_margin 0)
			(solder_paste_margin 0)
		)
	)
	(footprint "Vault:RESC1005X40X25NL05T05"
		(layer "F.Cu")
		(at 155.6216 131.4662 90)
		(property "Reference" "R92"
			(at -1.8214 -0.073069 90)
			(unlocked yes)
			(layer "F.SilkS")
			(effects
				(font
					(size 0.762 0.762)
					(thickness 0.2286)
				)
			)
		)
		(property "Value" "27_1%_0402"
			(at -2.732271 7.37632 0)
			(unlocked yes)
			(layer "F.SilkS")
			(hide yes)
			(effects
				(font
					(size 0.762 0.762)
					(thickness 0.2286)
				)
			)
		)
		(sheetname "09-USBUart_PPSMUX_UARTMUX")
		(sheetfile "09-USBUart_PPSMUX_UARTMUX.kicad_sch")
		(duplicate_pad_numbers_are_jumpers no)
		(pad "1" smd rect
			(at -0.45 0 180)
			(size 0.55 0.55)
			(layers "F.Cu" "F.Mask" "F.Paste")
			(net "FTDI_TX")
		)
		(pad "2" smd rect
			(at 0.45 0 180)
			(size 0.55 0.55)
			(layers "F.Cu" "F.Mask" "F.Paste")
			(net "NetR92_2")
		)
	)
	(footprint "Vault:RESC1005X40X25LL05T10"
		(layer "F.Cu")
		(at 117.6216 77.4162)
		(property "Reference" "R170"
			(at -2.0968 -0.173079 0)
			(unlocked yes)
			(layer "F.SilkS")
			(effects
				(font
					(size 0.762 0.762)
					(thickness 0.2032)
				)
			)
		)
		(property "Value" "DNI_49.9_1%_0402"
			(at -2.579871 11.71832 270)
			(unlocked yes)
			(layer "F.SilkS")
			(hide yes)
			(effects
				(font
					(size 0.762 0.762)
					(thickness 0.2032)
				)
			)
		)
		(sheetname "11-M2_RCB_MUX")
		(sheetfile "11-M2_RCB_MUX.kicad_sch")
		(duplicate_pad_numbers_are_jumpers no)
		(pad "1" smd rect
			(at -0.375 0 90)
			(size 0.45 0.5)
			(layers "F.Cu" "F.Mask" "F.Paste")
			(net "GPS1_PIN11")
		)
		(pad "2" smd rect
			(at 0.375 0 90)
			(size 0.45 0.5)
			(layers "F.Cu" "F.Mask" "F.Paste")
			(net "RCB_GPS1_PIN11")
		)
	)
	(footprint "Vault:RESC1005X40X25LL05T05"
		(layer "F.Cu")
		(at 210.1216 131.5162)
		(property "Reference" "R131"
			(at 4.10058 -0.216869 0)
			(unlocked yes)
			(layer "F.SilkS")
			(effects
				(font
					(size 0.762 0.762)
					(thickness 0.2032)
				)
			)
		)
		(property "Value" "DNI_0_1%_0402"
			(at -2.579871 9.56002 270)
			(unlocked yes)
			(layer "F.SilkS")
			(hide yes)
			(effects
				(font
					(size 0.762 0.762)
					(thickness 0.2032)
				)
			)
		)
		(sheetname "10-M2_GPS")
		(sheetfile "10-M2_GPS.kicad_sch")
		(duplicate_pad_numbers_are_jumpers no)
		(pad "1" smd rect
			(at -0.4 0 90)
			(size 0.45 0.45)
			(layers "F.Cu" "F.Mask" "F.Paste")
			(net "NetJ45_35")
		)
		(pad "2" smd rect
			(at 0.4 0 90)
			(size 0.45 0.45)
			(layers "F.Cu" "F.Mask" "F.Paste")
			(net "M2_GPS2_TP1")
		)
	)
	(footprint "Vault:FP-0402-L_1_0_1-W_0_5_0_1-IPC_C"
		(layer "F.Cu")
		(at 75.7216 130.9162 -90)
		(property "Reference" "C27"
			(at 0.4286 -1.373069 270)
			(unlocked yes)
			(layer "F.SilkS")
			(effects
				(font
					(size 0.762 0.762)
					(thickness 0.2286)
				)
			)
		)
		(property "Value" "0.1uF_25V_0402"
			(at 2.069035 2.567201 270)
			(unlocked yes)
			(layer "F.SilkS")
			(hide yes)
			(effects
				(font
					(size 0.762 0.762)
					(thickness 0.2286)
				)
			)
		)
		(sheetname "01-USER_IO")
		(sheetfile "01-USER_IO.kicad_sch")
		(duplicate_pad_numbers_are_jumpers no)
		(fp_line
			(start 0.65607 0.7)
			(end -0.65607 0.7)
			(stroke
				(width 0.2)
				(type solid)
			)
			(layer "F.SilkS")
		)
		(fp_line
			(start 0.65607 -0.7)
			(end -0.65607 -0.7)
			(stroke
				(width 0.2)
				(type solid)
			)
			(layer "F.SilkS")
		)
		(fp_line
			(start -0.75607 0.4)
			(end -0.75607 -0.4)
			(stroke
				(width 0.2)
				(type solid)
			)
			(layer "F.CrtYd")
		)
		(fp_line
			(start 0.75607 0.4)
			(end -0.75607 0.4)
			(stroke
				(width 0.2)
				(type solid)
			)
			(layer "F.CrtYd")
		)
		(fp_line
			(start 0.75607 0.4)
			(end 0.75607 -0.4)
			(stroke
				(width 0.2)
				(type solid)
			)
			(layer "F.CrtYd")
		)
		(fp_line
			(start 0.75607 -0.4)
			(end -0.75607 -0.4)
			(stroke
				(width 0.2)
				(type solid)
			)
			(layer "F.CrtYd")
		)
		(fp_line
			(start 0 0.5)
			(end 0 -0.5)
			(stroke
				(width 0.1)
				(type solid)
			)
			(layer "F.Fab")
		)
		(fp_line
			(start -0.75607 0.4)
			(end -0.75607 -0.4)
			(stroke
				(width 0.2)
				(type solid)
			)
			(layer "F.Fab")
		)
		(fp_line
			(start 0.75607 0.4)
			(end -0.75607 0.4)
			(stroke
				(width 0.2)
				(type solid)
			)
			(layer "F.Fab")
		)
		(fp_line
			(start 0.75607 0.4)
			(end 0.75607 -0.4)
			(stroke
				(width 0.2)
				(type solid)
			)
			(layer "F.Fab")
		)
		(fp_line
			(start 0.5 0)
			(end -0.5 0)
			(stroke
				(width 0.1)
				(type solid)
			)
			(layer "F.Fab")
		)
		(fp_line
			(start 0.75607 -0.4)
			(end -0.75607 -0.4)
			(stroke
				(width 0.2)
				(type solid)
			)
			(layer "F.Fab")
		)
		(fp_text user "${REFERENCE}"
			(at -0.00001 0.09602 270)
			(unlocked yes)
			(layer "F.Fab")
			(effects
				(font
					(face "Arial")
					(size 0.63 0.63)
					(thickness 0.1)
				)
				(justify left bottom)
			)
		)
		(pad "1" smd rect
			(at -0.36554 0 270)
			(size 0.58106 0.51213)
			(layers "F.Cu" "F.Mask" "F.Paste")
			(net "+3.3V")
			(solder_mask_margin 0)
			(solder_paste_margin 0)
		)
		(pad "2" smd rect
			(at 0.36554 0 270)
			(size 0.58106 0.51213)
			(layers "F.Cu" "F.Mask" "F.Paste")
			(net "GND")
			(solder_mask_margin 0)
			(solder_paste_margin 0)
		)
	)
	(footprint "Vault:FP-LTST-C191KGKT-MFG"
		(layer "F.Cu")
		(at 96.3216 78.5162 180)
		(property "Reference" "D4"
			(at 3.2 -0.493345 0)
			(unlocked yes)
			(layer "F.SilkS")
			(effects
				(font
					(size 0.762 0.762)
					(thickness 0.2286)
				)
				(justify left bottom)
			)
		)
		(property "Value" "LTST-C191KGKT"
			(at 18.2973 -9.341045 0)
			(unlocked yes)
			(layer "F.SilkS")
			(hide yes)
			(effects
				(font
					(size 0.762 0.762)
					(thickness 0.2286)
				)
				(justify left bottom)
			)
		)
		(sheetname "03-POWER")
		(sheetfile "03-POWER.kicad_sch")
		(duplicate_pad_numbers_are_jumpers no)
		(fp_line
			(start 0.85 0.775)
			(end -0.85 0.775)
			(stroke
				(width 0.2)
				(type solid)
			)
			(layer "F.SilkS")
		)
		(fp_line
			(start 0.85 -0.775)
			(end -0.85 -0.775)
			(stroke
				(width 0.2)
				(type solid)
			)
			(layer "F.SilkS")
		)
		(fp_circle
			(center -1.7 0)
			(end -1.7 0.125)
			(stroke
				(width 0.25)
				(type solid)
			)
			(fill no)
			(layer "F.SilkS")
		)
		(fp_line
			(start 1.25 0.55)
			(end -1.25 0.55)
			(stroke
				(width 0.2)
				(type solid)
			)
			(layer "F.CrtYd")
		)
		(fp_line
			(start 1.25 -0.55)
			(end 1.25 0.55)
			(stroke
				(width 0.2)
				(type solid)
			)
			(layer "F.CrtYd")
		)
		(fp_line
			(start 1.25 -0.55)
			(end -1.25 -0.55)
			(stroke
				(width 0.2)
				(type solid)
			)
			(layer "F.CrtYd")
		)
		(fp_line
			(start -1.25 -0.55)
			(end -1.25 0.55)
			(stroke
				(width 0.2)
				(type solid)
			)
			(layer "F.CrtYd")
		)
		(fp_line
			(start 1.25 0.55)
			(end -1.25 0.55)
			(stroke
				(width 0.2)
				(type solid)
			)
			(layer "F.Fab")
		)
		(fp_line
			(start 1.25 -0.55)
			(end 1.25 0.55)
			(stroke
				(width 0.2)
				(type solid)
			)
			(layer "F.Fab")
		)
		(fp_line
			(start 1.25 -0.55)
			(end -1.25 -0.55)
			(stroke
				(width 0.2)
				(type solid)
			)
			(layer "F.Fab")
		)
		(fp_line
			(start 0.5 0)
			(end -0.5 0)
			(stroke
				(width 0.1)
				(type solid)
			)
			(layer "F.Fab")
		)
		(fp_line
			(start 0 -0.5)
			(end 0 0.5)
			(stroke
				(width 0.1)
				(type solid)
			)
			(layer "F.Fab")
		)
		(fp_line
			(start -1.25 -0.55)
			(end -1.25 0.55)
			(stroke
				(width 0.2)
				(type solid)
			)
			(layer "F.Fab")
		)
		(fp_text user "${REFERENCE}"
			(at 0 0.29535 180)
			(unlocked yes)
			(layer "F.Fab")
			(effects
				(font
					(face "Arial")
					(size 0.63 0.63)
					(thickness 0.1)
				)
				(justify left bottom)
			)
		)
		(pad "1" smd rect
			(at -0.75 0 180)
			(size 0.8 0.8)
			(layers "F.Cu" "F.Mask" "F.Paste")
			(net "NetD4_1")
			(solder_mask_margin 0)
			(solder_paste_margin 0)
		)
		(pad "2" smd rect
			(at 0.75 0 180)
			(size 0.8 0.8)
			(layers "F.Cu" "F.Mask" "F.Paste")
			(net "+5.0V")
			(solder_mask_margin 0)
			(solder_paste_margin 0)
		)
	)
	(footprint "Vault:AMPH-901-143-6RFX_V"
		(layer "F.Cu")
		(at 69.9716 95.0786 180)
		(property "Reference" "AN1"
			(at 0.85 3.969055 0)
			(unlocked yes)
			(layer "F.SilkS")
			(effects
				(font
					(size 0.762 0.762)
					(thickness 0.2286)
				)
				(justify left bottom)
			)
		)
		(property "Value" "RF2-49B-T-00-50-G-HDW"
			(at 4.6101 -12.120245 0)
			(unlocked yes)
			(layer "F.SilkS")
			(hide yes)
			(effects
				(font
					(size 0.762 0.762)
					(thickness 0.2286)
				)
				(justify left bottom)
			)
		)
		(sheetname "01-USER_IO")
		(sheetfile "01-USER_IO.kicad_sch")
		(duplicate_pad_numbers_are_jumpers no)
		(fp_line
			(start 3.5 -1.38)
			(end 3.5 1.38)
			(stroke
				(width 0.2)
				(type solid)
			)
			(layer "F.SilkS")
		)
		(fp_line
			(start 1.38 3.5)
			(end -1.38 3.5)
			(stroke
				(width 0.2)
				(type solid)
			)
			(layer "F.SilkS")
		)
		(fp_line
			(start 1.38 -3.5)
			(end -1.38 -3.5)
			(stroke
				(width 0.2)
				(type solid)
			)
			(layer "F.SilkS")
		)
		(fp_line
			(start -3.5 -1.38)
			(end -3.5 1.38)
			(stroke
				(width 0.2)
				(type solid)
			)
			(layer "F.SilkS")
		)
		(pad "1" thru_hole rect
			(at 0 0 180)
			(size 2 2)
			(drill 1.5)
			(layers "*.Cu" "*.Mask")
			(remove_unused_layers no)
			(net "NetAN1_1")
		)
		(pad "2" thru_hole circle
			(at -2.54 -2.54 180)
			(size 2.2 2.2)
			(drill 1.7)
			(layers "*.Cu" "*.Mask")
			(remove_unused_layers no)
			(net "GND")
			(thermal_bridge_angle 90)
		)
		(pad "3" thru_hole circle
			(at -2.54 2.54 180)
			(size 2.2 2.2)
			(drill 1.7)
			(layers "*.Cu" "*.Mask")
			(remove_unused_layers no)
			(net "GND")
			(thermal_bridge_angle 90)
		)
		(pad "4" thru_hole circle
			(at 2.54 2.54 180)
			(size 2.2 2.2)
			(drill 1.7)
			(layers "*.Cu" "*.Mask")
			(remove_unused_layers no)
			(net "GND")
			(thermal_bridge_angle 90)
		)
		(pad "5" thru_hole circle
			(at 2.54 -2.54 180)
			(size 2.2 2.2)
			(drill 1.7)
			(layers "*.Cu" "*.Mask")
			(remove_unused_layers no)
			(net "GND")
			(thermal_bridge_angle 90)
		)
	)
	(footprint "Vault:FP-0402-L_1_0_1-W_0_5_0_1-IPC_C"
		(layer "F.Cu")
		(at 228.2216 132.0162)
		(property "Reference" "C89"
			(at 2.6286 0.126931 0)
			(unlocked yes)
			(layer "F.SilkS")
			(effects
				(font
					(size 0.762 0.762)
					(thickness 0.2286)
				)
			)
		)
		(property "Value" "0.1uF_25V_0402"
			(at -2.465551 9.839215 270)
			(unlocked yes)
			(layer "F.SilkS")
			(hide yes)
			(effects
				(font
					(size 0.762 0.762)
					(thickness 0.2286)
				)
			)
		)
		(sheetname "09-USBUart_PPSMUX_UARTMUX")
		(sheetfile "09-USBUart_PPSMUX_UARTMUX.kicad_sch")
		(duplicate_pad_numbers_are_jumpers no)
		(fp_line
			(start -0.65607 -0.7)
			(end 0.65607 -0.7)
			(stroke
				(width 0.2)
				(type solid)
			)
			(layer "F.SilkS")
		)
		(fp_line
			(start -0.65607 0.7)
			(end 0.65607 0.7)
			(stroke
				(width 0.2)
				(type solid)
			)
			(layer "F.SilkS")
		)
		(fp_line
			(start -0.75607 -0.4)
			(end 0.75607 -0.4)
			(stroke
				(width 0.2)
				(type solid)
			)
			(layer "F.CrtYd")
		)
		(fp_line
			(start -0.75607 0.4)
			(end -0.75607 -0.4)
			(stroke
				(width 0.2)
				(type solid)
			)
			(layer "F.CrtYd")
		)
		(fp_line
			(start -0.75607 0.4)
			(end 0.75607 0.4)
			(stroke
				(width 0.2)
				(type solid)
			)
			(layer "F.CrtYd")
		)
		(fp_line
			(start 0.75607 0.4)
			(end 0.75607 -0.4)
			(stroke
				(width 0.2)
				(type solid)
			)
			(layer "F.CrtYd")
		)
		(fp_line
			(start -0.75607 -0.4)
			(end 0.75607 -0.4)
			(stroke
				(width 0.2)
				(type solid)
			)
			(layer "F.Fab")
		)
		(fp_line
			(start -0.75607 0.4)
			(end -0.75607 -0.4)
			(stroke
				(width 0.2)
				(type solid)
			)
			(layer "F.Fab")
		)
		(fp_line
			(start -0.75607 0.4)
			(end 0.75607 0.4)
			(stroke
				(width 0.2)
				(type solid)
			)
			(layer "F.Fab")
		)
		(fp_line
			(start -0.5 0)
			(end 0.5 0)
			(stroke
				(width 0.1)
				(type solid)
			)
			(layer "F.Fab")
		)
		(fp_line
			(start 0 0.5)
			(end 0 -0.5)
			(stroke
				(width 0.1)
				(type solid)
			)
			(layer "F.Fab")
		)
		(fp_line
			(start 0.75607 0.4)
			(end 0.75607 -0.4)
			(stroke
				(width 0.2)
				(type solid)
			)
			(layer "F.Fab")
		)
		(fp_text user "${REFERENCE}"
			(at -0.00001 0.09602 360)
			(unlocked yes)
			(layer "F.Fab")
			(effects
				(font
					(face "Arial")
					(size 0.63 0.63)
					(thickness 0.1)
				)
				(justify left bottom)
			)
		)
		(pad "1" smd rect
			(at -0.36554 0)
			(size 0.58106 0.51213)
			(layers "F.Cu" "F.Mask" "F.Paste")
			(net "FTDI_VBUS")
			(solder_mask_margin 0)
			(solder_paste_margin 0)
		)
		(pad "2" smd rect
			(at 0.36554 0)
			(size 0.58106 0.51213)
			(layers "F.Cu" "F.Mask" "F.Paste")
			(net "GND")
			(solder_mask_margin 0)
			(solder_paste_margin 0)
		)
	)
	(footprint "Vault:FP-LTST-C191KGKT-MFG"
		(layer "F.Cu")
		(at 79.4216 50.3662)
		(property "Reference" "D3"
			(at -4.571395 -0.323069 0)
			(unlocked yes)
			(layer "F.SilkS")
			(effects
				(font
					(size 0.762 0.762)
					(thickness 0.2286)
				)
			)
		)
		(property "Value" "LTST-C191KGKT"
			(at 1.2818 2.452871 0)
			(unlocked yes)
			(layer "F.SilkS")
			(hide yes)
			(effects
				(font
					(size 0.762 0.762)
					(thickness 0.2286)
				)
			)
		)
		(sheetname "02-USER_IO_STATUS")
		(sheetfile "02-USER_IO_STATUS.kicad_sch")
		(duplicate_pad_numbers_are_jumpers no)
		(fp_line
			(start -0.85 -0.775)
			(end 0.85 -0.775)
			(stroke
				(width 0.2)
				(type solid)
			)
			(layer "F.SilkS")
		)
		(fp_line
			(start -0.85 0.775)
			(end 0.85 0.775)
			(stroke
				(width 0.2)
				(type solid)
			)
			(layer "F.SilkS")
		)
		(fp_circle
			(center -1.7 0)
			(end -1.7 -0.125)
			(stroke
				(width 0.25)
				(type solid)
			)
			(fill no)
			(layer "F.SilkS")
		)
		(fp_line
			(start -1.25 -0.55)
			(end 1.25 -0.55)
			(stroke
				(width 0.2)
				(type solid)
			)
			(layer "F.CrtYd")
		)
		(fp_line
			(start -1.25 0.55)
			(end -1.25 -0.55)
			(stroke
				(width 0.2)
				(type solid)
			)
			(layer "F.CrtYd")
		)
		(fp_line
			(start -1.25 0.55)
			(end 1.25 0.55)
			(stroke
				(width 0.2)
				(type solid)
			)
			(layer "F.CrtYd")
		)
		(fp_line
			(start 1.25 0.55)
			(end 1.25 -0.55)
			(stroke
				(width 0.2)
				(type solid)
			)
			(layer "F.CrtYd")
		)
		(fp_line
			(start -1.25 -0.55)
			(end 1.25 -0.55)
			(stroke
				(width 0.2)
				(type solid)
			)
			(layer "F.Fab")
		)
		(fp_line
			(start -1.25 0.55)
			(end -1.25 -0.55)
			(stroke
				(width 0.2)
				(type solid)
			)
			(layer "F.Fab")
		)
		(fp_line
			(start -1.25 0.55)
			(end 1.25 0.55)
			(stroke
				(width 0.2)
				(type solid)
			)
			(layer "F.Fab")
		)
		(fp_line
			(start -0.5 0)
			(end 0.5 0)
			(stroke
				(width 0.1)
				(type solid)
			)
			(layer "F.Fab")
		)
		(fp_line
			(start 0 0.5)
			(end 0 -0.5)
			(stroke
				(width 0.1)
				(type solid)
			)
			(layer "F.Fab")
		)
		(fp_line
			(start 1.25 0.55)
			(end 1.25 -0.55)
			(stroke
				(width 0.2)
				(type solid)
			)
			(layer "F.Fab")
		)
		(fp_text user "${REFERENCE}"
			(at 0 0.28425 360)
			(unlocked yes)
			(layer "F.Fab")
			(effects
				(font
					(face "Arial")
					(size 0.63 0.63)
					(thickness 0.1)
				)
				(justify left bottom)
			)
		)
		(pad "1" smd rect
			(at -0.75 0)
			(size 0.8 0.8)
			(layers "F.Cu" "F.Mask" "F.Paste")
			(net "NetD3_1")
			(solder_mask_margin 0)
			(solder_paste_margin 0)
		)
		(pad "2" smd rect
			(at 0.75 0)
			(size 0.8 0.8)
			(layers "F.Cu" "F.Mask" "F.Paste")
			(net "+3.3V")
			(solder_mask_margin 0)
			(solder_paste_margin 0)
		)
	)
	(footprint "Vault:FP-D0008A-MFG"
		(layer "F.Cu")
		(at 226.0216 73.6162 90)
		(property "Reference" "U2"
			(at 0.5 2.806655 270)
			(unlocked yes)
			(layer "F.SilkS")
			(effects
				(font
					(size 0.762 0.762)
					(thickness 0.2286)
				)
				(justify left bottom)
			)
		)
		(property "Value" "INA219BIDR"
			(at -9.427445 10.9955 0)
			(unlocked yes)
			(layer "F.SilkS")
			(hide yes)
			(effects
				(font
					(size 0.762 0.762)
					(thickness 0.2286)
				)
				(justify left bottom)
			)
		)
		(sheetname "03-POWER")
		(sheetfile "03-POWER.kicad_sch")
		(duplicate_pad_numbers_are_jumpers no)
		(fp_line
			(start 1.5 -2.5)
			(end 1.5 2.5)
			(stroke
				(width 0.2)
				(type solid)
			)
			(layer "F.SilkS")
		)
		(fp_line
			(start -1.5 -2.5)
			(end 1.5 -2.5)
			(stroke
				(width 0.2)
				(type solid)
			)
			(layer "F.SilkS")
		)
		(fp_line
			(start -1.5 -2.5)
			(end -1.5 2.5)
			(stroke
				(width 0.2)
				(type solid)
			)
			(layer "F.SilkS")
		)
		(fp_line
			(start -1.5 2.5)
			(end 1.5 2.5)
			(stroke
				(width 0.2)
				(type solid)
			)
			(layer "F.SilkS")
		)
		(fp_circle
			(center -4.05 -1.905)
			(end -3.925 -1.905)
			(stroke
				(width 0.25)
				(type solid)
			)
			(fill no)
			(layer "F.SilkS")
		)
		(fp_circle
			(center -0.725 -1.725)
			(end -0.475 -1.725)
			(stroke
				(width 0.5)
				(type solid)
			)
			(fill no)
			(layer "F.SilkS")
		)
		(fp_line
			(start 3.575 -2.75)
			(end 3.575 2.75)
			(stroke
				(width 0.2)
				(type solid)
			)
			(layer "F.CrtYd")
		)
		(fp_line
			(start -3.575 -2.75)
			(end 3.575 -2.75)
			(stroke
				(width 0.2)
				(type solid)
			)
			(layer "F.CrtYd")
		)
		(fp_line
			(start -3.575 -2.75)
			(end -3.575 2.75)
			(stroke
				(width 0.2)
				(type solid)
			)
			(layer "F.CrtYd")
		)
		(fp_line
			(start -3.575 2.75)
			(end 3.575 2.75)
			(stroke
				(width 0.2)
				(type solid)
			)
			(layer "F.CrtYd")
		)
		(fp_line
			(start 3.575 -2.75)
			(end 3.575 2.75)
			(stroke
				(width 0.2)
				(type solid)
			)
			(layer "F.Fab")
		)
		(fp_line
			(start -3.575 -2.75)
			(end 3.575 -2.75)
			(stroke
				(width 0.2)
				(type solid)
			)
			(layer "F.Fab")
		)
		(fp_line
			(start -3.575 -2.75)
			(end -3.575 2.75)
			(stroke
				(width 0.2)
				(type solid)
			)
			(layer "F.Fab")
		)
		(fp_line
			(start 0 -0.5)
			(end 0 0.5)
			(stroke
				(width 0.1)
				(type solid)
			)
			(layer "F.Fab")
		)
		(fp_line
			(start -0.5 0)
			(end 0.5 0)
			(stroke
				(width 0.1)
				(type solid)
			)
			(layer "F.Fab")
		)
		(fp_line
			(start -3.575 2.75)
			(end 3.575 2.75)
			(stroke
				(width 0.2)
				(type solid)
			)
			(layer "F.Fab")
		)
		(fp_text user "${REFERENCE}"
			(at -0.00002 0.09601 90)
			(unlocked yes)
			(layer "F.Fab")
			(effects
				(font
					(face "Arial")
					(size 0.63 0.63)
					(thickness 0.1)
				)
				(justify left bottom)
			)
		)
		(pad "1" smd roundrect
			(at -2.7 -1.905 90)
			(size 1.55 0.6)
			(layers "F.Cu" "F.Mask" "F.Paste")
			(roundrect_rratio 0.085)
			(net "NetR64_1")
			(solder_mask_margin 0)
			(solder_paste_margin 0)
		)
		(pad "2" smd roundrect
			(at -2.7 -0.635 90)
			(size 1.55 0.6)
			(layers "F.Cu" "F.Mask" "F.Paste")
			(roundrect_rratio 0.085)
			(net "NetR62_1")
			(solder_mask_margin 0)
			(solder_paste_margin 0)
		)
		(pad "3" smd roundrect
			(at -2.7 0.635 90)
			(size 1.55 0.6)
			(layers "F.Cu" "F.Mask" "F.Paste")
			(roundrect_rratio 0.085)
			(net "SENS_I2C_SDA")
			(solder_mask_margin 0)
			(solder_paste_margin 0)
		)
		(pad "4" smd roundrect
			(at -2.7 1.905 90)
			(size 1.55 0.6)
			(layers "F.Cu" "F.Mask" "F.Paste")
			(roundrect_rratio 0.085)
			(net "SENS_I2C_SCL")
			(solder_mask_margin 0)
			(solder_paste_margin 0)
		)
		(pad "5" smd roundrect
			(at 2.7 1.905 90)
			(size 1.55 0.6)
			(layers "F.Cu" "F.Mask" "F.Paste")
			(roundrect_rratio 0.085)
			(net "+3.3V")
			(solder_mask_margin 0)
			(solder_paste_margin 0)
		)
		(pad "6" smd roundrect
			(at 2.7 0.635 90)
			(size 1.55 0.6)
			(layers "F.Cu" "F.Mask" "F.Paste")
			(roundrect_rratio 0.085)
			(net "GND")
			(solder_mask_margin 0)
			(solder_paste_margin 0)
		)
		(pad "7" smd roundrect
			(at 2.7 -0.635 90)
			(size 1.55 0.6)
			(layers "F.Cu" "F.Mask" "F.Paste")
			(roundrect_rratio 0.085)
			(net "+12V")
			(solder_mask_margin 0)
			(solder_paste_margin 0)
		)
		(pad "8" smd roundrect
			(at 2.7 -1.905 90)
			(size 1.55 0.6)
			(layers "F.Cu" "F.Mask" "F.Paste")
			(roundrect_rratio 0.085)
			(net "+12V_SENS")
			(solder_mask_margin 0)
			(solder_paste_margin 0)
		)
	)
	(footprint "Vault:FP-LTST-C191KGKT-MFG"
		(layer "F.Cu")
		(at 187.5716 74.5162)
		(property "Reference" "D20"
			(at 0.1786 -1.473079 0)
			(unlocked yes)
			(layer "F.SilkS")
			(effects
				(font
					(size 0.762 0.762)
					(thickness 0.2286)
				)
			)
		)
		(property "Value" "LTST-C191KGKT"
			(at -3.519671 10.67713 270)
			(unlocked yes)
			(layer "F.SilkS")
			(hide yes)
			(effects
				(font
					(size 0.762 0.762)
					(thickness 0.2286)
				)
			)
		)
		(sheetname "03-POWER")
		(sheetfile "03-POWER.kicad_sch")
		(duplicate_pad_numbers_are_jumpers no)
		(fp_line
			(start -0.85 -0.775)
			(end 0.85 -0.775)
			(stroke
				(width 0.2)
				(type solid)
			)
			(layer "F.SilkS")
		)
		(fp_line
			(start -0.85 0.775)
			(end 0.85 0.775)
			(stroke
				(width 0.2)
				(type solid)
			)
			(layer "F.SilkS")
		)
		(fp_circle
			(center -1.7 0)
			(end -1.7 -0.125)
			(stroke
				(width 0.25)
				(type solid)
			)
			(fill no)
			(layer "F.SilkS")
		)
		(fp_line
			(start -1.25 -0.55)
			(end 1.25 -0.55)
			(stroke
				(width 0.2)
				(type solid)
			)
			(layer "F.CrtYd")
		)
		(fp_line
			(start -1.25 0.55)
			(end -1.25 -0.55)
			(stroke
				(width 0.2)
				(type solid)
			)
			(layer "F.CrtYd")
		)
		(fp_line
			(start -1.25 0.55)
			(end 1.25 0.55)
			(stroke
				(width 0.2)
				(type solid)
			)
			(layer "F.CrtYd")
		)
		(fp_line
			(start 1.25 0.55)
			(end 1.25 -0.55)
			(stroke
				(width 0.2)
				(type solid)
			)
			(layer "F.CrtYd")
		)
		(fp_line
			(start -1.25 -0.55)
			(end 1.25 -0.55)
			(stroke
				(width 0.2)
				(type solid)
			)
			(layer "F.Fab")
		)
		(fp_line
			(start -1.25 0.55)
			(end -1.25 -0.55)
			(stroke
				(width 0.2)
				(type solid)
			)
			(layer "F.Fab")
		)
		(fp_line
			(start -1.25 0.55)
			(end 1.25 0.55)
			(stroke
				(width 0.2)
				(type solid)
			)
			(layer "F.Fab")
		)
		(fp_line
			(start -0.5 0)
			(end 0.5 0)
			(stroke
				(width 0.1)
				(type solid)
			)
			(layer "F.Fab")
		)
		(fp_line
			(start 0 0.5)
			(end 0 -0.5)
			(stroke
				(width 0.1)
				(type solid)
			)
			(layer "F.Fab")
		)
		(fp_line
			(start 1.25 0.55)
			(end 1.25 -0.55)
			(stroke
				(width 0.2)
				(type solid)
			)
			(layer "F.Fab")
		)
		(fp_text user "${REFERENCE}"
			(at 0 0.28425 360)
			(unlocked yes)
			(layer "F.Fab")
			(effects
				(font
					(face "Arial")
					(size 0.63 0.63)
					(thickness 0.1)
				)
				(justify left bottom)
			)
		)
		(pad "1" smd rect
			(at -0.75 0)
			(size 0.8 0.8)
			(layers "F.Cu" "F.Mask" "F.Paste")
			(net "NetD20_1")
			(solder_mask_margin 0)
			(solder_paste_margin 0)
		)
		(pad "2" smd rect
			(at 0.75 0)
			(size 0.8 0.8)
			(layers "F.Cu" "F.Mask" "F.Paste")
			(net "+3.3V")
			(solder_mask_margin 0)
			(solder_paste_margin 0)
		)
	)
	(footprint "Vault:RESC1608X55X25NL10T15"
		(layer "F.Cu")
		(at 75.4216 99.7162 180)
		(property "Reference" "R25"
			(at -0.2286 1.223079 0)
			(unlocked yes)
			(layer "F.SilkS")
			(effects
				(font
					(size 0.762 0.762)
					(thickness 0.2286)
				)
			)
		)
		(property "Value" "49.9R"
			(at -2.884671 3.186595 90)
			(unlocked yes)
			(layer "F.SilkS")
			(hide yes)
			(effects
				(font
					(size 0.762 0.762)
					(thickness 0.2286)
				)
			)
		)
		(sheetname "01-USER_IO")
		(sheetfile "01-USER_IO.kicad_sch")
		(duplicate_pad_numbers_are_jumpers no)
		(pad "1" smd rect
			(at -0.7 0 270)
			(size 0.9 0.7)
			(layers "F.Cu" "F.Mask" "F.Paste")
			(net "NetR25_1")
		)
		(pad "2" smd rect
			(at 0.7 0 270)
			(size 0.9 0.7)
			(layers "F.Cu" "F.Mask" "F.Paste")
			(net "NetAN1_1")
		)
	)
	(footprint "Vault:RESC1005X40X25NL10T10"
		(layer "F.Cu")
		(at 169.8216 110.4162)
		(property "Reference" "R124"
			(at -0.1968 -1.073069 0)
			(unlocked yes)
			(layer "F.SilkS")
			(effects
				(font
					(size 0.762 0.762)
					(thickness 0.2032)
				)
			)
		)
		(property "Value" "4.7K_1%_0402"
			(at -2.732281 8.747475 270)
			(unlocked yes)
			(layer "F.SilkS")
			(hide yes)
			(effects
				(font
					(size 0.762 0.762)
					(thickness 0.2032)
				)
			)
		)
		(sheetname "08-DIPSwitches_I2C")
		(sheetfile "08-DIPSwitches_I2C.kicad_sch")
		(duplicate_pad_numbers_are_jumpers no)
		(pad "1" smd rect
			(at -0.425 0 90)
			(size 0.6 0.65)
			(layers "F.Cu" "F.Mask" "F.Paste")
			(net "SCL")
		)
		(pad "2" smd rect
			(at 0.425 0 90)
			(size 0.6 0.65)
			(layers "F.Cu" "F.Mask" "F.Paste")
			(net "+3.3V")
		)
	)
	(footprint "SA53:SolderSocket"
		(locked yes)
		(layer "F.Cu")
		(at 116.3736 140.0162 90)
		(property "Reference" "SKT8"
			(at -3.426921 0.8766 0)
			(unlocked yes)
			(layer "F.SilkS")
			(effects
				(font
					(size 0.762 0.762)
					(thickness 0.2286)
				)
			)
		)
		(property "Value" "0332-0-43-80-18-27-10-0"
			(at -2.910071 16.1362 0)
			(unlocked yes)
			(layer "F.SilkS")
			(hide yes)
			(effects
				(font
					(size 0.762 0.762)
					(thickness 0.2286)
				)
			)
		)
		(sheetname "06-MAC")
		(sheetfile "06-MAC.kicad_sch")
		(duplicate_pad_numbers_are_jumpers no)
		(pad "1" thru_hole circle
			(at 0 0 90)
			(size 2.54 2.54)
			(drill 2.0066)
			(layers "*.Cu" "*.Mask")
			(remove_unused_layers no)
			(net "MAC_PPS_IN")
			(thermal_bridge_angle 90)
		)
	)
	(footprint "Vault:RESC1005X40X25NL10T10"
		(layer "F.Cu")
		(at 175.3216 112.0162)
		(property "Reference" "R113"
			(at 2.6032 0.126931 0)
			(unlocked yes)
			(layer "F.SilkS")
			(effects
				(font
					(size 0.762 0.762)
					(thickness 0.2032)
				)
			)
		)
		(property "Value" "4.7K_1%_0402"
			(at -2.732281 8.747475 270)
			(unlocked yes)
			(layer "F.SilkS")
			(hide yes)
			(effects
				(font
					(size 0.762 0.762)
					(thickness 0.2032)
				)
			)
		)
		(sheetname "08-DIPSwitches_I2C")
		(sheetfile "08-DIPSwitches_I2C.kicad_sch")
		(duplicate_pad_numbers_are_jumpers no)
		(pad "1" smd rect
			(at -0.425 0 90)
			(size 0.6 0.65)
			(layers "F.Cu" "F.Mask" "F.Paste")
			(net "DC_I2C_SDA")
		)
		(pad "2" smd rect
			(at 0.425 0 90)
			(size 0.6 0.65)
			(layers "F.Cu" "F.Mask" "F.Paste")
			(net "+3.3V")
		)
	)
	(footprint "Vault:RESC1005X40X25LL05T10"
		(layer "F.Cu")
		(at 194.7216 125.7162 -90)
		(property "Reference" "R175"
			(at 0.2968 2.073069 90)
			(unlocked yes)
			(layer "F.SilkS")
			(effects
				(font
					(size 0.762 0.762)
					(thickness 0.2032)
				)
			)
		)
		(property "Value" "49.9_1%_0402"
			(at -2.579871 8.798265 180)
			(unlocked yes)
			(layer "F.SilkS")
			(hide yes)
			(effects
				(font
					(size 0.762 0.762)
					(thickness 0.2032)
				)
			)
		)
		(sheetname "11-M2_RCB_MUX")
		(sheetfile "11-M2_RCB_MUX.kicad_sch")
		(duplicate_pad_numbers_are_jumpers no)
		(pad "1" smd rect
			(at -0.375 0)
			(size 0.45 0.5)
			(layers "F.Cu" "F.Mask" "F.Paste")
			(net "NetR175_1")
		)
		(pad "2" smd rect
			(at 0.375 0)
			(size 0.45 0.5)
			(layers "F.Cu" "F.Mask" "F.Paste")
			(net "GPS2_PIN12")
		)
	)
	(footprint "Vault:AMPH-901-143-6RFX_V"
		(layer "F.Cu")
		(at 69.9716 108.5782 180)
		(property "Reference" "AN2"
			(at 1.75 3.768655 0)
			(unlocked yes)
			(layer "F.SilkS")
			(effects
				(font
					(size 0.762 0.762)
					(thickness 0.2286)
				)
				(justify left bottom)
			)
		)
		(property "Value" "RF2-49B-T-00-50-G-HDW"
			(at 4.6101 -1.960245 0)
			(unlocked yes)
			(layer "F.SilkS")
			(hide yes)
			(effects
				(font
					(size 0.762 0.762)
					(thickness 0.2286)
				)
				(justify left bottom)
			)
		)
		(sheetname "01-USER_IO")
		(sheetfile "01-USER_IO.kicad_sch")
		(duplicate_pad_numbers_are_jumpers no)
		(fp_line
			(start 3.5 -1.38)
			(end 3.5 1.38)
			(stroke
				(width 0.2)
				(type solid)
			)
			(layer "F.SilkS")
		)
		(fp_line
			(start 1.38 3.5)
			(end -1.38 3.5)
			(stroke
				(width 0.2)
				(type solid)
			)
			(layer "F.SilkS")
		)
		(fp_line
			(start 1.38 -3.5)
			(end -1.38 -3.5)
			(stroke
				(width 0.2)
				(type solid)
			)
			(layer "F.SilkS")
		)
		(fp_line
			(start -3.5 -1.38)
			(end -3.5 1.38)
			(stroke
				(width 0.2)
				(type solid)
			)
			(layer "F.SilkS")
		)
		(pad "1" thru_hole rect
			(at 0 0 180)
			(size 2 2)
			(drill 1.5)
			(layers "*.Cu" "*.Mask")
			(remove_unused_layers no)
			(net "NetAN2_1")
		)
		(pad "2" thru_hole circle
			(at -2.54 -2.54 180)
			(size 2.2 2.2)
			(drill 1.7)
			(layers "*.Cu" "*.Mask")
			(remove_unused_layers no)
			(net "GND")
			(thermal_bridge_angle 90)
		)
		(pad "3" thru_hole circle
			(at -2.54 2.54 180)
			(size 2.2 2.2)
			(drill 1.7)
			(layers "*.Cu" "*.Mask")
			(remove_unused_layers no)
			(net "GND")
			(thermal_bridge_angle 90)
		)
		(pad "4" thru_hole circle
			(at 2.54 2.54 180)
			(size 2.2 2.2)
			(drill 1.7)
			(layers "*.Cu" "*.Mask")
			(remove_unused_layers no)
			(net "GND")
			(thermal_bridge_angle 90)
		)
		(pad "5" thru_hole circle
			(at 2.54 -2.54 180)
			(size 2.2 2.2)
			(drill 1.7)
			(layers "*.Cu" "*.Mask")
			(remove_unused_layers no)
			(net "GND")
			(thermal_bridge_angle 90)
		)
	)
	(footprint "Vault:RESC1005X40X25LL05T05"
		(layer "F.Cu")
		(at 84.65686 82.56371)
		(property "Reference" "R109"
			(at -2.87139 -0.073079 0)
			(unlocked yes)
			(layer "F.SilkS")
			(effects
				(font
					(size 0.762 0.762)
					(thickness 0.2286)
				)
			)
		)
		(property "Value" "4.7K_0402"
			(at -2.389351 6.513005 270)
			(unlocked yes)
			(layer "F.SilkS")
			(hide yes)
			(effects
				(font
					(size 0.762 0.762)
					(thickness 0.2032)
				)
			)
		)
		(sheetname "02-USER_IO_STATUS")
		(sheetfile "02-USER_IO_STATUS.kicad_sch")
		(duplicate_pad_numbers_are_jumpers no)
		(pad "1" smd rect
			(at -0.39999 0 90)
			(size 0.45 0.45)
			(layers "F.Cu" "F.Mask" "F.Paste")
			(net "+3.3V")
		)
		(pad "2" smd rect
			(at 0.40001 0 90)
			(size 0.45 0.45)
			(layers "F.Cu" "F.Mask" "F.Paste")
			(net "NetR40_2")
		)
	)
	(footprint "Vault:FP-ERJ2RK-IPC_A"
		(layer "F.Cu")
		(at 191.4216 74.5162 180)
		(property "Reference" "R77"
			(at -0.3286 1.573079 0)
			(unlocked yes)
			(layer "F.SilkS")
			(effects
				(font
					(size 0.762 0.762)
					(thickness 0.2286)
				)
			)
		)
		(property "Value" "200_1%_0402"
			(at -2.935471 7.782475 90)
			(unlocked yes)
			(layer "F.SilkS")
			(hide yes)
			(effects
				(font
					(size 0.762 0.762)
					(thickness 0.2286)
				)
			)
		)
		(sheetname "03-POWER")
		(sheetfile "03-POWER.kicad_sch")
		(duplicate_pad_numbers_are_jumpers no)
		(fp_line
			(start 0.83624 0.73624)
			(end -0.83624 0.73624)
			(stroke
				(width 0.2)
				(type solid)
			)
			(layer "F.SilkS")
		)
		(fp_line
			(start 0.83624 -0.73624)
			(end -0.83624 -0.73624)
			(stroke
				(width 0.2)
				(type solid)
			)
			(layer "F.SilkS")
		)
		(fp_line
			(start 1.03624 0.53624)
			(end -1.03624 0.53624)
			(stroke
				(width 0.2)
				(type solid)
			)
			(layer "F.CrtYd")
		)
		(fp_line
			(start 1.03624 -0.53624)
			(end 1.03624 0.53624)
			(stroke
				(width 0.2)
				(type solid)
			)
			(layer "F.CrtYd")
		)
		(fp_line
			(start 1.03624 -0.53624)
			(end -1.03624 -0.53624)
			(stroke
				(width 0.2)
				(type solid)
			)
			(layer "F.CrtYd")
		)
		(fp_line
			(start -1.03624 -0.53624)
			(end -1.03624 0.53624)
			(stroke
				(width 0.2)
				(type solid)
			)
			(layer "F.CrtYd")
		)
		(fp_line
			(start 1.03624 0.53624)
			(end -1.03624 0.53624)
			(stroke
				(width 0.2)
				(type solid)
			)
			(layer "F.Fab")
		)
		(fp_line
			(start 1.03624 -0.53624)
			(end 1.03624 0.53624)
			(stroke
				(width 0.2)
				(type solid)
			)
			(layer "F.Fab")
		)
		(fp_line
			(start 1.03624 -0.53624)
			(end -1.03624 -0.53624)
			(stroke
				(width 0.2)
				(type solid)
			)
			(layer "F.Fab")
		)
		(fp_line
			(start 0.5 0)
			(end -0.5 0)
			(stroke
				(width 0.1)
				(type solid)
			)
			(layer "F.Fab")
		)
		(fp_line
			(start 0 -0.5)
			(end 0 0.5)
			(stroke
				(width 0.1)
				(type solid)
			)
			(layer "F.Fab")
		)
		(fp_line
			(start -1.03624 -0.53624)
			(end -1.03624 0.53624)
			(stroke
				(width 0.2)
				(type solid)
			)
			(layer "F.Fab")
		)
		(fp_text user "${REFERENCE}"
			(at -0.00001 0.10711 180)
			(unlocked yes)
			(layer "F.Fab")
			(effects
				(font
					(face "Arial")
					(size 0.63 0.63)
					(thickness 0.1)
				)
				(justify left bottom)
			)
		)
		(pad "1" smd rect
			(at -0.50215 0 180)
			(size 0.66818 0.67248)
			(layers "F.Cu" "F.Mask" "F.Paste")
			(net "GND")
			(solder_mask_margin 0)
			(solder_paste_margin 0)
		)
		(pad "2" smd rect
			(at 0.50215 0 180)
			(size 0.66818 0.67248)
			(layers "F.Cu" "F.Mask" "F.Paste")
			(net "NetD20_1")
			(solder_mask_margin 0)
			(solder_paste_margin 0)
		)
	)
	(footprint "Vault:FP-RUT0012A-MFG"
		(layer "F.Cu")
		(at 143.7216 104.7162 90)
		(property "Reference" "U23"
			(at 2.273079 -2.6714 0)
			(unlocked yes)
			(layer "F.SilkS")
			(effects
				(font
					(size 0.762 0.762)
					(thickness 0.2286)
				)
			)
		)
		(property "Value" "TMUX1072RUTR"
			(at 7.426675 3.164071 90)
			(unlocked yes)
			(layer "F.SilkS")
			(hide yes)
			(effects
				(font
					(size 0.762 0.762)
					(thickness 0.2286)
				)
			)
		)
		(sheetname "09-USBUart_PPSMUX_UARTMUX")
		(sheetfile "09-USBUart_PPSMUX_UARTMUX.kicad_sch")
		(duplicate_pad_numbers_are_jumpers no)
		(fp_line
			(start -0.9 -1.525)
			(end 0.9 -1.525)
			(stroke
				(width 0.2)
				(type solid)
			)
			(layer "F.SilkS")
		)
		(fp_line
			(start -0.9 1.525)
			(end 0.9 1.525)
			(stroke
				(width 0.2)
				(type solid)
			)
			(layer "F.SilkS")
		)
		(fp_circle
			(center -1.575 -0.8)
			(end -1.45 -0.8)
			(stroke
				(width 0.25)
				(type solid)
			)
			(fill no)
			(layer "F.SilkS")
		)
		(fp_rect
			(start 0.35004 -0.69996)
			(end 0.85004 -0.89996)
			(stroke
				(width 0)
				(type default)
			)
			(fill yes)
			(layer "F.Paste")
		)
		(fp_rect
			(start -0.10006 -0.49994)
			(end 0.09994 -0.99994)
			(stroke
				(width 0)
				(type default)
			)
			(fill yes)
			(layer "F.Paste")
		)
		(fp_rect
			(start 0.34996 -0.30004)
			(end 0.84996 -0.50004)
			(stroke
				(width 0)
				(type default)
			)
			(fill yes)
			(layer "F.Paste")
		)
		(fp_rect
			(start -0.84996 -0.29996)
			(end -0.34996 -0.49996)
			(stroke
				(width 0)
				(type default)
			)
			(fill yes)
			(layer "F.Paste")
		)
		(fp_rect
			(start 0.34996 0.09996)
			(end 0.84996 -0.10004)
			(stroke
				(width 0)
				(type default)
			)
			(fill yes)
			(layer "F.Paste")
		)
		(fp_rect
			(start -0.84996 0.10004)
			(end -0.34996 -0.09996)
			(stroke
				(width 0)
				(type default)
			)
			(fill yes)
			(layer "F.Paste")
		)
		(fp_rect
			(start 0.34996 0.49996)
			(end 0.84996 0.29996)
			(stroke
				(width 0)
				(type default)
			)
			(fill yes)
			(layer "F.Paste")
		)
		(fp_rect
			(start -0.84996 0.50004)
			(end -0.34996 0.30004)
			(stroke
				(width 0)
				(type default)
			)
			(fill yes)
			(layer "F.Paste")
		)
		(fp_rect
			(start -0.850045 0.899965)
			(end -0.350035 0.699965)
			(stroke
				(width 0)
				(type default)
			)
			(fill yes)
			(layer "F.Paste")
		)
		(fp_rect
			(start 0.35004 0.90004)
			(end 0.85004 0.70004)
			(stroke
				(width 0)
				(type default)
			)
			(fill yes)
			(layer "F.Paste")
		)
		(fp_rect
			(start -0.09994 0.99994)
			(end 0.10006 0.49994)
			(stroke
				(width 0)
				(type default)
			)
			(fill yes)
			(layer "F.Paste")
		)
		(fp_poly
			(pts
				(xy -0.5 -1) (xy -0.35 -1) (xy -0.35 -0.7) (xy -0.85 -0.7) (xy -0.85 -0.9) (xy -0.5 -0.9)
			)
			(stroke
				(width 0)
				(type default)
			)
			(fill yes)
			(layer "F.Paste")
		)
		(fp_line
			(start 1.05 -1.2)
			(end 1.05 1.2)
			(stroke
				(width 0.2)
				(type solid)
			)
			(layer "F.CrtYd")
		)
		(fp_line
			(start -1.05 -1.2)
			(end 1.05 -1.2)
			(stroke
				(width 0.2)
				(type solid)
			)
			(layer "F.CrtYd")
		)
		(fp_line
			(start -1.05 -1.2)
			(end -1.05 1.2)
			(stroke
				(width 0.2)
				(type solid)
			)
			(layer "F.CrtYd")
		)
		(fp_line
			(start -1.05 1.2)
			(end 1.05 1.2)
			(stroke
				(width 0.2)
				(type solid)
			)
			(layer "F.CrtYd")
		)
		(fp_line
			(start 1.05 -1.2)
			(end 1.05 1.2)
			(stroke
				(width 0.2)
				(type solid)
			)
			(layer "F.Fab")
		)
		(fp_line
			(start -1.05 -1.2)
			(end 1.05 -1.2)
			(stroke
				(width 0.2)
				(type solid)
			)
			(layer "F.Fab")
		)
		(fp_line
			(start -1.05 -1.2)
			(end -1.05 1.2)
			(stroke
				(width 0.2)
				(type solid)
			)
			(layer "F.Fab")
		)
		(fp_line
			(start 0 -0.5)
			(end 0 0.5)
			(stroke
				(width 0.1)
				(type solid)
			)
			(layer "F.Fab")
		)
		(fp_line
			(start -0.5 0)
			(end 0.5 0)
			(stroke
				(width 0.1)
				(type solid)
			)
			(layer "F.Fab")
		)
		(fp_line
			(start -1.05 1.2)
			(end 1.05 1.2)
			(stroke
				(width 0.2)
				(type solid)
			)
			(layer "F.Fab")
		)
		(fp_text user "${REFERENCE}"
			(at -0.00001 0.09602 90)
			(unlocked yes)
			(layer "F.Fab")
			(effects
				(font
					(face "Arial")
					(size 0.63 0.63)
					(thickness 0.1)
				)
				(justify left bottom)
			)
		)
		(pad "" smd custom
			(at -0.5 -1.1)
			(size 0.000001 0.000001)
			(layers "F.Cu" "F.Mask")
			(solder_mask_margin 0)
			(thermal_bridge_angle 90)
			(options
				(clearance outline)
				(anchor circle)
			)
			(primitives
				(gr_poly
					(pts
						(xy 0 0) (xy 0 -0.15) (xy 0.4 -0.15) (xy 0.4 0.45) (xy 0.2 0.45) (xy 0.2 0)
					)
					(width 0)
					(fill yes)
				)
			)
		)
		(pad "1" smd circle
			(at -0.45 -0.8 90)
			(size 0.18 0.18)
			(layers "F.Cu" "F.Mask" "F.Paste")
			(net "DIP_SW_PPS_SEL")
			(solder_mask_margin 0)
			(solder_paste_margin -1000)
			(thermal_bridge_angle 90)
		)
		(pad "2" smd rect
			(at -0.65 -0.4 90)
			(size 0.6 0.2)
			(layers "F.Cu" "F.Mask" "F.Paste")
			(net "NetR97_2")
			(solder_mask_margin 0)
			(solder_paste_margin -1000)
		)
		(pad "3" smd rect
			(at -0.65 0 90)
			(size 0.6 0.2)
			(layers "F.Cu" "F.Mask" "F.Paste")
			(net "GND")
			(solder_mask_margin 0)
			(solder_paste_margin -1000)
		)
		(pad "4" smd rect
			(at -0.65 0.4 90)
			(size 0.6 0.2)
			(layers "F.Cu" "F.Mask" "F.Paste")
			(net "NetR99_2")
			(solder_mask_margin 0)
			(solder_paste_margin -1000)
		)
		(pad "5" smd rect
			(at -0.65 0.8 90)
			(size 0.6 0.2)
			(layers "F.Cu" "F.Mask" "F.Paste")
			(net "DIP_SW_PPS_SEL")
			(solder_mask_margin 0)
			(solder_paste_margin -1000)
		)
		(pad "6" smd rect
			(at 0 0.8 90)
			(size 0.2 0.6)
			(layers "F.Cu" "F.Mask" "F.Paste")
			(net "GND")
			(solder_mask_margin 0)
			(solder_paste_margin -1000)
		)
		(pad "7" smd rect
			(at 0.65 0.8 90)
			(size 0.6 0.2)
			(layers "F.Cu" "F.Mask" "F.Paste")
			(net "FPGA_MAC_PPS_IN0-")
			(solder_mask_margin 0)
			(solder_paste_margin -1000)
		)
		(pad "8" smd rect
			(at 0.65 0.4 90)
			(size 0.6 0.2)
			(layers "F.Cu" "F.Mask" "F.Paste")
			(net "NetR98_2")
			(solder_mask_margin 0)
			(solder_paste_margin -1000)
		)
		(pad "9" smd rect
			(at 0.65 0 90)
			(size 0.6 0.2)
			(layers "F.Cu" "F.Mask" "F.Paste")
			(net "+3.3V")
			(solder_mask_margin 0)
			(solder_paste_margin -1000)
		)
		(pad "10" smd rect
			(at 0.65 -0.4 90)
			(size 0.6 0.2)
			(layers "F.Cu" "F.Mask" "F.Paste")
			(net "NetR96_2")
			(solder_mask_margin 0)
			(solder_paste_margin -1000)
		)
		(pad "11" smd rect
			(at 0.65 -0.8 90)
			(size 0.6 0.2)
			(layers "F.Cu" "F.Mask" "F.Paste")
			(net "FPGA_MAC_PPS_OUT-")
			(solder_mask_margin 0)
			(solder_paste_margin -1000)
		)
		(pad "12" smd rect
			(at 0 -0.8 90)
			(size 0.2 0.6)
			(layers "F.Cu" "F.Mask" "F.Paste")
			(net "GND")
			(solder_mask_margin 0)
			(solder_paste_margin -1000)
		)
	)
	(footprint "Vault:TECO-1909763-1_V"
		(layer "F.Cu")
		(at 77.19563 95.0786 -90)
		(property "Reference" "J1"
			(at -3.435469 -0.054565 0)
			(unlocked yes)
			(layer "F.SilkS")
			(effects
				(font
					(size 0.762 0.762)
					(thickness 0.2286)
				)
			)
		)
		(property "Value" "1909763-1"
			(at 4.582685 3.722871 270)
			(unlocked yes)
			(layer "F.SilkS")
			(hide yes)
			(effects
				(font
					(size 0.762 0.762)
					(thickness 0.2286)
				)
			)
		)
		(sheetname "01-USER_IO")
		(sheetfile "01-USER_IO.kicad_sch")
		(duplicate_pad_numbers_are_jumpers no)
		(fp_line
			(start 0.55 -1.3)
			(end -0.55 -1.3)
			(stroke
				(width 0.2)
				(type solid)
			)
			(layer "F.SilkS")
		)
		(fp_circle
			(center -1.778 1.65)
			(end -1.903 1.65)
			(stroke
				(width 0.25)
				(type solid)
			)
			(fill no)
			(layer "F.SilkS")
		)
		(pad "1" smd rect
			(at -1.475 0 270)
			(size 1.05 2.2)
			(layers "F.Cu" "F.Mask" "F.Paste")
			(net "GND")
		)
		(pad "2" smd rect
			(at 0 1.525 270)
			(size 1 1.05)
			(layers "F.Cu" "F.Mask" "F.Paste")
			(net "NetAN1_1")
		)
		(pad "3" smd rect
			(at 1.475 0 270)
			(size 1.05 2.2)
			(layers "F.Cu" "F.Mask" "F.Paste")
			(net "GND")
		)
	)
	(footprint "Vault:RESC1005X40X25LL05T05"
		(layer "F.Cu")
		(at 118.58072 83.9662)
		(property "Reference" "R71"
			(at -0.030515 -0.923069 0)
			(unlocked yes)
			(layer "F.SilkS")
			(effects
				(font
					(size 0.762 0.762)
					(thickness 0.2286)
				)
			)
		)
		(property "Value" "DNI_0_1%_0402"
			(at -2.884671 8.54431 270)
			(unlocked yes)
			(layer "F.SilkS")
			(hide yes)
			(effects
				(font
					(size 0.762 0.762)
					(thickness 0.2286)
				)
			)
		)
		(sheetname "05-GPS_IMU_SENSORS")
		(sheetfile "05-GPS_IMU_SENSORS.kicad_sch")
		(duplicate_pad_numbers_are_jumpers no)
		(pad "1" smd rect
			(at -0.4 0 90)
			(size 0.45 0.45)
			(layers "F.Cu" "F.Mask" "F.Paste")
			(net "BNO_XIN32")
		)
		(pad "2" smd rect
			(at 0.40001 0 90)
			(size 0.45 0.45)
			(layers "F.Cu" "F.Mask" "F.Paste")
			(net "FPGA_BNO_XIN32")
		)
	)
	(footprint "Vault:SMTC-TSM-105-01-X-DV"
		(layer "F.Cu")
		(at 227.6466 139.7762 90)
		(property "Reference" "P4"
			(at 6.633079 -3.321795 0)
			(unlocked yes)
			(layer "F.SilkS")
			(effects
				(font
					(size 0.762 0.762)
					(thickness 0.2032)
				)
			)
		)
		(property "Value" "TSM-105-01-L-DV"
			(at -8.777471 6.917965 0)
			(unlocked yes)
			(layer "F.SilkS")
			(hide yes)
			(effects
				(font
					(size 0.762 0.762)
					(thickness 0.2032)
				)
			)
		)
		(sheetname "04-PCIe_JTAG")
		(sheetfile "04-PCIe_JTAG.kicad_sch")
		(duplicate_pad_numbers_are_jumpers no)
		(fp_line
			(start 6.35 -2.54)
			(end 6.35 2.54)
			(stroke
				(width 0.2)
				(type solid)
			)
			(layer "F.SilkS")
		)
		(fp_line
			(start 6.115 -2.54)
			(end 6.35 -2.54)
			(stroke
				(width 0.2)
				(type solid)
			)
			(layer "F.SilkS")
		)
		(fp_line
			(start -6.35 -2.54)
			(end -6.115 -2.54)
			(stroke
				(width 0.2)
				(type solid)
			)
			(layer "F.SilkS")
		)
		(fp_line
			(start -6.35 -2.54)
			(end -6.35 2.54)
			(stroke
				(width 0.2)
				(type solid)
			)
			(layer "F.SilkS")
		)
		(fp_line
			(start 6.115 2.54)
			(end 6.35 2.54)
			(stroke
				(width 0.2)
				(type solid)
			)
			(layer "F.SilkS")
		)
		(fp_line
			(start -6.35 2.54)
			(end -6.115 2.54)
			(stroke
				(width 0.2)
				(type solid)
			)
			(layer "F.SilkS")
		)
		(fp_circle
			(center -6.985 2.54)
			(end -6.86 2.54)
			(stroke
				(width 0.25)
				(type solid)
			)
			(fill no)
			(layer "F.SilkS")
		)
		(pad "1" smd rect
			(at -5.08 2.475 90)
			(size 1.27 3.68)
			(layers "F.Cu" "F.Mask" "F.Paste")
			(net "NetP4_1")
		)
		(pad "2" smd rect
			(at -5.08 -2.475 90)
			(size 1.27 3.68)
			(layers "F.Cu" "F.Mask" "F.Paste")
			(net "GND")
		)
		(pad "3" smd rect
			(at -2.54 2.475 90)
			(size 1.27 3.68)
			(layers "F.Cu" "F.Mask" "F.Paste")
			(net "NetP4_3")
		)
		(pad "4" smd rect
			(at -2.54 -2.475 90)
			(size 1.27 3.68)
			(layers "F.Cu" "F.Mask" "F.Paste")
			(net "+3.3V")
		)
		(pad "5" smd rect
			(at 0 2.475 90)
			(size 1.27 3.68)
			(layers "F.Cu" "F.Mask" "F.Paste")
			(net "NetP4_5")
		)
		(pad "6" smd rect
			(at 0 -2.475 90)
			(size 1.27 3.68)
			(layers "F.Cu" "F.Mask" "F.Paste")
			(net "+3.3V")
		)
		(pad "7" smd rect
			(at 2.54 2.475 90)
			(size 1.27 3.68)
			(layers "F.Cu" "F.Mask" "F.Paste")
		)
		(pad "8" smd rect
			(at 2.54 -2.475 90)
			(size 1.27 3.68)
			(layers "F.Cu" "F.Mask" "F.Paste")
		)
		(pad "9" smd rect
			(at 5.08 2.475 90)
			(size 1.27 3.68)
			(layers "F.Cu" "F.Mask" "F.Paste")
			(net "NetP4_9")
		)
		(pad "10" smd rect
			(at 5.08 -2.475 90)
			(size 1.27 3.68)
			(layers "F.Cu" "F.Mask" "F.Paste")
			(net "GND")
		)
	)
	(footprint "Vault:RESC1005X40X25NL05T05"
		(layer "F.Cu")
		(at 189.3216 133.9162 -90)
		(property "Reference" "R156"
			(at 2.65329 0.357071 270)
			(unlocked yes)
			(layer "F.SilkS")
			(effects
				(font
					(size 0.762 0.762)
					(thickness 0.2032)
				)
			)
		)
		(property "Value" "DNI_27_1%_0402"
			(at -2.732271 10.270975 180)
			(unlocked yes)
			(layer "F.SilkS")
			(hide yes)
			(effects
				(font
					(size 0.762 0.762)
					(thickness 0.2032)
				)
			)
		)
		(sheetname "11-M2_RCB_MUX")
		(sheetfile "11-M2_RCB_MUX.kicad_sch")
		(duplicate_pad_numbers_are_jumpers no)
		(pad "1" smd rect
			(at -0.45 0)
			(size 0.55 0.55)
			(layers "F.Cu" "F.Mask" "F.Paste")
			(net "M2_GPS2_RX")
		)
		(pad "2" smd rect
			(at 0.45 0)
			(size 0.55 0.55)
			(layers "F.Cu" "F.Mask" "F.Paste")
			(net "GPS2_RX")
		)
	)
	(footprint "Vault:RESC1005X40X25NL05T05"
		(layer "F.Cu")
		(at 106.6216 56.7162 180)
		(property "Reference" "R163"
			(at 2.36762 0.329369 0)
			(unlocked yes)
			(layer "F.SilkS")
			(effects
				(font
					(size 0.762 0.762)
					(thickness 0.2032)
				)
			)
		)
		(property "Value" "DNI_27_1%_0402"
			(at -2.732271 10.270975 90)
			(unlocked yes)
			(layer "F.SilkS")
			(hide yes)
			(effects
				(font
					(size 0.762 0.762)
					(thickness 0.2032)
				)
			)
		)
		(sheetname "11-M2_RCB_MUX")
		(sheetfile "11-M2_RCB_MUX.kicad_sch")
		(duplicate_pad_numbers_are_jumpers no)
		(pad "1" smd rect
			(at -0.45 0 270)
			(size 0.55 0.55)
			(layers "F.Cu" "F.Mask" "F.Paste")
			(net "M2_GPS1_RX")
		)
		(pad "2" smd rect
			(at 0.45 0 270)
			(size 0.55 0.55)
			(layers "F.Cu" "F.Mask" "F.Paste")
			(net "GPS1_RX")
		)
	)
	(footprint "SamacSys:SOP50P310X90-8N"
		(layer "F.Cu")
		(at 76.1216 141.9162 180)
		(property "Reference" "U16"
			(at -0.2286 1.973079 0)
			(unlocked yes)
			(layer "F.SilkS")
			(effects
				(font
					(size 0.762 0.762)
					(thickness 0.2286)
				)
			)
		)
		(property "Value" "NC7WV125K8X"
			(at 6.207715 2.884671 180)
			(unlocked yes)
			(layer "F.SilkS")
			(hide yes)
			(effects
				(font
					(size 0.762 0.762)
					(thickness 0.2286)
				)
			)
		)
		(sheetname "01-USER_IO")
		(sheetfile "01-USER_IO.kicad_sch")
		(duplicate_pad_numbers_are_jumpers no)
		(fp_line
			(start 0.8 1)
			(end -0.8 1)
			(stroke
				(width 0.2)
				(type solid)
			)
			(layer "F.SilkS")
		)
		(fp_line
			(start 0.8 -1)
			(end 0.8 1)
			(stroke
				(width 0.2)
				(type solid)
			)
			(layer "F.SilkS")
		)
		(fp_line
			(start 0.8 -1)
			(end -0.8 -1)
			(stroke
				(width 0.2)
				(type solid)
			)
			(layer "F.SilkS")
		)
		(fp_line
			(start -0.8 -1)
			(end -0.8 1)
			(stroke
				(width 0.2)
				(type solid)
			)
			(layer "F.SilkS")
		)
		(fp_line
			(start -1.15 -1.25)
			(end -2 -1.25)
			(stroke
				(width 0.2)
				(type solid)
			)
			(layer "F.SilkS")
		)
		(pad "1" smd rect
			(at -1.575 -0.75 180)
			(size 0.85 0.3)
			(layers "F.Cu" "F.Mask" "F.Paste")
			(net "ANT4_IO_OUT")
		)
		(pad "2" smd rect
			(at -1.575 -0.25 180)
			(size 0.85 0.3)
			(layers "F.Cu" "F.Mask" "F.Paste")
			(net "ANT4_OUT")
		)
		(pad "3" smd rect
			(at -1.575 0.25 180)
			(size 0.85 0.3)
			(layers "F.Cu" "F.Mask" "F.Paste")
			(net "ANT4_IN")
		)
		(pad "4" smd rect
			(at -1.575 0.75 180)
			(size 0.85 0.3)
			(layers "F.Cu" "F.Mask" "F.Paste")
			(net "GND")
		)
		(pad "5" smd rect
			(at 1.575 0.75 180)
			(size 0.85 0.3)
			(layers "F.Cu" "F.Mask" "F.Paste")
			(net "NetR34_1")
		)
		(pad "6" smd rect
			(at 1.575 0.25 180)
			(size 0.85 0.3)
			(layers "F.Cu" "F.Mask" "F.Paste")
			(net "NetR34_1")
		)
		(pad "7" smd rect
			(at 1.575 -0.25 180)
			(size 0.85 0.3)
			(layers "F.Cu" "F.Mask" "F.Paste")
			(net "ANT4_IO_IN")
		)
		(pad "8" smd rect
			(at 1.575 -0.75 180)
			(size 0.85 0.3)
			(layers "F.Cu" "F.Mask" "F.Paste")
			(net "+3.3V")
		)
	)
	(footprint "Vault:RESC1005X40X25LL05T05"
		(layer "F.Cu")
		(at 84.65686 84.46371 180)
		(property "Reference" "R110"
			(at 2.97139 -0.426921 0)
			(unlocked yes)
			(layer "F.SilkS")
			(effects
				(font
					(size 0.762 0.762)
					(thickness 0.2286)
				)
			)
		)
		(property "Value" "DNI_4.7K_0402"
			(at -2.389361 9.43306 90)
			(unlocked yes)
			(layer "F.SilkS")
			(hide yes)
			(effects
				(font
					(size 0.762 0.762)
					(thickness 0.2032)
				)
			)
		)
		(sheetname "02-USER_IO_STATUS")
		(sheetfile "02-USER_IO_STATUS.kicad_sch")
		(duplicate_pad_numbers_are_jumpers no)
		(pad "1" smd rect
			(at -0.4 0 270)
			(size 0.45 0.45)
			(layers "F.Cu" "F.Mask" "F.Paste")
			(net "NetR108_2")
		)
		(pad "2" smd rect
			(at 0.4 0 270)
			(size 0.45 0.45)
			(layers "F.Cu" "F.Mask" "F.Paste")
			(net "GND")
		)
	)
	(footprint "Vault:RESC1005X40X25LL05T10"
		(layer "F.Cu")
		(at 122.9216 77.4162 180)
		(property "Reference" "R173"
			(at -2.4032 0.073079 0)
			(unlocked yes)
			(layer "F.SilkS")
			(effects
				(font
					(size 0.762 0.762)
					(thickness 0.2032)
				)
			)
		)
		(property "Value" "DNI_49.9_1%_0402"
			(at -2.579871 11.71832 90)
			(unlocked yes)
			(layer "F.SilkS")
			(hide yes)
			(effects
				(font
					(size 0.762 0.762)
					(thickness 0.2032)
				)
			)
		)
		(sheetname "11-M2_RCB_MUX")
		(sheetfile "11-M2_RCB_MUX.kicad_sch")
		(duplicate_pad_numbers_are_jumpers no)
		(pad "1" smd rect
			(at -0.375 0 270)
			(size 0.45 0.5)
			(layers "F.Cu" "F.Mask" "F.Paste")
			(net "GPS1_PIN12")
		)
		(pad "2" smd rect
			(at 0.375 0 270)
			(size 0.45 0.5)
			(layers "F.Cu" "F.Mask" "F.Paste")
			(net "RCB_GPS1_PIN12")
		)
	)
	(footprint "IS32FL3207:IS32FL3207"
		(layer "F.Cu")
		(at 93.70686 86.56371)
		(property "Reference" "U6"
			(at -2.271395 -3.723079 0)
			(unlocked yes)
			(layer "F.SilkS")
			(effects
				(font
					(size 0.762 0.762)
					(thickness 0.2286)
				)
			)
		)
		(property "Value" "IS32FL3207"
			(at 4.17596 4.662671 0)
			(unlocked yes)
			(layer "F.SilkS")
			(hide yes)
			(effects
				(font
					(size 0.762 0.762)
					(thickness 0.2286)
				)
			)
		)
		(sheetname "02-USER_IO_STATUS")
		(sheetfile "02-USER_IO_STATUS.kicad_sch")
		(duplicate_pad_numbers_are_jumpers no)
		(fp_line
			(start -2.65 -2.65)
			(end -2.04999 -2.65)
			(stroke
				(width 0.2)
				(type solid)
			)
			(layer "F.SilkS")
		)
		(fp_line
			(start -2.65 -2.05)
			(end -2.65 -2.65)
			(stroke
				(width 0.2)
				(type solid)
			)
			(layer "F.SilkS")
		)
		(fp_line
			(start -2.65 2.65)
			(end -2.65 2.05)
			(stroke
				(width 0.2)
				(type solid)
			)
			(layer "F.SilkS")
		)
		(fp_line
			(start -2.65 2.65)
			(end -2.04999 2.65)
			(stroke
				(width 0.2)
				(type solid)
			)
			(layer "F.SilkS")
		)
		(fp_line
			(start 2.05001 -2.65)
			(end 2.65 -2.65)
			(stroke
				(width 0.2)
				(type solid)
			)
			(layer "F.SilkS")
		)
		(fp_line
			(start 2.05001 2.65)
			(end 2.65 2.65)
			(stroke
				(width 0.2)
				(type solid)
			)
			(layer "F.SilkS")
		)
		(fp_line
			(start 2.65 -2.05)
			(end 2.65 -2.65)
			(stroke
				(width 0.2)
				(type solid)
			)
			(layer "F.SilkS")
		)
		(fp_line
			(start 2.65 2.65)
			(end 2.65 2.05)
			(stroke
				(width 0.2)
				(type solid)
			)
			(layer "F.SilkS")
		)
		(fp_circle
			(center -3.29999 -2.5)
			(end -3.29999 -2.625)
			(stroke
				(width 0.25)
				(type solid)
			)
			(fill no)
			(layer "F.SilkS")
		)
		(pad "1" smd rect
			(at -2.32499 -1.5 90)
			(size 0.26 0.9)
			(layers "F.Cu" "F.Mask" "F.Paste")
			(net "NetR40_2")
		)
		(pad "2" smd rect
			(at -2.32499 -1 90)
			(size 0.26 0.9)
			(layers "F.Cu" "F.Mask" "F.Paste")
			(net "NetR108_2")
		)
		(pad "3" smd rect
			(at -2.32499 -0.5 90)
			(size 0.26 0.9)
			(layers "F.Cu" "F.Mask" "F.Paste")
			(net "+3.3V")
		)
		(pad "4" smd rect
			(at -2.32499 0 90)
			(size 0.26 0.9)
			(layers "F.Cu" "F.Mask" "F.Paste")
			(net "GND")
		)
		(pad "5" smd rect
			(at -2.32499 0.5 90)
			(size 0.26 0.9)
			(layers "F.Cu" "F.Mask" "F.Paste")
			(net "NetR41_2")
		)
		(pad "6" smd rect
			(at -2.32499 1 90)
			(size 0.26 0.9)
			(layers "F.Cu" "F.Mask" "F.Paste")
			(net "SENS_I2C_SDA")
		)
		(pad "7" smd rect
			(at -2.32499 1.5 90)
			(size 0.26 0.9)
			(layers "F.Cu" "F.Mask" "F.Paste")
			(net "SENS_I2C_SCL")
		)
		(pad "8" smd rect
			(at -1.5 2.32499)
			(size 0.26 0.9)
			(layers "F.Cu" "F.Mask" "F.Paste")
			(net "NetD13_4")
		)
		(pad "9" smd rect
			(at -1 2.32499)
			(size 0.26 0.9)
			(layers "F.Cu" "F.Mask" "F.Paste")
			(net "NetD13_3")
		)
		(pad "10" smd rect
			(at -0.5 2.32499)
			(size 0.26 0.9)
			(layers "F.Cu" "F.Mask" "F.Paste")
			(net "NetD13_2")
		)
		(pad "11" smd rect
			(at 0 2.32499)
			(size 0.26 0.9)
			(layers "F.Cu" "F.Mask" "F.Paste")
			(net "GND")
		)
		(pad "12" smd rect
			(at 0.5 2.32499)
			(size 0.26 0.9)
			(layers "F.Cu" "F.Mask" "F.Paste")
			(net "NetD14_4")
		)
		(pad "13" smd rect
			(at 1 2.32499)
			(size 0.26 0.9)
			(layers "F.Cu" "F.Mask" "F.Paste")
			(net "NetD14_3")
		)
		(pad "14" smd rect
			(at 1.5 2.32499)
			(size 0.26 0.9)
			(layers "F.Cu" "F.Mask" "F.Paste")
			(net "NetD14_2")
		)
		(pad "15" smd rect
			(at 2.32501 1.5 90)
			(size 0.26 0.9)
			(layers "F.Cu" "F.Mask" "F.Paste")
			(net "NetD15_4")
		)
		(pad "16" smd rect
			(at 2.32501 1 90)
			(size 0.26 0.9)
			(layers "F.Cu" "F.Mask" "F.Paste")
			(net "NetD15_3")
		)
		(pad "17" smd rect
			(at 2.32501 0.5 90)
			(size 0.26 0.9)
			(layers "F.Cu" "F.Mask" "F.Paste")
			(net "NetD15_2")
		)
		(pad "18" smd rect
			(at 2.32501 0 90)
			(size 0.26 0.9)
			(layers "F.Cu" "F.Mask" "F.Paste")
			(net "GND")
		)
		(pad "19" smd rect
			(at 2.32501 -0.5 90)
			(size 0.26 0.9)
			(layers "F.Cu" "F.Mask" "F.Paste")
			(net "NetD16_4")
		)
		(pad "20" smd rect
			(at 2.32501 -1 90)
			(size 0.26 0.9)
			(layers "F.Cu" "F.Mask" "F.Paste")
			(net "NetD16_3")
		)
		(pad "21" smd rect
			(at 2.32501 -1.5 90)
			(size 0.26 0.9)
			(layers "F.Cu" "F.Mask" "F.Paste")
			(net "NetD16_2")
		)
		(pad "22" smd rect
			(at 1.50001 -2.325)
			(size 0.26 0.9)
			(layers "F.Cu" "F.Mask" "F.Paste")
			(net "NetD17_4")
		)
		(pad "23" smd rect
			(at 1.00001 -2.325)
			(size 0.26 0.9)
			(layers "F.Cu" "F.Mask" "F.Paste")
			(net "NetD17_3")
		)
		(pad "24" smd rect
			(at 0.50001 -2.325)
			(size 0.26 0.9)
			(layers "F.Cu" "F.Mask" "F.Paste")
			(net "NetD17_2")
		)
		(pad "25" smd rect
			(at 0 -2.325)
			(size 0.26 0.9)
			(layers "F.Cu" "F.Mask" "F.Paste")
			(net "GND")
		)
		(pad "26" smd rect
			(at -0.49999 -2.325)
			(size 0.26 0.9)
			(layers "F.Cu" "F.Mask" "F.Paste")
			(net "NetD18_4")
		)
		(pad "27" smd rect
			(at -0.99999 -2.325)
			(size 0.26 0.9)
			(layers "F.Cu" "F.Mask" "F.Paste")
			(net "NetD18_3")
		)
		(pad "28" smd rect
			(at -1.49999 -2.325)
			(size 0.26 0.9)
			(layers "F.Cu" "F.Mask" "F.Paste")
			(net "NetD18_2")
		)
		(pad "29" smd rect
			(at 0 0)
			(size 3.25 3.25)
			(layers "F.Cu" "F.Mask" "F.Paste")
			(net "GND")
		)
	)
	(footprint "SamacSys:155124M173200"
		(layer "F.Cu")
		(at 67.4466 128.4162 90)
		(property "Reference" "D17"
			(at -0.3286 1.448069 270)
			(unlocked yes)
			(layer "F.SilkS")
			(effects
				(font
					(size 0.762 0.762)
					(thickness 0.2286)
				)
			)
		)
		(property "Value" "155124M173200"
			(at 7.1471 2.605271 90)
			(unlocked yes)
			(layer "F.SilkS")
			(hide yes)
			(effects
				(font
					(size 0.762 0.762)
					(thickness 0.2286)
				)
			)
		)
		(sheetname "02-USER_IO_STATUS")
		(sheetfile "02-USER_IO_STATUS.kicad_sch")
		(duplicate_pad_numbers_are_jumpers no)
		(fp_line
			(start -0.8 0.5)
			(end 0.8 0.5)
			(stroke
				(width 0.1)
				(type solid)
			)
			(layer "F.SilkS")
		)
		(fp_arc
			(start -2 -0.1)
			(mid -1.95 -0.05)
			(end -2 0)
			(stroke
				(width 0.381)
				(type solid)
			)
			(layer "F.SilkS")
		)
		(fp_arc
			(start -2 0)
			(mid -2.05 -0.05)
			(end -2 -0.1)
			(stroke
				(width 0.381)
				(type solid)
			)
			(layer "F.SilkS")
		)
		(pad "1" smd rect
			(at -1.4 0 180)
			(size 0.9 0.6)
			(layers "F.Cu" "F.Mask" "F.Paste")
			(net "+3.3V")
		)
		(pad "2" smd rect
			(at -0.45 -0.325 90)
			(size 0.6 0.55)
			(layers "F.Cu" "F.Mask" "F.Paste")
			(net "NetD17_2")
		)
		(pad "3" smd rect
			(at 0.45 -0.325 90)
			(size 0.6 0.55)
			(layers "F.Cu" "F.Mask" "F.Paste")
			(net "NetD17_3")
		)
		(pad "4" smd rect
			(at 1.4 0 180)
			(size 0.9 0.6)
			(layers "F.Cu" "F.Mask" "F.Paste")
			(net "NetD17_4")
		)
	)
	(footprint "SA53:SA53_Header"
		(locked yes)
		(layer "F.Cu")
		(at 130.25657 114.79691 180)
		(property "Reference" "J31"
			(at 3.046085 -8.854759 180)
			(unlocked yes)
			(layer "F.SilkS")
			(effects
				(font
					(size 0.762 0.762)
					(thickness 0.2286)
				)
			)
		)
		(property "Value" "SA53_Header"
			(at 7.655515 4.548351 180)
			(unlocked yes)
			(layer "F.SilkS")
			(hide yes)
			(effects
				(font
					(size 0.762 0.762)
					(thickness 0.2286)
				)
			)
		)
		(sheetname "06-MAC")
		(sheetfile "06-MAC.kicad_sch")
		(duplicate_pad_numbers_are_jumpers no)
		(fp_circle
			(center 6.42 0.072)
			(end 6.42 0.199)
			(stroke
				(width 0.254)
				(type solid)
			)
			(fill no)
			(layer "F.SilkS")
		)
		(pad "1" smd rect
			(at 5 0.072 270)
			(size 0.25 1.8)
			(layers "F.Cu" "F.Mask" "F.Paste")
			(net "MAC_PPS_IN1+")
		)
		(pad "2" smd rect
			(at 1 0.072 270)
			(size 0.25 1.8)
			(layers "F.Cu" "F.Mask" "F.Paste")
			(net "MAC_USB+")
		)
		(pad "3" smd rect
			(at 5 -0.436 270)
			(size 0.25 1.8)
			(layers "F.Cu" "F.Mask" "F.Paste")
			(net "MAC_PPS_IN1-")
		)
		(pad "4" smd rect
			(at 1 -0.436 270)
			(size 0.25 1.8)
			(layers "F.Cu" "F.Mask" "F.Paste")
			(net "MAC_USB-")
		)
		(pad "5" smd rect
			(at 5 -0.944 270)
			(size 0.25 1.8)
			(layers "F.Cu" "F.Mask" "F.Paste")
			(net "MAC_PPS_IN0+")
		)
		(pad "6" smd rect
			(at 1 -0.944 270)
			(size 0.25 1.8)
			(layers "F.Cu" "F.Mask" "F.Paste")
			(net "MAC_USB_PWR")
		)
		(pad "7" smd rect
			(at 5 -1.452 270)
			(size 0.25 1.8)
			(layers "F.Cu" "F.Mask" "F.Paste")
			(net "MAC_PPS_IN0-")
		)
		(pad "8" smd rect
			(at 1 -1.452 270)
			(size 0.25 1.8)
			(layers "F.Cu" "F.Mask" "F.Paste")
			(net "GND")
		)
		(pad "9" smd rect
			(at 5 -1.96 270)
			(size 0.25 1.8)
			(layers "F.Cu" "F.Mask" "F.Paste")
			(net "GND")
		)
		(pad "10" smd rect
			(at 1 -1.96 270)
			(size 0.25 1.8)
			(layers "F.Cu" "F.Mask" "F.Paste")
		)
		(pad "11" smd rect
			(at 5 -2.468 270)
			(size 0.25 1.8)
			(layers "F.Cu" "F.Mask" "F.Paste")
		)
		(pad "12" smd rect
			(at 1 -2.468 270)
			(size 0.25 1.8)
			(layers "F.Cu" "F.Mask" "F.Paste")
		)
		(pad "13" smd rect
			(at 5 -2.976 270)
			(size 0.25 1.8)
			(layers "F.Cu" "F.Mask" "F.Paste")
		)
		(pad "14" smd rect
			(at 1 -2.976 270)
			(size 0.25 1.8)
			(layers "F.Cu" "F.Mask" "F.Paste")
		)
		(pad "15" smd rect
			(at 5 -3.484 270)
			(size 0.25 1.8)
			(layers "F.Cu" "F.Mask" "F.Paste")
			(net "GND")
		)
		(pad "16" smd rect
			(at 1 -3.484 270)
			(size 0.25 1.8)
			(layers "F.Cu" "F.Mask" "F.Paste")
		)
		(pad "17" smd rect
			(at 5 -3.992 270)
			(size 0.25 1.8)
			(layers "F.Cu" "F.Mask" "F.Paste")
			(net "MAC_PPS_OUT+")
		)
		(pad "18" smd rect
			(at 1 -3.992 270)
			(size 0.25 1.8)
			(layers "F.Cu" "F.Mask" "F.Paste")
		)
		(pad "19" smd rect
			(at 5 -4.5 270)
			(size 0.25 1.8)
			(layers "F.Cu" "F.Mask" "F.Paste")
			(net "MAC_PPS_OUT-")
		)
		(pad "20" smd rect
			(at 1 -4.5 270)
			(size 0.25 1.8)
			(layers "F.Cu" "F.Mask" "F.Paste")
			(net "MAC_ALARM")
		)
		(zone
			(layer "F.Cu")
			(hatch edge 0.5)
			(connect_pads
				(clearance 0)
			)
			(min_thickness 0.25)
			(keepout
				(tracks allowed)
				(vias allowed)
				(pads allowed)
				(copperpour not_allowed)
				(footprints allowed)
			)
			(placement
				(enabled no)
				(sheetname "")
			)
			(fill
				(thermal_gap 0.5)
				(thermal_bridge_width 0.5)
				(island_removal_mode 0)
			)
			(polygon
				(pts
					(xy 123.58908 121.8662) (xy 123.58909 111.8662) (xy 131.08909 111.8662) (xy 131.08908 121.8662)
				)
			)
		)
	)
	(footprint "FPGA_CONN:SingleFPGAConn"
		(locked yes)
		(layer "F.Cu")
		(at 171.29647 138.90823 90)
		(property "Reference" "J37"
			(at -0.39436 -23.455119 90)
			(unlocked yes)
			(layer "F.SilkS")
			(effects
				(font
					(size 0.762 0.762)
					(thickness 0.2286)
				)
			)
		)
		(property "Value" "Single FPGA Conn"
			(at 9.25452 3.621231 90)
			(unlocked yes)
			(layer "F.SilkS")
			(hide yes)
			(effects
				(font
					(size 0.762 0.762)
					(thickness 0.2286)
				)
			)
		)
		(sheetname "07-FPGA")
		(sheetfile "07-FPGA.kicad_sch")
		(duplicate_pad_numbers_are_jumpers no)
		(fp_line
			(start 1.40005 -21.24989)
			(end 2 -20.69998)
			(stroke
				(width 0.15011)
				(type solid)
			)
			(layer "F.SilkS")
		)
		(fp_line
			(start -1.40005 -21.24989)
			(end 1.40005 -21.24989)
			(stroke
				(width 0.15011)
				(type solid)
			)
			(layer "F.SilkS")
		)
		(fp_line
			(start -1.40005 -21.24989)
			(end -1.40005 -20.69998)
			(stroke
				(width 0.15011)
				(type solid)
			)
			(layer "F.SilkS")
		)
		(fp_line
			(start 2 -20.69998)
			(end 2 -20.03298)
			(stroke
				(width 0.15011)
				(type solid)
			)
			(layer "F.SilkS")
		)
		(fp_line
			(start -2 -20.69998)
			(end -1.40005 -20.69998)
			(stroke
				(width 0.15011)
				(type solid)
			)
			(layer "F.SilkS")
		)
		(fp_line
			(start -2 -20.69998)
			(end -2 -20.03298)
			(stroke
				(width 0.15011)
				(type solid)
			)
			(layer "F.SilkS")
		)
		(fp_line
			(start 2 0.03302)
			(end 2 0.70003)
			(stroke
				(width 0.15011)
				(type solid)
			)
			(layer "F.SilkS")
		)
		(fp_line
			(start -2 0.03302)
			(end -2 0.70003)
			(stroke
				(width 0.15011)
				(type solid)
			)
			(layer "F.SilkS")
		)
		(fp_line
			(start 2 0.70003)
			(end 1.40005 1.24994)
			(stroke
				(width 0.15011)
				(type solid)
			)
			(layer "F.SilkS")
		)
		(fp_line
			(start -1.40005 0.70003)
			(end -1.40005 1.24994)
			(stroke
				(width 0.15011)
				(type solid)
			)
			(layer "F.SilkS")
		)
		(fp_line
			(start -2 0.70003)
			(end -1.40005 0.70003)
			(stroke
				(width 0.15011)
				(type solid)
			)
			(layer "F.SilkS")
		)
		(fp_line
			(start -1.40005 1.24994)
			(end 1.40005 1.24994)
			(stroke
				(width 0.15011)
				(type solid)
			)
			(layer "F.SilkS")
		)
		(fp_circle
			(center 3.5052 -0.22453)
			(end 3.70535 -0.22453)
			(stroke
				(width 0.40005)
				(type solid)
			)
			(fill no)
			(layer "F.SilkS")
		)
		(pad "1" smd rect
			(at 2.02489 -0.24993 90)
			(size 1.54991 0.24994)
			(layers "F.Cu" "F.Mask" "F.Paste")
		)
		(pad "2" smd rect
			(at -2.02489 -0.24993 90)
			(size 1.54991 0.24994)
			(layers "F.Cu" "F.Mask" "F.Paste")
		)
		(pad "3" smd rect
			(at 2.02489 -0.75006 90)
			(size 1.54991 0.24994)
			(layers "F.Cu" "F.Mask" "F.Paste")
		)
		(pad "4" smd rect
			(at -2.02489 -0.75006 90)
			(size 1.54991 0.24994)
			(layers "F.Cu" "F.Mask" "F.Paste")
		)
		(pad "5" smd rect
			(at 2.02489 -1.24993 90)
			(size 1.54991 0.24994)
			(layers "F.Cu" "F.Mask" "F.Paste")
		)
		(pad "6" smd rect
			(at -2.02489 -1.24993 90)
			(size 1.54991 0.24994)
			(layers "F.Cu" "F.Mask" "F.Paste")
		)
		(pad "7" smd rect
			(at 2.02489 -1.75006 90)
			(size 1.54991 0.24994)
			(layers "F.Cu" "F.Mask" "F.Paste")
		)
		(pad "8" smd rect
			(at -2.02489 -1.75006 90)
			(size 1.54991 0.24994)
			(layers "F.Cu" "F.Mask" "F.Paste")
		)
		(pad "9" smd rect
			(at 2.02489 -2.24993 90)
			(size 1.54991 0.24994)
			(layers "F.Cu" "F.Mask" "F.Paste")
			(net "GND")
		)
		(pad "10" smd rect
			(at -2.02489 -2.24993 90)
			(size 1.54991 0.24994)
			(layers "F.Cu" "F.Mask" "F.Paste")
			(net "GND")
		)
		(pad "11" smd rect
			(at 2.02489 -2.75005 90)
			(size 1.54991 0.24994)
			(layers "F.Cu" "F.Mask" "F.Paste")
		)
		(pad "12" smd rect
			(at -2.02489 -2.75005 90)
			(size 1.54991 0.24994)
			(layers "F.Cu" "F.Mask" "F.Paste")
			(net "PCIE_TX2_P")
		)
		(pad "13" smd rect
			(at 2.02489 -3.24993 90)
			(size 1.54991 0.24994)
			(layers "F.Cu" "F.Mask" "F.Paste")
		)
		(pad "14" smd rect
			(at -2.02489 -3.24993 90)
			(size 1.54991 0.24994)
			(layers "F.Cu" "F.Mask" "F.Paste")
			(net "PCIE_TX2_N")
		)
		(pad "15" smd rect
			(at 2.02489 -3.75005 90)
			(size 1.54991 0.24994)
			(layers "F.Cu" "F.Mask" "F.Paste")
			(net "GND")
		)
		(pad "16" smd rect
			(at -2.02489 -3.75005 90)
			(size 1.54991 0.24994)
			(layers "F.Cu" "F.Mask" "F.Paste")
		)
		(pad "17" smd rect
			(at 2.02489 -4.24992 90)
			(size 1.54991 0.24994)
			(layers "F.Cu" "F.Mask" "F.Paste")
			(net "PCIE_TX3_P")
		)
		(pad "18" smd rect
			(at -2.02489 -4.24992 90)
			(size 1.54991 0.24994)
			(layers "F.Cu" "F.Mask" "F.Paste")
			(net "PCIE_RX2_P")
		)
		(pad "19" smd rect
			(at 2.02489 -4.75005 90)
			(size 1.54991 0.24994)
			(layers "F.Cu" "F.Mask" "F.Paste")
			(net "PCIE_TX3_N")
		)
		(pad "20" smd rect
			(at -2.02489 -4.75005 90)
			(size 1.54991 0.24994)
			(layers "F.Cu" "F.Mask" "F.Paste")
			(net "PCIE_RX2_N")
		)
		(pad "21" smd rect
			(at 2.02489 -5.24992 90)
			(size 1.54991 0.24994)
			(layers "F.Cu" "F.Mask" "F.Paste")
			(net "GND")
		)
		(pad "22" smd rect
			(at -2.02489 -5.24992 90)
			(size 1.54991 0.24994)
			(layers "F.Cu" "F.Mask" "F.Paste")
		)
		(pad "23" smd rect
			(at 2.02489 -5.75005 90)
			(size 1.54991 0.24994)
			(layers "F.Cu" "F.Mask" "F.Paste")
			(net "PCIE_RX3_P")
		)
		(pad "24" smd rect
			(at -2.02489 -5.75005 90)
			(size 1.54991 0.24994)
			(layers "F.Cu" "F.Mask" "F.Paste")
			(net "PCIE_TX1_P")
		)
		(pad "25" smd rect
			(at 2.02489 -6.24992 90)
			(size 1.54991 0.24994)
			(layers "F.Cu" "F.Mask" "F.Paste")
			(net "PCIE_RX3_N")
		)
		(pad "26" smd rect
			(at -2.02489 -6.24992 90)
			(size 1.54991 0.24994)
			(layers "F.Cu" "F.Mask" "F.Paste")
			(net "PCIE_TX1_N")
		)
		(pad "27" smd rect
			(at 2.02489 -6.75005 90)
			(size 1.54991 0.24994)
			(layers "F.Cu" "F.Mask" "F.Paste")
			(net "GND")
		)
		(pad "28" smd rect
			(at -2.02489 -6.75005 90)
			(size 1.54991 0.24994)
			(layers "F.Cu" "F.Mask" "F.Paste")
		)
		(pad "29" smd rect
			(at 2.02489 -7.24992 90)
			(size 1.54991 0.24994)
			(layers "F.Cu" "F.Mask" "F.Paste")
			(net "PCIE_TX0_P")
		)
		(pad "30" smd rect
			(at -2.02489 -7.24992 90)
			(size 1.54991 0.24994)
			(layers "F.Cu" "F.Mask" "F.Paste")
			(net "PCIE_RX1_P")
		)
		(pad "31" smd rect
			(at 2.02489 -7.75004 90)
			(size 1.54991 0.24994)
			(layers "F.Cu" "F.Mask" "F.Paste")
			(net "PCIE_TX0_N")
		)
		(pad "32" smd rect
			(at -2.02489 -7.75004 90)
			(size 1.54991 0.24994)
			(layers "F.Cu" "F.Mask" "F.Paste")
			(net "PCIE_RX1_N")
		)
		(pad "33" smd rect
			(at 2.02489 -8.24992 90)
			(size 1.54991 0.24994)
			(layers "F.Cu" "F.Mask" "F.Paste")
			(net "GND")
		)
		(pad "34" smd rect
			(at -2.02489 -8.24992 90)
			(size 1.54991 0.24994)
			(layers "F.Cu" "F.Mask" "F.Paste")
		)
		(pad "35" smd rect
			(at 2.02489 -8.75004 90)
			(size 1.54991 0.24994)
			(layers "F.Cu" "F.Mask" "F.Paste")
			(net "PCIE_RX0_P")
		)
		(pad "36" smd rect
			(at -2.02489 -8.75004 90)
			(size 1.54991 0.24994)
			(layers "F.Cu" "F.Mask" "F.Paste")
			(net "PCIE_CLK_P")
		)
		(pad "37" smd rect
			(at 2.02489 -9.24991 90)
			(size 1.54991 0.24994)
			(layers "F.Cu" "F.Mask" "F.Paste")
			(net "PCIE_RX0_N")
		)
		(pad "38" smd rect
			(at -2.02489 -9.24991 90)
			(size 1.54991 0.24994)
			(layers "F.Cu" "F.Mask" "F.Paste")
			(net "PCIE_CLK_N")
		)
		(pad "39" smd rect
			(at 2.02489 -9.75004 90)
			(size 1.54991 0.24994)
			(layers "F.Cu" "F.Mask" "F.Paste")
			(net "GND")
		)
		(pad "40" smd rect
			(at -2.02489 -9.75004 90)
			(size 1.54991 0.24994)
			(layers "F.Cu" "F.Mask" "F.Paste")
			(net "GND")
		)
		(pad "41" smd rect
			(at 2.02489 -10.24991 90)
			(size 1.54991 0.24994)
			(layers "F.Cu" "F.Mask" "F.Paste")
		)
		(pad "42" smd rect
			(at -2.02489 -10.24991 90)
			(size 1.54991 0.24994)
			(layers "F.Cu" "F.Mask" "F.Paste")
		)
		(pad "43" smd rect
			(at 2.02489 -10.75004 90)
			(size 1.54991 0.24994)
			(layers "F.Cu" "F.Mask" "F.Paste")
		)
		(pad "44" smd rect
			(at -2.02489 -10.75004 90)
			(size 1.54991 0.24994)
			(layers "F.Cu" "F.Mask" "F.Paste")
		)
		(pad "45" smd rect
			(at 2.02489 -11.24991 90)
			(size 1.54991 0.24994)
			(layers "F.Cu" "F.Mask" "F.Paste")
		)
		(pad "46" smd rect
			(at -2.02489 -11.24991 90)
			(size 1.54991 0.24994)
			(layers "F.Cu" "F.Mask" "F.Paste")
		)
		(pad "47" smd rect
			(at 2.02489 -11.75004 90)
			(size 1.54991 0.24994)
			(layers "F.Cu" "F.Mask" "F.Paste")
		)
		(pad "48" smd rect
			(at -2.02489 -11.75004 90)
			(size 1.54991 0.24994)
			(layers "F.Cu" "F.Mask" "F.Paste")
		)
		(pad "49" smd rect
			(at 2.02489 -12.24991 90)
			(size 1.54991 0.24994)
			(layers "F.Cu" "F.Mask" "F.Paste")
			(net "GND")
		)
		(pad "50" smd rect
			(at -2.02489 -12.24991 90)
			(size 1.54991 0.24994)
			(layers "F.Cu" "F.Mask" "F.Paste")
			(net "GND")
		)
		(pad "51" smd rect
			(at 2.02489 -12.75003 90)
			(size 1.54991 0.24994)
			(layers "F.Cu" "F.Mask" "F.Paste")
		)
		(pad "52" smd rect
			(at -2.02489 -12.75003 90)
			(size 1.54991 0.24994)
			(layers "F.Cu" "F.Mask" "F.Paste")
		)
		(pad "53" smd rect
			(at 2.02489 -13.24991 90)
			(size 1.54991 0.24994)
			(layers "F.Cu" "F.Mask" "F.Paste")
		)
		(pad "54" smd rect
			(at -2.02489 -13.24991 90)
			(size 1.54991 0.24994)
			(layers "F.Cu" "F.Mask" "F.Paste")
		)
		(pad "55" smd rect
			(at 2.02489 -13.75003 90)
			(size 1.54991 0.24994)
			(layers "F.Cu" "F.Mask" "F.Paste")
		)
		(pad "56" smd rect
			(at -2.02489 -13.75003 90)
			(size 1.54991 0.24994)
			(layers "F.Cu" "F.Mask" "F.Paste")
		)
		(pad "57" smd rect
			(at 2.02489 -14.2499 90)
			(size 1.54991 0.24994)
			(layers "F.Cu" "F.Mask" "F.Paste")
		)
		(pad "58" smd rect
			(at -2.02489 -14.2499 90)
			(size 1.54991 0.24994)
			(layers "F.Cu" "F.Mask" "F.Paste")
		)
		(pad "59" smd rect
			(at 2.02489 -14.75003 90)
			(size 1.54991 0.24994)
			(layers "F.Cu" "F.Mask" "F.Paste")
			(net "GND")
		)
		(pad "60" smd rect
			(at -2.02489 -14.75003 90)
			(size 1.54991 0.24994)
			(layers "F.Cu" "F.Mask" "F.Paste")
			(net "GND")
		)
		(pad "61" smd rect
			(at 2.02489 -15.2499 90)
			(size 1.54991 0.24994)
			(layers "F.Cu" "F.Mask" "F.Paste")
		)
		(pad "62" smd rect
			(at -2.02489 -15.2499 90)
			(size 1.54991 0.24994)
			(layers "F.Cu" "F.Mask" "F.Paste")
		)
		(pad "63" smd rect
			(at 2.02489 -15.75003 90)
			(size 1.54991 0.24994)
			(layers "F.Cu" "F.Mask" "F.Paste")
		)
		(pad "64" smd rect
			(at -2.02489 -15.75003 90)
			(size 1.54991 0.24994)
			(layers "F.Cu" "F.Mask" "F.Paste")
		)
		(pad "65" smd rect
			(at 2.02489 -16.2499 90)
			(size 1.54991 0.24994)
			(layers "F.Cu" "F.Mask" "F.Paste")
		)
		(pad "66" smd rect
			(at -2.02489 -16.2499 90)
			(size 1.54991 0.24994)
			(layers "F.Cu" "F.Mask" "F.Paste")
		)
		(pad "67" smd rect
			(at 2.02489 -16.75003 90)
			(size 1.54991 0.24994)
			(layers "F.Cu" "F.Mask" "F.Paste")
		)
		(pad "68" smd rect
			(at -2.02489 -16.75003 90)
			(size 1.54991 0.24994)
			(layers "F.Cu" "F.Mask" "F.Paste")
		)
		(pad "69" smd rect
			(at 2.02489 -17.2499 90)
			(size 1.54991 0.24994)
			(layers "F.Cu" "F.Mask" "F.Paste")
			(net "GND")
		)
		(pad "70" smd rect
			(at -2.02489 -17.2499 90)
			(size 1.54991 0.24994)
			(layers "F.Cu" "F.Mask" "F.Paste")
			(net "GND")
		)
		(pad "71" smd rect
			(at 2.02489 -17.75002 90)
			(size 1.54991 0.24994)
			(layers "F.Cu" "F.Mask" "F.Paste")
		)
		(pad "72" smd rect
			(at -2.02489 -17.75002 90)
			(size 1.54991 0.24994)
			(layers "F.Cu" "F.Mask" "F.Paste")
		)
		(pad "73" smd rect
			(at 2.02489 -18.2499 90)
			(size 1.54991 0.24994)
			(layers "F.Cu" "F.Mask" "F.Paste")
		)
		(pad "74" smd rect
			(at -2.02489 -18.2499 90)
			(size 1.54991 0.24994)
			(layers "F.Cu" "F.Mask" "F.Paste")
		)
		(pad "75" smd rect
			(at 2.02489 -18.75002 90)
			(size 1.54991 0.24994)
			(layers "F.Cu" "F.Mask" "F.Paste")
		)
		(pad "76" smd rect
			(at -2.02489 -18.75002 90)
			(size 1.54991 0.24994)
			(layers "F.Cu" "F.Mask" "F.Paste")
		)
		(pad "77" smd rect
			(at 2.02489 -19.24989 90)
			(size 1.54991 0.24994)
			(layers "F.Cu" "F.Mask" "F.Paste")
		)
		(pad "78" smd rect
			(at -2.02489 -19.24989 90)
			(size 1.54991 0.24994)
			(layers "F.Cu" "F.Mask" "F.Paste")
		)
		(pad "79" smd rect
			(at 2.02489 -19.75002 90)
			(size 1.54991 0.24994)
			(layers "F.Cu" "F.Mask" "F.Paste")
		)
		(pad "80" smd rect
			(at -2.02489 -19.75002 90)
			(size 1.54991 0.24994)
			(layers "F.Cu" "F.Mask" "F.Paste")
		)
		(pad "81" smd rect
			(at 0.01135 1.17626 90)
			(size 1.70002 1.35001)
			(layers "F.Cu" "F.Mask" "F.Paste")
		)
		(pad "82" thru_hole circle
			(at 0 0 90)
			(size 0.55016 0.55016)
			(drill 0.55016)
			(layers "*.Cu" "*.Mask")
			(remove_unused_layers no)
			(thermal_bridge_angle 90)
		)
		(pad "83" thru_hole circle
			(at 0 -19.99996 90)
			(size 0.55016 0.55016)
			(drill 0.55016)
			(layers "*.Cu" "*.Mask")
			(remove_unused_layers no)
			(thermal_bridge_angle 90)
		)
		(pad "84" smd rect
			(at 0.01135 -21.17374 90)
			(size 1.70002 1.35001)
			(layers "F.Cu" "F.Mask" "F.Paste")
		)
	)
	(footprint "Resistors:RESC1005X04N"
		(layer "F.Cu")
		(at 105.8216 143.5162)
		(property "Reference" "R23"
			(at -3.3 0.493345 0)
			(unlocked yes)
			(layer "F.SilkS")
			(effects
				(font
					(size 0.762 0.762)
					(thickness 0.2286)
				)
				(justify left bottom)
			)
		)
		(property "Value" "ERJ-2GE0R00X"
			(at -0.2413 3.331845 0)
			(unlocked yes)
			(layer "F.SilkS")
			(hide yes)
			(effects
				(font
					(size 0.762 0.762)
					(thickness 0.2286)
				)
				(justify left bottom)
			)
		)
		(sheetname "04-PCIe_JTAG")
		(sheetfile "04-PCIe_JTAG.kicad_sch")
		(duplicate_pad_numbers_are_jumpers no)
		(pad "1" smd rect
			(at -0.425 0 90)
			(size 0.6 0.65)
			(layers "F.Cu" "F.Mask" "F.Paste")
			(net "PRSNT")
		)
		(pad "2" smd rect
			(at 0.425 0 90)
			(size 0.6 0.65)
			(layers "F.Cu" "F.Mask" "F.Paste")
			(net "NetP2_B17")
		)
	)
	(footprint "Vault:RESC1005X40X25NL05T05"
		(layer "F.Cu")
		(at 153.4216 127.1162)
		(property "Reference" "R102"
			(at -0.2714 -1.173069 0)
			(unlocked yes)
			(layer "F.SilkS")
			(effects
				(font
					(size 0.762 0.762)
					(thickness 0.2286)
				)
			)
		)
		(property "Value" "DNI_27_1%_0402"
			(at -2.732271 10.296375 270)
			(unlocked yes)
			(layer "F.SilkS")
			(hide yes)
			(effects
				(font
					(size 0.762 0.762)
					(thickness 0.2286)
				)
			)
		)
		(sheetname "09-USBUart_PPSMUX_UARTMUX")
		(sheetfile "09-USBUart_PPSMUX_UARTMUX.kicad_sch")
		(duplicate_pad_numbers_are_jumpers no)
		(pad "1" smd rect
			(at -0.45 0 90)
			(size 0.55 0.55)
			(layers "F.Cu" "F.Mask" "F.Paste")
			(net "GPS2_TX_FPGA")
		)
		(pad "2" smd rect
			(at 0.45 0 90)
			(size 0.55 0.55)
			(layers "F.Cu" "F.Mask" "F.Paste")
			(net "GPS2_TX")
		)
	)
	(footprint "Vault:FP-BNO055-MFG"
		(layer "F.Cu")
		(at 113.58072 87.2662)
		(property "Reference" "U13"
			(at -3.632189 1.8214 90)
			(unlocked yes)
			(layer "F.SilkS")
			(effects
				(font
					(size 0.762 0.762)
					(thickness 0.2286)
				)
			)
		)
		(property "Value" "BNO055"
			(at 1.94175 3.494271 0)
			(unlocked yes)
			(layer "F.SilkS")
			(hide yes)
			(effects
				(font
					(size 0.762 0.762)
					(thickness 0.2286)
				)
			)
		)
		(sheetname "05-GPS_IMU_SENSORS")
		(sheetfile "05-GPS_IMU_SENSORS.kicad_sch")
		(duplicate_pad_numbers_are_jumpers no)
		(fp_rect
			(start -1.82503 -2.04997)
			(end -1.30003 -2.44997)
			(stroke
				(width 0)
				(type default)
			)
			(fill yes)
			(layer "F.Mask")
		)
		(fp_rect
			(start -1.82503 -0.04997)
			(end -1.30003 -0.44997)
			(stroke
				(width 0)
				(type default)
			)
			(fill yes)
			(layer "F.Mask")
		)
		(fp_rect
			(start -1.82503 0.45003)
			(end -1.30003 0.05003)
			(stroke
				(width 0)
				(type default)
			)
			(fill yes)
			(layer "F.Mask")
		)
		(fp_rect
			(start -1.82503 2.45003)
			(end -1.30003 2.05003)
			(stroke
				(width 0)
				(type default)
			)
			(fill yes)
			(layer "F.Mask")
		)
		(fp_rect
			(start -1.825 -1.55)
			(end -1.3 -1.95)
			(stroke
				(width 0)
				(type default)
			)
			(fill yes)
			(layer "F.Mask")
		)
		(fp_rect
			(start -1.825 -0.55)
			(end -1.3 -0.95)
			(stroke
				(width 0)
				(type default)
			)
			(fill yes)
			(layer "F.Mask")
		)
		(fp_rect
			(start -1.825 0.95)
			(end -1.3 0.55)
			(stroke
				(width 0)
				(type default)
			)
			(fill yes)
			(layer "F.Mask")
		)
		(fp_rect
			(start -1.825 1.95)
			(end -1.3 1.55)
			(stroke
				(width 0)
				(type default)
			)
			(fill yes)
			(layer "F.Mask")
		)
		(fp_rect
			(start -1.82497 -1.05003)
			(end -1.29997 -1.45003)
			(stroke
				(width 0)
				(type default)
			)
			(fill yes)
			(layer "F.Mask")
		)
		(fp_rect
			(start -1.82497 1.44997)
			(end -1.29997 1.04997)
			(stroke
				(width 0)
				(type default)
			)
			(fill yes)
			(layer "F.Mask")
		)
		(fp_rect
			(start -0.9 -2.05)
			(end -0.59999 -2.575)
			(stroke
				(width 0)
				(type default)
			)
			(fill yes)
			(layer "F.Mask")
		)
		(fp_rect
			(start -0.9 2.575)
			(end -0.59999 2.05)
			(stroke
				(width 0)
				(type default)
			)
			(fill yes)
			(layer "F.Mask")
		)
		(fp_rect
			(start -0.40001 2.57498)
			(end -0.10001 2.04998)
			(stroke
				(width 0)
				(type default)
			)
			(fill yes)
			(layer "F.Mask")
		)
		(fp_rect
			(start -0.39998 -2.04998)
			(end -0.09998 -2.57498)
			(stroke
				(width 0)
				(type default)
			)
			(fill yes)
			(layer "F.Mask")
		)
		(fp_rect
			(start 0.09999 2.57498)
			(end 0.39999 2.04998)
			(stroke
				(width 0)
				(type default)
			)
			(fill yes)
			(layer "F.Mask")
		)
		(fp_rect
			(start 0.10002 -2.04998)
			(end 0.40002 -2.57498)
			(stroke
				(width 0)
				(type default)
			)
			(fill yes)
			(layer "F.Mask")
		)
		(fp_rect
			(start 0.6 -2.05)
			(end 0.9 -2.575)
			(stroke
				(width 0)
				(type default)
			)
			(fill yes)
			(layer "F.Mask")
		)
		(fp_rect
			(start 0.6 2.575)
			(end 0.9 2.05)
			(stroke
				(width 0)
				(type default)
			)
			(fill yes)
			(layer "F.Mask")
		)
		(fp_rect
			(start 1.29998 -1.04997)
			(end 1.82498 -1.44997)
			(stroke
				(width 0)
				(type default)
			)
			(fill yes)
			(layer "F.Mask")
		)
		(fp_rect
			(start 1.29998 1.45003)
			(end 1.82498 1.05003)
			(stroke
				(width 0)
				(type default)
			)
			(fill yes)
			(layer "F.Mask")
		)
		(fp_rect
			(start 1.3 -1.55)
			(end 1.825 -1.95)
			(stroke
				(width 0)
				(type default)
			)
			(fill yes)
			(layer "F.Mask")
		)
		(fp_rect
			(start 1.3 -0.55)
			(end 1.825 -0.95)
			(stroke
				(width 0)
				(type default)
			)
			(fill yes)
			(layer "F.Mask")
		)
		(fp_rect
			(start 1.3 0.95)
			(end 1.825 0.55)
			(stroke
				(width 0)
				(type default)
			)
			(fill yes)
			(layer "F.Mask")
		)
		(fp_rect
			(start 1.3 1.95)
			(end 1.825 1.55)
			(stroke
				(width 0)
				(type default)
			)
			(fill yes)
			(layer "F.Mask")
		)
		(fp_rect
			(start 1.30003 -2.05003)
			(end 1.82503 -2.45003)
			(stroke
				(width 0)
				(type default)
			)
			(fill yes)
			(layer "F.Mask")
		)
		(fp_rect
			(start 1.30003 -0.05003)
			(end 1.82503 -0.45003)
			(stroke
				(width 0)
				(type default)
			)
			(fill yes)
			(layer "F.Mask")
		)
		(fp_rect
			(start 1.30003 0.44997)
			(end 1.82503 0.04997)
			(stroke
				(width 0)
				(type default)
			)
			(fill yes)
			(layer "F.Mask")
		)
		(fp_rect
			(start 1.30003 2.44997)
			(end 1.82503 2.04997)
			(stroke
				(width 0)
				(type default)
			)
			(fill yes)
			(layer "F.Mask")
		)
		(fp_line
			(start -2.25 2.65)
			(end -2.25 -2.65)
			(stroke
				(width 0.2)
				(type solid)
			)
			(layer "F.SilkS")
		)
		(fp_line
			(start 2.25 2.65)
			(end 2.25 -2.65)
			(stroke
				(width 0.2)
				(type solid)
			)
			(layer "F.SilkS")
		)
		(fp_circle
			(center 2.75 -2.25)
			(end 2.75 -2.375)
			(stroke
				(width 0.25)
				(type solid)
			)
			(fill no)
			(layer "F.SilkS")
		)
		(fp_line
			(start -2.45 -3.15)
			(end 2.45 -3.15)
			(stroke
				(width 0.2)
				(type solid)
			)
			(layer "F.CrtYd")
		)
		(fp_line
			(start -2.45 3.15)
			(end -2.45 -3.15)
			(stroke
				(width 0.2)
				(type solid)
			)
			(layer "F.CrtYd")
		)
		(fp_line
			(start -2.45 3.15)
			(end 2.45 3.15)
			(stroke
				(width 0.2)
				(type solid)
			)
			(layer "F.CrtYd")
		)
		(fp_line
			(start 2.45 3.15)
			(end 2.45 -3.15)
			(stroke
				(width 0.2)
				(type solid)
			)
			(layer "F.CrtYd")
		)
		(fp_line
			(start -2.45 -3.15)
			(end 2.45 -3.15)
			(stroke
				(width 0.2)
				(type solid)
			)
			(layer "F.Fab")
		)
		(fp_line
			(start -2.45 3.15)
			(end -2.45 -3.15)
			(stroke
				(width 0.2)
				(type solid)
			)
			(layer "F.Fab")
		)
		(fp_line
			(start -2.45 3.15)
			(end 2.45 3.15)
			(stroke
				(width 0.2)
				(type solid)
			)
			(layer "F.Fab")
		)
		(fp_line
			(start -0.735 0)
			(end 0.735 0)
			(stroke
				(width 0.1)
				(type solid)
			)
			(layer "F.Fab")
		)
		(fp_line
			(start 0 0.735)
			(end 0 -0.735)
			(stroke
				(width 0.1)
				(type solid)
			)
			(layer "F.Fab")
		)
		(fp_line
			(start 2.45 3.15)
			(end 2.45 -3.15)
			(stroke
				(width 0.2)
				(type solid)
			)
			(layer "F.Fab")
		)
		(fp_text user "${REFERENCE}"
			(at 0 0.28425 360)
			(unlocked yes)
			(layer "F.Fab")
			(effects
				(font
					(face "Arial")
					(size 0.63 0.63)
					(thickness 0.1)
				)
				(justify left bottom)
			)
		)
		(pad "1" smd rect
			(at 1.5625 -2.25)
			(size 0.475 0.35)
			(layers "F.Cu" "F.Mask" "F.Paste")
			(solder_mask_margin -1000)
			(solder_paste_margin 0)
		)
		(pad "2" smd rect
			(at 0.75 -2.3125)
			(size 0.25 0.475)
			(layers "F.Cu" "F.Mask" "F.Paste")
			(net "GND")
			(solder_mask_margin -1000)
			(solder_paste_margin 0)
		)
		(pad "3" smd rect
			(at 0.25 -2.3125)
			(size 0.25 0.475)
			(layers "F.Cu" "F.Mask" "F.Paste")
			(net "BNO_P3V3")
			(solder_mask_margin -1000)
			(solder_paste_margin 0)
		)
		(pad "4" smd rect
			(at -0.25 -2.3125)
			(size 0.25 0.475)
			(layers "F.Cu" "F.Mask" "F.Paste")
			(net "NetR51_2")
			(solder_mask_margin -1000)
			(solder_paste_margin 0)
		)
		(pad "5" smd rect
			(at -0.75 -2.3125)
			(size 0.25 0.475)
			(layers "F.Cu" "F.Mask" "F.Paste")
			(net "GND")
			(solder_mask_margin -1000)
			(solder_paste_margin 0)
		)
		(pad "6" smd rect
			(at -1.56249 -2.25)
			(size 0.475 0.35)
			(layers "F.Cu" "F.Mask" "F.Paste")
			(net "GND")
			(solder_mask_margin -1000)
			(solder_paste_margin 0)
		)
		(pad "7" smd rect
			(at -1.56249 -1.75)
			(size 0.475 0.35)
			(layers "F.Cu" "F.Mask" "F.Paste")
			(net "NetR57_2")
			(solder_mask_margin -1000)
			(solder_paste_margin 0)
		)
		(pad "8" smd rect
			(at -1.56249 -1.25)
			(size 0.475 0.35)
			(layers "F.Cu" "F.Mask" "F.Paste")
			(net "NetR58_2")
			(solder_mask_margin -1000)
			(solder_paste_margin 0)
		)
		(pad "9" smd rect
			(at -1.56249 -0.75)
			(size 0.475 0.35)
			(layers "F.Cu" "F.Mask" "F.Paste")
			(net "NetC65_1")
			(solder_mask_margin -1000)
			(solder_paste_margin 0)
		)
		(pad "10" smd rect
			(at -1.56249 -0.25)
			(size 0.475 0.35)
			(layers "F.Cu" "F.Mask" "F.Paste")
			(net "NetR55_2")
			(solder_mask_margin -1000)
			(solder_paste_margin 0)
		)
		(pad "11" smd rect
			(at -1.56249 0.25)
			(size 0.475 0.35)
			(layers "F.Cu" "F.Mask" "F.Paste")
			(net "NetR52_1")
			(solder_mask_margin -1000)
			(solder_paste_margin 0)
		)
		(pad "12" smd rect
			(at -1.56249 0.75)
			(size 0.475 0.35)
			(layers "F.Cu" "F.Mask" "F.Paste")
			(solder_mask_margin -1000)
			(solder_paste_margin 0)
		)
		(pad "13" smd rect
			(at -1.56249 1.25)
			(size 0.475 0.35)
			(layers "F.Cu" "F.Mask" "F.Paste")
			(solder_mask_margin -1000)
			(solder_paste_margin 0)
		)
		(pad "14" smd rect
			(at -1.56249 1.75)
			(size 0.475 0.35)
			(layers "F.Cu" "F.Mask" "F.Paste")
			(net "BNO_INT")
			(solder_mask_margin -1000)
			(solder_paste_margin 0)
		)
		(pad "15" smd rect
			(at -1.56249 2.25)
			(size 0.475 0.35)
			(layers "F.Cu" "F.Mask" "F.Paste")
			(solder_mask_margin -1000)
			(solder_paste_margin 0)
		)
		(pad "16" smd rect
			(at -0.75 2.3125)
			(size 0.25 0.475)
			(layers "F.Cu" "F.Mask" "F.Paste")
			(solder_mask_margin -1000)
			(solder_paste_margin 0)
		)
		(pad "17" smd rect
			(at -0.25 2.3125)
			(size 0.25 0.475)
			(layers "F.Cu" "F.Mask" "F.Paste")
			(net "NetR53_1")
			(solder_mask_margin -1000)
			(solder_paste_margin 0)
		)
		(pad "18" smd rect
			(at 0.25 2.3125)
			(size 0.25 0.475)
			(layers "F.Cu" "F.Mask" "F.Paste")
			(net "GND")
			(solder_mask_margin -1000)
			(solder_paste_margin 0)
		)
		(pad "19" smd rect
			(at 0.75 2.3125)
			(size 0.25 0.475)
			(layers "F.Cu" "F.Mask" "F.Paste")
			(net "SENS_I2C_SCL")
			(solder_mask_margin -1000)
			(solder_paste_margin 0)
		)
		(pad "20" smd rect
			(at 1.5625 2.25)
			(size 0.475 0.35)
			(layers "F.Cu" "F.Mask" "F.Paste")
			(net "SENS_I2C_SDA")
			(solder_mask_margin -1000)
			(solder_paste_margin 0)
		)
		(pad "21" smd rect
			(at 1.5625 1.75)
			(size 0.475 0.35)
			(layers "F.Cu" "F.Mask" "F.Paste")
			(solder_mask_margin -1000)
			(solder_paste_margin 0)
		)
		(pad "22" smd rect
			(at 1.5625 1.25)
			(size 0.475 0.35)
			(layers "F.Cu" "F.Mask" "F.Paste")
			(solder_mask_margin -1000)
			(solder_paste_margin 0)
		)
		(pad "23" smd rect
			(at 1.5625 0.75)
			(size 0.475 0.35)
			(layers "F.Cu" "F.Mask" "F.Paste")
			(solder_mask_margin -1000)
			(solder_paste_margin 0)
		)
		(pad "24" smd rect
			(at 1.5625 0.25)
			(size 0.475 0.35)
			(layers "F.Cu" "F.Mask" "F.Paste")
			(solder_mask_margin -1000)
			(solder_paste_margin 0)
		)
		(pad "25" smd rect
			(at 1.5625 -0.25)
			(size 0.475 0.35)
			(layers "F.Cu" "F.Mask" "F.Paste")
			(net "GND")
			(solder_mask_margin -1000)
			(solder_paste_margin 0)
		)
		(pad "26" smd rect
			(at 1.5625 -0.75)
			(size 0.475 0.35)
			(layers "F.Cu" "F.Mask" "F.Paste")
			(net "BNO_XOUT32")
			(solder_mask_margin -1000)
			(solder_paste_margin 0)
		)
		(pad "27" smd rect
			(at 1.5625 -1.25)
			(size 0.475 0.35)
			(layers "F.Cu" "F.Mask" "F.Paste")
			(net "BNO_XIN32")
			(solder_mask_margin -1000)
			(solder_paste_margin 0)
		)
		(pad "28" smd rect
			(at 1.5625 -1.75)
			(size 0.475 0.35)
			(layers "F.Cu" "F.Mask" "F.Paste")
			(net "BNO_P3V3")
			(solder_mask_margin -1000)
			(solder_paste_margin 0)
		)
	)
	(footprint "Vault:RESC1005X40X25LL05T10"
		(layer "F.Cu")
		(at 146.1216 103.3162)
		(property "Reference" "R107"
			(at 1.57942 -1.122249 0)
			(unlocked yes)
			(layer "F.SilkS")
			(effects
				(font
					(size 0.762 0.762)
					(thickness 0.2286)
				)
			)
		)
		(property "Value" "DNI_49.9_1%_0402"
			(at -2.579871 11.74372 270)
			(unlocked yes)
			(layer "F.SilkS")
			(hide yes)
			(effects
				(font
					(size 0.762 0.762)
					(thickness 0.2286)
				)
			)
		)
		(sheetname "09-USBUart_PPSMUX_UARTMUX")
		(sheetfile "09-USBUart_PPSMUX_UARTMUX.kicad_sch")
		(duplicate_pad_numbers_are_jumpers no)
		(pad "1" smd rect
			(at -0.375 0 90)
			(size 0.45 0.5)
			(layers "F.Cu" "F.Mask" "F.Paste")
			(net "FPGA_MAC_PPS_IN0-")
		)
		(pad "2" smd rect
			(at 0.375 0 90)
			(size 0.45 0.5)
			(layers "F.Cu" "F.Mask" "F.Paste")
			(net "FPGA_MAC_PPS_DIFF_IN0")
		)
	)
	(footprint "Vault:RESC1005X40X25LL05T10"
		(layer "F.Cu")
		(at 192.2216 128.9162 90)
		(property "Reference" "R142"
			(at 0.90981 -2.466549 90)
			(unlocked yes)
			(layer "F.SilkS")
			(effects
				(font
					(size 0.762 0.762)
					(thickness 0.2032)
				)
			)
		)
		(property "Value" "49.9_1%_0402"
			(at -2.579871 8.798265 0)
			(unlocked yes)
			(layer "F.SilkS")
			(hide yes)
			(effects
				(font
					(size 0.762 0.762)
					(thickness 0.2032)
				)
			)
		)
		(sheetname "11-M2_RCB_MUX")
		(sheetfile "11-M2_RCB_MUX.kicad_sch")
		(duplicate_pad_numbers_are_jumpers no)
		(pad "1" smd rect
			(at -0.375 0 180)
			(size 0.45 0.5)
			(layers "F.Cu" "F.Mask" "F.Paste")
			(net "NetR142_1")
		)
		(pad "2" smd rect
			(at 0.375 0 180)
			(size 0.45 0.5)
			(layers "F.Cu" "F.Mask" "F.Paste")
			(net "GPS2_TX")
		)
	)
	(footprint "Vault:RESC3216X89X64NL25T25"
		(layer "F.Cu")
		(at 223.2466 68.4162)
		(property "Reference" "R7"
			(at 2.475 0.493345 0)
			(unlocked yes)
			(layer "F.SilkS")
			(effects
				(font
					(size 0.762 0.762)
					(thickness 0.2286)
				)
				(justify left bottom)
			)
		)
		(property "Value" "2mOhm_1%_1206"
			(at 7.6471 8.378245 0)
			(unlocked yes)
			(layer "F.SilkS")
			(hide yes)
			(effects
				(font
					(size 0.762 0.762)
					(thickness 0.2286)
				)
				(justify left bottom)
			)
		)
		(sheetname "03-POWER")
		(sheetfile "03-POWER.kicad_sch")
		(duplicate_pad_numbers_are_jumpers no)
		(fp_line
			(start -0.2 -0.825)
			(end 0.2 -0.825)
			(stroke
				(width 0.2)
				(type solid)
			)
			(layer "F.SilkS")
		)
		(fp_line
			(start -0.2 0.825)
			(end 0.2 0.825)
			(stroke
				(width 0.2)
				(type solid)
			)
			(layer "F.SilkS")
		)
		(pad "1" smd rect
			(at -1.325 0 90)
			(size 1.85 1.5)
			(layers "F.Cu" "F.Mask" "F.Paste")
			(net "+12V_SENS")
		)
		(pad "2" smd rect
			(at 1.325 0 90)
			(size 1.85 1.5)
			(layers "F.Cu" "F.Mask" "F.Paste")
			(net "+12V")
		)
	)
	(footprint "Vault:CTS-219-2LPST_V"
		(layer "F.Cu")
		(at 226.4216 98.0162 180)
		(property "Reference" "SW2"
			(at -2.7968 -3.973069 180)
			(unlocked yes)
			(layer "F.SilkS")
			(effects
				(font
					(size 0.762 0.762)
					(thickness 0.2032)
				)
			)
		)
		(property "Value" "219-2LPST"
			(at 5.115805 7.659871 180)
			(unlocked yes)
			(layer "F.SilkS")
			(hide yes)
			(effects
				(font
					(size 0.762 0.762)
					(thickness 0.2032)
				)
			)
		)
		(sheetname "08-DIPSwitches_I2C")
		(sheetfile "08-DIPSwitches_I2C.kicad_sch")
		(duplicate_pad_numbers_are_jumpers no)
		(fp_line
			(start 3.3528 3.2766)
			(end -3.3528 3.2766)
			(stroke
				(width 0.2)
				(type solid)
			)
			(layer "F.SilkS")
		)
		(fp_line
			(start 3.3528 2.2292)
			(end 3.3528 3.2766)
			(stroke
				(width 0.2)
				(type solid)
			)
			(layer "F.SilkS")
		)
		(fp_line
			(start 3.3528 -3.2766)
			(end 3.3528 -2.2292)
			(stroke
				(width 0.2)
				(type solid)
			)
			(layer "F.SilkS")
		)
		(fp_line
			(start 3.3528 -3.2766)
			(end -3.3528 -3.2766)
			(stroke
				(width 0.2)
				(type solid)
			)
			(layer "F.SilkS")
		)
		(fp_line
			(start -3.3528 2.2292)
			(end -3.3528 3.2766)
			(stroke
				(width 0.2)
				(type solid)
			)
			(layer "F.SilkS")
		)
		(fp_line
			(start -3.3528 -3.2766)
			(end -3.3528 -2.2292)
			(stroke
				(width 0.2)
				(type solid)
			)
			(layer "F.SilkS")
		)
		(fp_circle
			(center -4.3 -2.9)
			(end -4.3 -2.775)
			(stroke
				(width 0.25)
				(type solid)
			)
			(fill no)
			(layer "F.SilkS")
		)
		(pad "1" smd rect
			(at -4.3053 -1.27 90)
			(size 1.1176 2.4384)
			(layers "F.Cu" "F.Mask" "F.Paste")
			(net "GND")
		)
		(pad "2" smd rect
			(at -4.3053 1.27 90)
			(size 1.1176 2.4384)
			(layers "F.Cu" "F.Mask" "F.Paste")
			(net "GND")
		)
		(pad "3" smd rect
			(at 4.3053 1.27 90)
			(size 1.1176 2.4384)
			(layers "F.Cu" "F.Mask" "F.Paste")
			(net "DIP_SW_GPS1_SEL")
		)
		(pad "4" smd rect
			(at 4.3053 -1.27 90)
			(size 1.1176 2.4384)
			(layers "F.Cu" "F.Mask" "F.Paste")
			(net "DIP_SW_GPS2_SEL")
		)
	)
	(footprint "GNSS:GNSS Header 16-pin"
		(locked yes)
		(layer "F.Cu")
		(at 103.2491 74.2286)
		(property "Reference" "J6"
			(at 3.943895 1.260669 180)
			(unlocked yes)
			(layer "F.SilkS")
			(effects
				(font
					(size 0.762 0.762)
					(thickness 0.2286)
				)
			)
		)
		(property "Value" "GNSS Header 16-pin"
			(at 6.740165 4.840511 0)
			(unlocked yes)
			(layer "F.SilkS")
			(hide yes)
			(effects
				(font
					(size 0.762 0.762)
					(thickness 0.2286)
				)
			)
		)
		(sheetname "05-GPS_IMU_SENSORS")
		(sheetfile "05-GPS_IMU_SENSORS.kicad_sch")
		(duplicate_pad_numbers_are_jumpers no)
		(fp_line
			(start -0.5 -7.5)
			(end 8.5 -7.5)
			(stroke
				(width 0.0254)
				(type solid)
			)
			(layer "F.SilkS")
		)
		(fp_line
			(start -0.5 0.5)
			(end -0.5 -7.5)
			(stroke
				(width 0.0254)
				(type solid)
			)
			(layer "F.SilkS")
		)
		(fp_line
			(start -0.5 0.5)
			(end 8.5 0.5)
			(stroke
				(width 0.0254)
				(type solid)
			)
			(layer "F.SilkS")
		)
		(fp_line
			(start 8.5 0.5)
			(end 8.5 -7.5)
			(stroke
				(width 0.0254)
				(type solid)
			)
			(layer "F.SilkS")
		)
		(fp_circle
			(center 0 -0.5)
			(end 0 -0.5254)
			(stroke
				(width 0.508)
				(type solid)
			)
			(fill no)
			(layer "F.SilkS")
		)
		(fp_text user "Orig 2x4"
			(at 9.610805 -0.2286 90)
			(unlocked yes)
			(layer "F.SilkS")
			(effects
				(font
					(size 0.762 0.762)
					(thickness 0.2286)
				)
				(justify left bottom)
			)
		)
		(pad "0" thru_hole circle
			(at 4 -13.49998 270)
			(size 0 0)
			(drill 0.76)
			(layers "*.Cu" "*.Mask")
			(remove_unused_layers no)
			(thermal_bridge_angle 90)
		)
		(pad "0" thru_hole circle
			(at 4 -1.5 270)
			(size 0 0)
			(drill 0.76)
			(layers "*.Cu" "*.Mask")
			(remove_unused_layers no)
			(thermal_bridge_angle 90)
		)
		(pad "1" smd rect
			(at 1.7775 -0.5 270)
			(size 1.12 2.105)
			(layers "F.Cu" "F.Mask" "F.Paste")
			(net "+5.0V")
		)
		(pad "2" smd rect
			(at 6.2225 -0.5 270)
			(size 1.12 2.105)
			(layers "F.Cu" "F.Mask" "F.Paste")
			(net "+3.3V")
		)
		(pad "3" smd rect
			(at 1.7775 -2.5 270)
			(size 1.12 2.105)
			(layers "F.Cu" "F.Mask" "F.Paste")
			(net "RCB_GPS1_TX")
		)
		(pad "4" smd rect
			(at 6.2225 -2.5 270)
			(size 1.12 2.105)
			(layers "F.Cu" "F.Mask" "F.Paste")
			(net "GPS1_RST")
		)
		(pad "5" smd rect
			(at 1.7775 -4.5 270)
			(size 1.12 2.105)
			(layers "F.Cu" "F.Mask" "F.Paste")
			(net "RCB_GPS1_RX")
		)
		(pad "6" smd rect
			(at 6.2225 -4.5 270)
			(size 1.12 2.105)
			(layers "F.Cu" "F.Mask" "F.Paste")
			(net "RCB_GPS1_TP1")
		)
		(pad "7" smd rect
			(at 1.7775 -6.5 270)
			(size 1.12 2.105)
			(layers "F.Cu" "F.Mask" "F.Paste")
			(net "RCB_GPS1_TP2")
		)
		(pad "8" smd rect
			(at 6.2225 -6.5 270)
			(size 1.12 2.105)
			(layers "F.Cu" "F.Mask" "F.Paste")
			(net "GND")
		)
		(pad "9" smd rect
			(at 1.7775 -8.50001 270)
			(size 1.12 2.105)
			(layers "F.Cu" "F.Mask" "F.Paste")
			(net "+5.0V")
		)
		(pad "10" smd rect
			(at 6.2225 -8.50001 270)
			(size 1.12 2.105)
			(layers "F.Cu" "F.Mask" "F.Paste")
			(net "+3.3V")
		)
		(pad "11" smd rect
			(at 1.7775 -10.50001 270)
			(size 1.12 2.105)
			(layers "F.Cu" "F.Mask" "F.Paste")
			(net "RCB_GPS1_PIN11")
		)
		(pad "12" smd rect
			(at 6.2225 -10.50001 270)
			(size 1.12 2.105)
			(layers "F.Cu" "F.Mask" "F.Paste")
			(net "RCB_GPS1_PIN12")
		)
		(pad "13" smd rect
			(at 1.7775 -12.5 270)
			(size 1.12 2.105)
			(layers "F.Cu" "F.Mask" "F.Paste")
			(net "GPS1_PIN13")
		)
		(pad "14" smd rect
			(at 6.2225 -12.5 270)
			(size 1.12 2.105)
			(layers "F.Cu" "F.Mask" "F.Paste")
			(net "GPS1_PIN14")
		)
		(pad "15" smd rect
			(at 1.7775 -14.5 270)
			(size 1.12 2.105)
			(layers "F.Cu" "F.Mask" "F.Paste")
			(net "GPS1_PIN15")
		)
		(pad "16" smd rect
			(at 6.2225 -14.5 270)
			(size 1.12 2.105)
			(layers "F.Cu" "F.Mask" "F.Paste")
			(net "GND")
		)
	)
	(footprint "MBRD10200CT-13:TO252(DPAK)_DIO"
		(layer "F.Cu")
		(at 215.8216 64.4162 -90)
		(property "Reference" "CR1"
			(at -3.773079 5.196795 0)
			(unlocked yes)
			(layer "F.SilkS")
			(effects
				(font
					(size 0.762 0.762)
					(thickness 0.2032)
				)
			)
		)
		(property "Value" "MBRD10200CT-13"
			(at 5.013215 8.269471 270)
			(unlocked yes)
			(layer "F.SilkS")
			(hide yes)
			(effects
				(font
					(size 0.762 0.762)
					(thickness 0.2032)
				)
			)
		)
		(sheetname "03-POWER")
		(sheetfile "03-POWER.kicad_sch")
		(duplicate_pad_numbers_are_jumpers no)
		(fp_line
			(start -0.5715 4.2418)
			(end -0.5715 3.2258)
			(stroke
				(width 0.1524)
				(type solid)
			)
			(layer "F.SilkS")
		)
		(fp_line
			(start 0.5715 4.2418)
			(end -0.5715 4.2418)
			(stroke
				(width 0.1524)
				(type solid)
			)
			(layer "F.SilkS")
		)
		(fp_line
			(start 0.5715 4.2418)
			(end 0.5715 3.2258)
			(stroke
				(width 0.1524)
				(type solid)
			)
			(layer "F.SilkS")
		)
		(fp_line
			(start -3.4798 3.2258)
			(end -3.4798 -3.2258)
			(stroke
				(width 0.1524)
				(type solid)
			)
			(layer "F.SilkS")
		)
		(fp_line
			(start -0.5715 3.2258)
			(end -3.4798 3.2258)
			(stroke
				(width 0.1524)
				(type solid)
			)
			(layer "F.SilkS")
		)
		(fp_line
			(start 3.4798 3.2258)
			(end 0.5715 3.2258)
			(stroke
				(width 0.1524)
				(type solid)
			)
			(layer "F.SilkS")
		)
		(fp_line
			(start 3.4798 3.2258)
			(end 3.4798 -3.2258)
			(stroke
				(width 0.1524)
				(type solid)
			)
			(layer "F.SilkS")
		)
		(fp_line
			(start -3.08864 -3.2258)
			(end -3.4798 -3.2258)
			(stroke
				(width 0.1524)
				(type solid)
			)
			(layer "F.SilkS")
		)
		(fp_line
			(start 3.4798 -3.2258)
			(end 3.08864 -3.2258)
			(stroke
				(width 0.1524)
				(type solid)
			)
			(layer "F.SilkS")
		)
		(fp_text user "*"
			(at -5.5245 5.946775 270)
			(unlocked yes)
			(layer "F.SilkS")
			(effects
				(font
					(size 1.27 1.27)
					(thickness 0.0762)
				)
				(justify left bottom)
			)
		)
		(pad "1" smd rect
			(at -2.286 5.1562 270)
			(size 0.9398 2.4892)
			(layers "F.Cu" "F.Mask" "F.Paste")
			(net "NetCR1_1")
			(solder_mask_margin 0)
			(solder_paste_margin 0)
		)
		(pad "2" smd rect
			(at 0 -1.7653 270)
			(size 5.5118 5.9182)
			(layers "F.Cu" "F.Mask" "F.Paste")
			(net "NetCR1_2")
			(solder_mask_margin 0)
			(solder_paste_margin 0)
		)
		(pad "3" smd rect
			(at 2.286 5.1562 270)
			(size 0.9398 2.4892)
			(layers "F.Cu" "F.Mask" "F.Paste")
			(net "+12V_PCIE")
			(solder_mask_margin 0)
			(solder_paste_margin 0)
		)
	)
	(footprint "Vault:M08A_L"
		(layer "F.Cu")
		(at 124.6216 86.1162 90)
		(property "Reference" "U4"
			(at 1.028595 -3.235469 90)
			(unlocked yes)
			(layer "F.SilkS")
			(effects
				(font
					(size 0.762 0.762)
					(thickness 0.2286)
				)
			)
		)
		(property "Value" "DS90LV028AQMA"
			(at 6.71518 4.180071 90)
			(unlocked yes)
			(layer "F.SilkS")
			(hide yes)
			(effects
				(font
					(size 0.762 0.762)
					(thickness 0.2286)
				)
			)
		)
		(sheetname "06-MAC")
		(sheetfile "06-MAC.kicad_sch")
		(duplicate_pad_numbers_are_jumpers no)
		(fp_line
			(start 1 -2.5)
			(end 1 2.5)
			(stroke
				(width 0.2)
				(type solid)
			)
			(layer "F.SilkS")
		)
		(fp_line
			(start -1 -2.5)
			(end 1 -2.5)
			(stroke
				(width 0.2)
				(type solid)
			)
			(layer "F.SilkS")
		)
		(fp_line
			(start -1 -2.5)
			(end -1 2.5)
			(stroke
				(width 0.2)
				(type solid)
			)
			(layer "F.SilkS")
		)
		(fp_line
			(start -1 2.5)
			(end 1 2.5)
			(stroke
				(width 0.2)
				(type solid)
			)
			(layer "F.SilkS")
		)
		(fp_circle
			(center -2.35 -2.755)
			(end -2.225 -2.755)
			(stroke
				(width 0.25)
				(type solid)
			)
			(fill no)
			(layer "F.SilkS")
		)
		(fp_circle
			(center -0.2 -1.7)
			(end 0 -1.7)
			(stroke
				(width 0.4)
				(type solid)
			)
			(fill no)
			(layer "F.SilkS")
		)
		(pad "1" smd oval
			(at -2.35 -1.905 180)
			(size 0.6 1.9)
			(layers "F.Cu" "F.Mask" "F.Paste")
			(net "MAC_PPS_OUT-")
		)
		(pad "2" smd oval
			(at -2.35 -0.635 180)
			(size 0.6 1.9)
			(layers "F.Cu" "F.Mask" "F.Paste")
			(net "MAC_PPS_OUT+")
		)
		(pad "3" smd oval
			(at -2.35 0.635 180)
			(size 0.6 1.9)
			(layers "F.Cu" "F.Mask" "F.Paste")
		)
		(pad "4" smd oval
			(at -2.35 1.905 180)
			(size 0.6 1.9)
			(layers "F.Cu" "F.Mask" "F.Paste")
		)
		(pad "5" smd oval
			(at 2.35 1.905 180)
			(size 0.6 1.9)
			(layers "F.Cu" "F.Mask" "F.Paste")
			(net "GND")
		)
		(pad "6" smd oval
			(at 2.35 0.635 180)
			(size 0.6 1.9)
			(layers "F.Cu" "F.Mask" "F.Paste")
		)
		(pad "7" smd oval
			(at 2.35 -0.635 180)
			(size 0.6 1.9)
			(layers "F.Cu" "F.Mask" "F.Paste")
			(net "FPGA_MAC_PPSDIFF_OUT")
		)
		(pad "8" smd oval
			(at 2.35 -1.905 180)
			(size 0.6 1.9)
			(layers "F.Cu" "F.Mask" "F.Paste")
			(net "+3.3V")
		)
	)
	(footprint "Vault:FP-ERJ2R-MFG"
		(layer "F.Cu")
		(at 227.2216 120.3162)
		(property "Reference" "R83"
			(at -2.1714 0.426931 0)
			(unlocked yes)
			(layer "F.SilkS")
			(effects
				(font
					(size 0.762 0.762)
					(thickness 0.2286)
				)
			)
		)
		(property "Value" "15K_1%_0402"
			(at -2.732271 8.011115 270)
			(unlocked yes)
			(layer "F.SilkS")
			(hide yes)
			(effects
				(font
					(size 0.762 0.762)
					(thickness 0.2286)
				)
			)
		)
		(sheetname "09-USBUart_PPSMUX_UARTMUX")
		(sheetfile "09-USBUart_PPSMUX_UARTMUX.kicad_sch")
		(duplicate_pad_numbers_are_jumpers no)
		(fp_line
			(start -0.529 0.636)
			(end 0.521 0.636)
			(stroke
				(width 0.2)
				(type solid)
			)
			(layer "F.SilkS")
		)
		(fp_line
			(start -0.525 -0.65)
			(end 0.525 -0.65)
			(stroke
				(width 0.2)
				(type solid)
			)
			(layer "F.SilkS")
		)
		(fp_line
			(start -0.85 -0.375)
			(end 0.85 -0.375)
			(stroke
				(width 0.2)
				(type solid)
			)
			(layer "F.CrtYd")
		)
		(fp_line
			(start -0.85 0.375)
			(end -0.85 -0.375)
			(stroke
				(width 0.2)
				(type solid)
			)
			(layer "F.CrtYd")
		)
		(fp_line
			(start -0.85 0.375)
			(end 0.85 0.375)
			(stroke
				(width 0.2)
				(type solid)
			)
			(layer "F.CrtYd")
		)
		(fp_line
			(start 0.85 0.375)
			(end 0.85 -0.375)
			(stroke
				(width 0.2)
				(type solid)
			)
			(layer "F.CrtYd")
		)
		(fp_line
			(start -0.85 -0.375)
			(end 0.85 -0.375)
			(stroke
				(width 0.2)
				(type solid)
			)
			(layer "F.Fab")
		)
		(fp_line
			(start -0.85 0.375)
			(end -0.85 -0.375)
			(stroke
				(width 0.2)
				(type solid)
			)
			(layer "F.Fab")
		)
		(fp_line
			(start -0.85 0.375)
			(end 0.85 0.375)
			(stroke
				(width 0.2)
				(type solid)
			)
			(layer "F.Fab")
		)
		(fp_line
			(start -0.5 0)
			(end 0.5 0)
			(stroke
				(width 0.1)
				(type solid)
			)
			(layer "F.Fab")
		)
		(fp_line
			(start 0 0.5)
			(end 0 -0.5)
			(stroke
				(width 0.1)
				(type solid)
			)
			(layer "F.Fab")
		)
		(fp_line
			(start 0.85 0.375)
			(end 0.85 -0.375)
			(stroke
				(width 0.2)
				(type solid)
			)
			(layer "F.Fab")
		)
		(fp_text user "${REFERENCE}"
			(at -0.00001 0.09602 360)
			(unlocked yes)
			(layer "F.Fab")
			(effects
				(font
					(face "Arial")
					(size 0.63 0.63)
					(thickness 0.1)
				)
				(justify left bottom)
			)
		)
		(pad "1" smd rect
			(at -0.5125 0)
			(size 0.475 0.5)
			(layers "F.Cu" "F.Mask" "F.Paste")
			(net "GND")
			(solder_mask_margin 0)
			(solder_paste_margin 0)
		)
		(pad "2" smd rect
			(at 0.5125 0)
			(size 0.475 0.5)
			(layers "F.Cu" "F.Mask" "F.Paste")
			(net "NetC91_1")
			(solder_mask_margin 0)
			(solder_paste_margin 0)
		)
	)
	(footprint "Vault:RESC1005X40X25NL05T05"
		(layer "F.Cu")
		(at 227.6216 113.2162 180)
		(property "Reference" "R42"
			(at -0.3286 0.773079 0)
			(unlocked yes)
			(layer "F.SilkS")
			(effects
				(font
					(size 0.762 0.762)
					(thickness 0.2286)
				)
			)
		)
		(property "Value" "27_1%_0402"
			(at -3.011631 6.10665 90)
			(unlocked yes)
			(layer "F.SilkS")
			(hide yes)
			(effects
				(font
					(size 0.762 0.762)
					(thickness 0.2286)
				)
			)
		)
		(sheetname "09-USBUart_PPSMUX_UARTMUX")
		(sheetfile "09-USBUart_PPSMUX_UARTMUX.kicad_sch")
		(duplicate_pad_numbers_are_jumpers no)
		(pad "1" smd rect
			(at -0.45 0 270)
			(size 0.55 0.55)
			(layers "F.Cu" "F.Mask" "F.Paste")
			(net "NetR42_1")
		)
		(pad "2" smd rect
			(at 0.45 0 270)
			(size 0.55 0.55)
			(layers "F.Cu" "F.Mask" "F.Paste")
			(net "FTDI_RX")
		)
	)
	(footprint "SA53:SolderSocket"
		(locked yes)
		(layer "F.Cu")
		(at 127.5216 137.3162 90)
		(property "Reference" "SKT9"
			(at -0.126931 7.1286 0)
			(unlocked yes)
			(layer "F.SilkS")
			(effects
				(font
					(size 0.762 0.762)
					(thickness 0.2286)
				)
			)
		)
		(property "Value" "0332-0-43-80-18-27-10-0"
			(at -2.910071 16.1362 0)
			(unlocked yes)
			(layer "F.SilkS")
			(hide yes)
			(effects
				(font
					(size 0.762 0.762)
					(thickness 0.2286)
				)
			)
		)
		(sheetname "06-MAC")
		(sheetfile "06-MAC.kicad_sch")
		(duplicate_pad_numbers_are_jumpers no)
		(pad "1" thru_hole circle
			(at 0 0 90)
			(size 2.54 2.54)
			(drill 2.0066)
			(layers "*.Cu" "*.Mask")
			(remove_unused_layers no)
			(net "GND")
			(thermal_bridge_angle 90)
		)
	)
	(footprint "Vault:FP-0402-L_1_0_0_05-W_0_5-IPC_A"
		(layer "B.Cu")
		(at 223.56155 127.69916 -90)
		(property "Reference" "C114"
			(at -0.13696 -1.533119 270)
			(unlocked yes)
			(layer "B.SilkS")
			(effects
				(font
					(size 0.762 0.762)
					(thickness 0.254)
				)
				(justify mirror)
			)
		)
		(property "Value" "1uF_16V_0402"
			(at -2.744961 -8.315705 180)
			(unlocked yes)
			(layer "B.SilkS")
			(hide yes)
			(effects
				(font
					(size 0.762 0.762)
					(thickness 0.254)
				)
				(justify mirror)
			)
		)
		(sheetname "09-USBUart_PPSMUX_UARTMUX")
		(sheetfile "09-USBUart_PPSMUX_UARTMUX.kicad_sch")
		(duplicate_pad_numbers_are_jumpers no)
		(fp_line
			(start 0.83623 0.73624)
			(end -0.83624 0.73624)
			(stroke
				(width 0.2)
				(type solid)
			)
			(layer "B.SilkS")
		)
		(fp_line
			(start 0.83623 -0.73623)
			(end -0.83624 -0.73623)
			(stroke
				(width 0.2)
				(type solid)
			)
			(layer "B.SilkS")
		)
		(fp_line
			(start -1.03624 0.53624)
			(end -1.03624 -0.53623)
			(stroke
				(width 0.2)
				(type solid)
			)
			(layer "B.CrtYd")
		)
		(fp_line
			(start 1.03623 0.53624)
			(end -1.03624 0.53624)
			(stroke
				(width 0.2)
				(type solid)
			)
			(layer "B.CrtYd")
		)
		(fp_line
			(start 1.03623 0.53624)
			(end 1.03623 -0.53623)
			(stroke
				(width 0.2)
				(type solid)
			)
			(layer "B.CrtYd")
		)
		(fp_line
			(start 1.03623 -0.53623)
			(end -1.03624 -0.53623)
			(stroke
				(width 0.2)
				(type solid)
			)
			(layer "B.CrtYd")
		)
		(fp_line
			(start -1.03624 0.53624)
			(end -1.03624 -0.53623)
			(stroke
				(width 0.2)
				(type solid)
			)
			(layer "B.Fab")
		)
		(fp_line
			(start 1.03623 0.53624)
			(end -1.03624 0.53624)
			(stroke
				(width 0.2)
				(type solid)
			)
			(layer "B.Fab")
		)
		(fp_line
			(start 1.03623 0.53624)
			(end 1.03623 -0.53623)
			(stroke
				(width 0.2)
				(type solid)
			)
			(layer "B.Fab")
		)
		(fp_line
			(start 0 0.5)
			(end 0 -0.5)
			(stroke
				(width 0.1)
				(type solid)
			)
			(layer "B.Fab")
		)
		(fp_line
			(start 0.49999 0)
			(end -0.5 0)
			(stroke
				(width 0.1)
				(type solid)
			)
			(layer "B.Fab")
		)
		(fp_line
			(start 1.03623 -0.53623)
			(end -1.03624 -0.53623)
			(stroke
				(width 0.2)
				(type solid)
			)
			(layer "B.Fab")
		)
		(fp_text user "${REFERENCE}"
			(at -0.00001 -0.09601 90)
			(unlocked yes)
			(layer "B.Fab")
			(effects
				(font
					(face "Arial")
					(size 0.63 0.63)
					(thickness 0.1)
				)
				(justify left bottom mirror)
			)
		)
		(pad "1" smd rect
			(at -0.47857 0 270)
			(size 0.71535 0.67248)
			(layers "B.Cu" "B.Mask" "B.Paste")
			(net "FTDI_VBUS")
			(solder_mask_margin 0)
			(solder_paste_margin 0)
		)
		(pad "2" smd rect
			(at 0.47856 0 270)
			(size 0.71535 0.67248)
			(layers "B.Cu" "B.Mask" "B.Paste")
			(net "GND")
			(solder_mask_margin 0)
			(solder_paste_margin 0)
		)
	)
	(footprint "Vault:RESC1005X40X25ML05T05"
		(layer "B.Cu")
		(at 213.53831 125.11792)
		(property "Reference" "R182"
			(at -0.59568 -1.574789 0)
			(unlocked yes)
			(layer "B.SilkS")
			(effects
				(font
					(size 0.762 0.762)
					(thickness 0.254)
				)
				(justify mirror)
			)
		)
		(property "Value" "10K_5%_0402"
			(at -2.884671 -8.061875 270)
			(unlocked yes)
			(layer "B.SilkS")
			(hide yes)
			(effects
				(font
					(size 0.762 0.762)
					(thickness 0.254)
				)
				(justify mirror)
			)
		)
		(sheetname "09-USBUart_PPSMUX_UARTMUX")
		(sheetfile "09-USBUart_PPSMUX_UARTMUX.kicad_sch")
		(duplicate_pad_numbers_are_jumpers no)
		(pad "1" smd rect
			(at -0.5 0 270)
			(size 0.65 0.65)
			(layers "B.Cu" "B.Mask" "B.Paste")
			(net "GND")
		)
		(pad "2" smd rect
			(at 0.5 0 270)
			(size 0.65 0.65)
			(layers "B.Cu" "B.Mask" "B.Paste")
			(net "NetR180_1")
		)
	)
	(footprint "Vault:RESC1005X40X25NL10T10"
		(layer "B.Cu")
		(at 126.8216 64.41711 90)
		(property "Reference" "R133"
			(at 2.29771 0.026921 90)
			(unlocked yes)
			(layer "B.SilkS")
			(effects
				(font
					(size 0.762 0.762)
					(thickness 0.2032)
				)
				(justify mirror)
			)
		)
		(property "Value" "4.7K_1%_0402"
			(at -2.732271 -8.747465 0)
			(unlocked yes)
			(layer "B.SilkS")
			(hide yes)
			(effects
				(font
					(size 0.762 0.762)
					(thickness 0.2032)
				)
				(justify mirror)
			)
		)
		(sheetname "10-M2_GPS")
		(sheetfile "10-M2_GPS.kicad_sch")
		(duplicate_pad_numbers_are_jumpers no)
		(pad "1" smd rect
			(at -0.425 0)
			(size 0.6 0.65)
			(layers "B.Cu" "B.Mask" "B.Paste")
			(net "GPS1_PIN14")
		)
		(pad "2" smd rect
			(at 0.425 0)
			(size 0.6 0.65)
			(layers "B.Cu" "B.Mask" "B.Paste")
			(net "+3.3V")
		)
	)
	(footprint "Vault:FP-0402-L_1_0_1-W_0_5_0_1-IPC_C"
		(layer "B.Cu")
		(at 110.66622 54.1145 -90)
		(property "Reference" "C109"
			(at 2.8049 -0.182301 90)
			(unlocked yes)
			(layer "B.SilkS")
			(effects
				(font
					(size 0.762 0.762)
					(thickness 0.2032)
				)
				(justify mirror)
			)
		)
		(property "Value" "0.1uF_25V_0402"
			(at -2.465551 -9.813805 180)
			(unlocked yes)
			(layer "B.SilkS")
			(hide yes)
			(effects
				(font
					(size 0.762 0.762)
					(thickness 0.2032)
				)
				(justify mirror)
			)
		)
		(sheetname "11-M2_RCB_MUX")
		(sheetfile "11-M2_RCB_MUX.kicad_sch")
		(duplicate_pad_numbers_are_jumpers no)
		(fp_line
			(start 0.65607 0.7)
			(end -0.65607 0.7)
			(stroke
				(width 0.2)
				(type solid)
			)
			(layer "B.SilkS")
		)
		(fp_line
			(start 0.65607 -0.7)
			(end -0.65607 -0.7)
			(stroke
				(width 0.2)
				(type solid)
			)
			(layer "B.SilkS")
		)
		(fp_line
			(start -0.75607 0.4)
			(end -0.75607 -0.4)
			(stroke
				(width 0.2)
				(type solid)
			)
			(layer "B.CrtYd")
		)
		(fp_line
			(start 0.75607 0.4)
			(end -0.75607 0.4)
			(stroke
				(width 0.2)
				(type solid)
			)
			(layer "B.CrtYd")
		)
		(fp_line
			(start 0.75607 0.4)
			(end 0.75607 -0.4)
			(stroke
				(width 0.2)
				(type solid)
			)
			(layer "B.CrtYd")
		)
		(fp_line
			(start 0.75607 -0.4)
			(end -0.75607 -0.4)
			(stroke
				(width 0.2)
				(type solid)
			)
			(layer "B.CrtYd")
		)
		(fp_line
			(start 0 0.5)
			(end 0 -0.5)
			(stroke
				(width 0.1)
				(type solid)
			)
			(layer "B.Fab")
		)
		(fp_line
			(start -0.75607 0.4)
			(end -0.75607 -0.4)
			(stroke
				(width 0.2)
				(type solid)
			)
			(layer "B.Fab")
		)
		(fp_line
			(start 0.75607 0.4)
			(end -0.75607 0.4)
			(stroke
				(width 0.2)
				(type solid)
			)
			(layer "B.Fab")
		)
		(fp_line
			(start 0.75607 0.4)
			(end 0.75607 -0.4)
			(stroke
				(width 0.2)
				(type solid)
			)
			(layer "B.Fab")
		)
		(fp_line
			(start 0.5 0)
			(end -0.5 0)
			(stroke
				(width 0.1)
				(type solid)
			)
			(layer "B.Fab")
		)
		(fp_line
			(start 0.75607 -0.4)
			(end -0.75607 -0.4)
			(stroke
				(width 0.2)
				(type solid)
			)
			(layer "B.Fab")
		)
		(fp_text user "${REFERENCE}"
			(at -0.00001 -0.09601 90)
			(unlocked yes)
			(layer "B.Fab")
			(effects
				(font
					(face "Arial")
					(size 0.63 0.63)
					(thickness 0.1)
				)
				(justify left bottom mirror)
			)
		)
		(pad "1" smd rect
			(at -0.36554 0 270)
			(size 0.58106 0.51213)
			(layers "B.Cu" "B.Mask" "B.Paste")
			(net "+3.3V")
			(solder_mask_margin 0)
			(solder_paste_margin 0)
		)
		(pad "2" smd rect
			(at 0.36554 0 270)
			(size 0.58106 0.51213)
			(layers "B.Cu" "B.Mask" "B.Paste")
			(net "GND")
			(solder_mask_margin 0)
			(solder_paste_margin 0)
		)
	)
	(footprint "Vault:CAPC1608X87X45ML20T05"
		(layer "B.Cu")
		(at 121.7216 83.5162 180)
		(property "Reference" "C24"
			(at 0.2286 1.373079 0)
			(unlocked yes)
			(layer "B.SilkS")
			(effects
				(font
					(size 0.762 0.762)
					(thickness 0.2286)
				)
				(justify mirror)
			)
		)
		(property "Value" "0.1uF"
			(at 2.069035 -2.630671 0)
			(unlocked yes)
			(layer "B.SilkS")
			(hide yes)
			(effects
				(font
					(size 0.762 0.762)
					(thickness 0.2286)
				)
				(justify mirror)
			)
		)
		(sheetname "06-MAC")
		(sheetfile "06-MAC.kicad_sch")
		(duplicate_pad_numbers_are_jumpers no)
		(pad "1" smd rect
			(at -0.7 0 90)
			(size 1.1 1.05)
			(layers "B.Cu" "B.Mask" "B.Paste")
			(net "+3.3V")
		)
		(pad "2" smd rect
			(at 0.7 0 90)
			(size 1.1 1.05)
			(layers "B.Cu" "B.Mask" "B.Paste")
			(net "GND")
		)
	)
	(footprint "Vault:FP-C1005-050-0_05-IPC_A"
		(layer "B.Cu")
		(at 100.8216 59.2162 180)
		(property "Reference" "C3"
			(at -0.6 1.106655 0)
			(unlocked yes)
			(layer "B.SilkS")
			(effects
				(font
					(size 0.762 0.762)
					(thickness 0.2286)
				)
				(justify left bottom mirror)
			)
		)
		(property "Value" "2.2uF_16V_0402"
			(at 0.7365 8.683165 0)
			(unlocked yes)
			(layer "B.SilkS")
			(hide yes)
			(effects
				(font
					(size 0.762 0.762)
					(thickness 0.2286)
				)
				(justify left bottom mirror)
			)
		)
		(sheetname "03-POWER")
		(sheetfile "03-POWER.kicad_sch")
		(duplicate_pad_numbers_are_jumpers no)
		(fp_line
			(start 0.83624 0.73624)
			(end -0.83624 0.73624)
			(stroke
				(width 0.2)
				(type solid)
			)
			(layer "B.SilkS")
		)
		(fp_line
			(start 0.83624 -0.73624)
			(end -0.83624 -0.73624)
			(stroke
				(width 0.2)
				(type solid)
			)
			(layer "B.SilkS")
		)
		(fp_line
			(start 1.03624 0.53624)
			(end -1.03624 0.53624)
			(stroke
				(width 0.2)
				(type solid)
			)
			(layer "B.CrtYd")
		)
		(fp_line
			(start 1.03624 -0.53624)
			(end 1.03624 0.53624)
			(stroke
				(width 0.2)
				(type solid)
			)
			(layer "B.CrtYd")
		)
		(fp_line
			(start 1.03624 -0.53624)
			(end -1.03624 -0.53624)
			(stroke
				(width 0.2)
				(type solid)
			)
			(layer "B.CrtYd")
		)
		(fp_line
			(start -1.03624 -0.53624)
			(end -1.03624 0.53624)
			(stroke
				(width 0.2)
				(type solid)
			)
			(layer "B.CrtYd")
		)
		(fp_line
			(start 1.03624 0.53624)
			(end -1.03624 0.53624)
			(stroke
				(width 0.2)
				(type solid)
			)
			(layer "B.Fab")
		)
		(fp_line
			(start 1.03624 -0.53624)
			(end 1.03624 0.53624)
			(stroke
				(width 0.2)
				(type solid)
			)
			(layer "B.Fab")
		)
		(fp_line
			(start 1.03624 -0.53624)
			(end -1.03624 -0.53624)
			(stroke
				(width 0.2)
				(type solid)
			)
			(layer "B.Fab")
		)
		(fp_line
			(start 0.5 0)
			(end -0.5 0)
			(stroke
				(width 0.1)
				(type solid)
			)
			(layer "B.Fab")
		)
		(fp_line
			(start 0 -0.5)
			(end 0 0.5)
			(stroke
				(width 0.1)
				(type solid)
			)
			(layer "B.Fab")
		)
		(fp_line
			(start -1.03624 -0.53624)
			(end -1.03624 0.53624)
			(stroke
				(width 0.2)
				(type solid)
			)
			(layer "B.Fab")
		)
		(fp_text user "${REFERENCE}"
			(at -0.00001 -0.09602 360)
			(unlocked yes)
			(layer "B.Fab")
			(effects
				(font
					(face "Arial")
					(size 0.63 0.63)
					(thickness 0.1)
				)
				(justify left bottom mirror)
			)
		)
		(pad "1" smd rect
			(at -0.46658 0 180)
			(size 0.73933 0.67248)
			(layers "B.Cu" "B.Mask" "B.Paste")
			(net "P5V_MUN_VCC")
			(solder_mask_margin 0)
			(solder_paste_margin 0)
		)
		(pad "2" smd rect
			(at 0.46657 0 180)
			(size 0.73933 0.67248)
			(layers "B.Cu" "B.Mask" "B.Paste")
			(net "GND")
			(solder_mask_margin 0)
			(solder_paste_margin 0)
		)
	)
	(footprint "Vault:RESC1005X40X25LL05T05"
		(layer "B.Cu")
		(at 112.25573 84.8412 -90)
		(property "Reference" "R57"
			(at -4.7964 -4.692791 90)
			(unlocked yes)
			(layer "B.SilkS")
			(effects
				(font
					(size 0.762 0.762)
					(thickness 0.2286)
				)
				(justify mirror)
			)
		)
		(property "Value" "4.7K_0402"
			(at -3.024391 -2.374035 180)
			(unlocked yes)
			(layer "B.SilkS")
			(hide yes)
			(effects
				(font
					(size 0.762 0.762)
					(thickness 0.2286)
				)
				(justify mirror)
			)
		)
		(sheetname "05-GPS_IMU_SENSORS")
		(sheetfile "05-GPS_IMU_SENSORS.kicad_sch")
		(duplicate_pad_numbers_are_jumpers no)
		(pad "1" smd rect
			(at -0.4 0 180)
			(size 0.45 0.45)
			(layers "B.Cu" "B.Mask" "B.Paste")
			(net "BNO_P3V3")
		)
		(pad "2" smd rect
			(at 0.4 0 180)
			(size 0.45 0.45)
			(layers "B.Cu" "B.Mask" "B.Paste")
			(net "NetR57_2")
		)
	)
	(footprint "Vault:RESC1005X40X25LL05T05"
		(layer "B.Cu")
		(at 113.78072 89.7662)
		(property "Reference" "R53"
			(at 0.86948 1.123069 180)
			(unlocked yes)
			(layer "B.SilkS")
			(effects
				(font
					(size 0.762 0.762)
					(thickness 0.2286)
				)
				(justify mirror)
			)
		)
		(property "Value" "4.7K_0402"
			(at -3.024391 -2.374045 270)
			(unlocked yes)
			(layer "B.SilkS")
			(hide yes)
			(effects
				(font
					(size 0.762 0.762)
					(thickness 0.2286)
				)
				(justify mirror)
			)
		)
		(sheetname "05-GPS_IMU_SENSORS")
		(sheetfile "05-GPS_IMU_SENSORS.kicad_sch")
		(duplicate_pad_numbers_are_jumpers no)
		(pad "1" smd rect
			(at -0.4 0 270)
			(size 0.45 0.45)
			(layers "B.Cu" "B.Mask" "B.Paste")
			(net "NetR53_1")
		)
		(pad "2" smd rect
			(at 0.40001 0 270)
			(size 0.45 0.45)
			(layers "B.Cu" "B.Mask" "B.Paste")
			(net "BNO_P3V3")
		)
	)
	(footprint "Vault:FP-0402-L_1_0_1-W_0_5_0_1-IPC_C"
		(layer "B.Cu")
		(at 228.16036 113.8162)
		(property "Reference" "C92"
			(at -0.13771 -1.704879 0)
			(unlocked yes)
			(layer "B.SilkS")
			(effects
				(font
					(size 0.762 0.762)
					(thickness 0.2286)
				)
				(justify mirror)
			)
		)
		(property "Value" "0.1uF_25V_0402"
			(at -2.465551 -9.839215 270)
			(unlocked yes)
			(layer "B.SilkS")
			(hide yes)
			(effects
				(font
					(size 0.762 0.762)
					(thickness 0.2286)
				)
				(justify mirror)
			)
		)
		(sheetname "09-USBUart_PPSMUX_UARTMUX")
		(sheetfile "09-USBUart_PPSMUX_UARTMUX.kicad_sch")
		(duplicate_pad_numbers_are_jumpers no)
		(fp_line
			(start -0.65606 -0.7)
			(end 0.65607 -0.7)
			(stroke
				(width 0.2)
				(type solid)
			)
			(layer "B.SilkS")
		)
		(fp_line
			(start -0.65606 0.7)
			(end 0.65607 0.7)
			(stroke
				(width 0.2)
				(type solid)
			)
			(layer "B.SilkS")
		)
		(fp_line
			(start -0.75606 -0.4)
			(end 0.75607 -0.4)
			(stroke
				(width 0.2)
				(type solid)
			)
			(layer "B.CrtYd")
		)
		(fp_line
			(start -0.75606 0.4)
			(end -0.75606 -0.4)
			(stroke
				(width 0.2)
				(type solid)
			)
			(layer "B.CrtYd")
		)
		(fp_line
			(start -0.75606 0.4)
			(end 0.75607 0.4)
			(stroke
				(width 0.2)
				(type solid)
			)
			(layer "B.CrtYd")
		)
		(fp_line
			(start 0.75607 0.4)
			(end 0.75607 -0.4)
			(stroke
				(width 0.2)
				(type solid)
			)
			(layer "B.CrtYd")
		)
		(fp_line
			(start -0.75606 -0.4)
			(end 0.75607 -0.4)
			(stroke
				(width 0.2)
				(type solid)
			)
			(layer "B.Fab")
		)
		(fp_line
			(start -0.75606 0.4)
			(end -0.75606 -0.4)
			(stroke
				(width 0.2)
				(type solid)
			)
			(layer "B.Fab")
		)
		(fp_line
			(start -0.75606 0.4)
			(end 0.75607 0.4)
			(stroke
				(width 0.2)
				(type solid)
			)
			(layer "B.Fab")
		)
		(fp_line
			(start -0.5 0)
			(end 0.5 0)
			(stroke
				(width 0.1)
				(type solid)
			)
			(layer "B.Fab")
		)
		(fp_line
			(start 0 0.5)
			(end 0 -0.5)
			(stroke
				(width 0.1)
				(type solid)
			)
			(layer "B.Fab")
		)
		(fp_line
			(start 0.75607 0.4)
			(end 0.75607 -0.4)
			(stroke
				(width 0.2)
				(type solid)
			)
			(layer "B.Fab")
		)
		(fp_text user "${REFERENCE}"
			(at -0.00001 -0.09601 180)
			(unlocked yes)
			(layer "B.Fab")
			(effects
				(font
					(face "Arial")
					(size 0.63 0.63)
					(thickness 0.1)
				)
				(justify left bottom mirror)
			)
		)
		(pad "1" smd rect
			(at -0.36553 0)
			(size 0.58106 0.51213)
			(layers "B.Cu" "B.Mask" "B.Paste")
			(net "NetC92_1")
			(solder_mask_margin 0)
			(solder_paste_margin 0)
		)
		(pad "2" smd rect
			(at 0.36554 0)
			(size 0.58106 0.51213)
			(layers "B.Cu" "B.Mask" "B.Paste")
			(net "GND")
			(solder_mask_margin 0)
			(solder_paste_margin 0)
		)
	)
	(footprint "Capacitors:CAPC1005X06N"
		(layer "B.Cu")
		(at 133.5746 151.7886 90)
		(property "Reference" "C49"
			(at 2.41349 -0.156655 270)
			(unlocked yes)
			(layer "B.SilkS")
			(effects
				(font
					(size 0.762 0.762)
					(thickness 0.2286)
				)
				(justify left bottom mirror)
			)
		)
		(property "Value" "CAP_0402_0.1UF_50V"
			(at -3.382645 0.2921 0)
			(unlocked yes)
			(layer "B.SilkS")
			(hide yes)
			(effects
				(font
					(size 0.762 0.762)
					(thickness 0.2286)
				)
				(justify left bottom mirror)
			)
		)
		(sheetname "04-PCIe_JTAG")
		(sheetfile "04-PCIe_JTAG.kicad_sch")
		(duplicate_pad_numbers_are_jumpers no)
		(pad "1" smd rect
			(at -0.43 0)
			(size 0.64 0.68)
			(layers "B.Cu" "B.Mask" "B.Paste")
			(net "NetC49_1")
		)
		(pad "2" smd rect
			(at 0.43 0)
			(size 0.64 0.68)
			(layers "B.Cu" "B.Mask" "B.Paste")
			(net "PCIE_TX1_N")
		)
	)
	(footprint "Capacitors:CAPC1005X06N"
		(layer "B.Cu")
		(at 128.6724 151.7886 90)
		(property "Reference" "C47"
			(at 2.41349 0.097345 270)
			(unlocked yes)
			(layer "B.SilkS")
			(effects
				(font
					(size 0.762 0.762)
					(thickness 0.2286)
				)
				(justify left bottom mirror)
			)
		)
		(property "Value" "CAP_0402_0.1UF_50V"
			(at -3.382645 0.2921 0)
			(unlocked yes)
			(layer "B.SilkS")
			(hide yes)
			(effects
				(font
					(size 0.762 0.762)
					(thickness 0.2286)
				)
				(justify left bottom mirror)
			)
		)
		(sheetname "04-PCIe_JTAG")
		(sheetfile "04-PCIe_JTAG.kicad_sch")
		(duplicate_pad_numbers_are_jumpers no)
		(pad "1" smd rect
			(at -0.43 0)
			(size 0.64 0.68)
			(layers "B.Cu" "B.Mask" "B.Paste")
			(net "NetC47_1")
		)
		(pad "2" smd rect
			(at 0.43 0)
			(size 0.64 0.68)
			(layers "B.Cu" "B.Mask" "B.Paste")
			(net "PCIE_TX0_N")
		)
	)
	(footprint "Vault:FP-C1005-050-0_05-IPC_A"
		(layer "B.Cu")
		(at 96.5216 67.0162 -90)
		(property "Reference" "C16"
			(at 3.3 0.493345 270)
			(unlocked yes)
			(layer "B.SilkS")
			(effects
				(font
					(size 0.762 0.762)
					(thickness 0.2286)
				)
				(justify left bottom mirror)
			)
		)
		(property "Value" "2.2uF_16V_0402"
			(at 1.941545 14.9177 0)
			(unlocked yes)
			(layer "B.SilkS")
			(hide yes)
			(effects
				(font
					(size 0.762 0.762)
					(thickness 0.2286)
				)
				(justify left bottom mirror)
			)
		)
		(sheetname "03-POWER")
		(sheetfile "03-POWER.kicad_sch")
		(duplicate_pad_numbers_are_jumpers no)
		(fp_line
			(start 0.83624 0.73624)
			(end -0.83624 0.73624)
			(stroke
				(width 0.2)
				(type solid)
			)
			(layer "B.SilkS")
		)
		(fp_line
			(start 0.83624 -0.73624)
			(end -0.83624 -0.73624)
			(stroke
				(width 0.2)
				(type solid)
			)
			(layer "B.SilkS")
		)
		(fp_line
			(start -1.03624 0.53624)
			(end -1.03624 -0.53624)
			(stroke
				(width 0.2)
				(type solid)
			)
			(layer "B.CrtYd")
		)
		(fp_line
			(start 1.03623 0.53624)
			(end -1.03624 0.53624)
			(stroke
				(width 0.2)
				(type solid)
			)
			(layer "B.CrtYd")
		)
		(fp_line
			(start 1.03623 0.53624)
			(end 1.03623 -0.53624)
			(stroke
				(width 0.2)
				(type solid)
			)
			(layer "B.CrtYd")
		)
		(fp_line
			(start 1.03623 -0.53624)
			(end -1.03624 -0.53624)
			(stroke
				(width 0.2)
				(type solid)
			)
			(layer "B.CrtYd")
		)
		(fp_line
			(start -1.03624 0.53624)
			(end -1.03624 -0.53624)
			(stroke
				(width 0.2)
				(type solid)
			)
			(layer "B.Fab")
		)
		(fp_line
			(start 1.03623 0.53624)
			(end -1.03624 0.53624)
			(stroke
				(width 0.2)
				(type solid)
			)
			(layer "B.Fab")
		)
		(fp_line
			(start 1.03623 0.53624)
			(end 1.03623 -0.53624)
			(stroke
				(width 0.2)
				(type solid)
			)
			(layer "B.Fab")
		)
		(fp_line
			(start 0 0.5)
			(end 0 -0.5)
			(stroke
				(width 0.1)
				(type solid)
			)
			(layer "B.Fab")
		)
		(fp_line
			(start 0.5 0)
			(end -0.5 0)
			(stroke
				(width 0.1)
				(type solid)
			)
			(layer "B.Fab")
		)
		(fp_line
			(start 1.03623 -0.53624)
			(end -1.03624 -0.53624)
			(stroke
				(width 0.2)
				(type solid)
			)
			(layer "B.Fab")
		)
		(fp_text user "${REFERENCE}"
			(at -0.00001 -0.09601 90)
			(unlocked yes)
			(layer "B.Fab")
			(effects
				(font
					(face "Arial")
					(size 0.63 0.63)
					(thickness 0.1)
				)
				(justify left bottom mirror)
			)
		)
		(pad "1" smd rect
			(at -0.46658 0 270)
			(size 0.73933 0.67248)
			(layers "B.Cu" "B.Mask" "B.Paste")
			(net "+5.0V")
			(solder_mask_margin 0)
			(solder_paste_margin 0)
		)
		(pad "2" smd rect
			(at 0.46657 0 270)
			(size 0.73933 0.67248)
			(layers "B.Cu" "B.Mask" "B.Paste")
			(net "GND")
			(solder_mask_margin 0)
			(solder_paste_margin 0)
		)
	)
	(footprint "Vault:RESC1005X40X25NL10T10"
		(layer "B.Cu")
		(at 89.9216 54.9162 180)
		(property "Reference" "R59"
			(at 0.2786 1.123069 0)
			(unlocked yes)
			(layer "B.SilkS")
			(effects
				(font
					(size 0.762 0.762)
					(thickness 0.2286)
				)
				(justify mirror)
			)
		)
		(property "Value" "10K_1%_0402"
			(at -2.884671 -8.544305 90)
			(unlocked yes)
			(layer "B.SilkS")
			(hide yes)
			(effects
				(font
					(size 0.762 0.762)
					(thickness 0.2286)
				)
				(justify mirror)
			)
		)
		(sheetname "03-POWER")
		(sheetfile "03-POWER.kicad_sch")
		(duplicate_pad_numbers_are_jumpers no)
		(pad "1" smd rect
			(at -0.425 0 90)
			(size 0.6 0.65)
			(layers "B.Cu" "B.Mask" "B.Paste")
			(net "GND")
		)
		(pad "2" smd rect
			(at 0.425 0 90)
			(size 0.6 0.65)
			(layers "B.Cu" "B.Mask" "B.Paste")
			(net "NetR9_2")
		)
	)
	(footprint "Vault:FP-0402-L_1_0_1-W_0_5_0_1-IPC_C"
		(layer "B.Cu")
		(at 99.7216 66.85066 -90)
		(property "Reference" "C18"
			(at 1.16554 -0.593345 90)
			(unlocked yes)
			(layer "B.SilkS")
			(effects
				(font
					(size 0.762 0.762)
					(thickness 0.2286)
				)
				(justify left bottom mirror)
			)
		)
		(property "Value" "0.1uF_25V_0402"
			(at 4.572625 15.71837 0)
			(unlocked yes)
			(layer "B.SilkS")
			(hide yes)
			(effects
				(font
					(size 0.762 0.762)
					(thickness 0.2286)
				)
				(justify left bottom mirror)
			)
		)
		(sheetname "03-POWER")
		(sheetfile "03-POWER.kicad_sch")
		(duplicate_pad_numbers_are_jumpers no)
		(fp_line
			(start 0.65607 0.7)
			(end -0.65606 0.7)
			(stroke
				(width 0.2)
				(type solid)
			)
			(layer "B.SilkS")
		)
		(fp_line
			(start 0.65607 -0.7)
			(end -0.65606 -0.7)
			(stroke
				(width 0.2)
				(type solid)
			)
			(layer "B.SilkS")
		)
		(fp_line
			(start -0.75606 0.4)
			(end -0.75606 -0.4)
			(stroke
				(width 0.2)
				(type solid)
			)
			(layer "B.CrtYd")
		)
		(fp_line
			(start 0.75607 0.4)
			(end -0.75606 0.4)
			(stroke
				(width 0.2)
				(type solid)
			)
			(layer "B.CrtYd")
		)
		(fp_line
			(start 0.75607 0.4)
			(end 0.75607 -0.4)
			(stroke
				(width 0.2)
				(type solid)
			)
			(layer "B.CrtYd")
		)
		(fp_line
			(start 0.75607 -0.4)
			(end -0.75606 -0.4)
			(stroke
				(width 0.2)
				(type solid)
			)
			(layer "B.CrtYd")
		)
		(fp_line
			(start 0 0.5)
			(end 0 -0.5)
			(stroke
				(width 0.1)
				(type solid)
			)
			(layer "B.Fab")
		)
		(fp_line
			(start -0.75606 0.4)
			(end -0.75606 -0.4)
			(stroke
				(width 0.2)
				(type solid)
			)
			(layer "B.Fab")
		)
		(fp_line
			(start 0.75607 0.4)
			(end -0.75606 0.4)
			(stroke
				(width 0.2)
				(type solid)
			)
			(layer "B.Fab")
		)
		(fp_line
			(start 0.75607 0.4)
			(end 0.75607 -0.4)
			(stroke
				(width 0.2)
				(type solid)
			)
			(layer "B.Fab")
		)
		(fp_line
			(start 0.5 0)
			(end -0.49999 0)
			(stroke
				(width 0.1)
				(type solid)
			)
			(layer "B.Fab")
		)
		(fp_line
			(start 0.75607 -0.4)
			(end -0.75606 -0.4)
			(stroke
				(width 0.2)
				(type solid)
			)
			(layer "B.Fab")
		)
		(fp_text user "${REFERENCE}"
			(at -0.00001 -0.09602 90)
			(unlocked yes)
			(layer "B.Fab")
			(effects
				(font
					(face "Arial")
					(size 0.63 0.63)
					(thickness 0.1)
				)
				(justify left bottom mirror)
			)
		)
		(pad "1" smd rect
			(at -0.36553 0 270)
			(size 0.58106 0.51213)
			(layers "B.Cu" "B.Mask" "B.Paste")
			(net "+5.0V")
			(solder_mask_margin 0)
			(solder_paste_margin 0)
		)
		(pad "2" smd rect
			(at 0.36554 0 270)
			(size 0.58106 0.51213)
			(layers "B.Cu" "B.Mask" "B.Paste")
			(net "GND")
			(solder_mask_margin 0)
			(solder_paste_margin 0)
		)
	)
	(footprint "Vault:RESC1005X40X25LL05T05"
		(layer "B.Cu")
		(at 113.56707 84.98575 180)
		(property "Reference" "R51"
			(at -5.325925 -0.161941 0)
			(unlocked yes)
			(layer "B.SilkS")
			(effects
				(font
					(size 0.762 0.762)
					(thickness 0.2286)
				)
				(justify mirror)
			)
		)
		(property "Value" "4.7K_0402"
			(at 1.612045 -2.262391 0)
			(unlocked yes)
			(layer "B.SilkS")
			(hide yes)
			(effects
				(font
					(size 0.762 0.762)
					(thickness 0.2286)
				)
				(justify mirror)
			)
		)
		(sheetname "05-GPS_IMU_SENSORS")
		(sheetfile "05-GPS_IMU_SENSORS.kicad_sch")
		(duplicate_pad_numbers_are_jumpers no)
		(pad "1" smd rect
			(at -0.4 0 90)
			(size 0.45 0.45)
			(layers "B.Cu" "B.Mask" "B.Paste")
			(net "BNO_P3V3")
		)
		(pad "2" smd rect
			(at 0.4 0 90)
			(size 0.45 0.45)
			(layers "B.Cu" "B.Mask" "B.Paste")
			(net "NetR51_2")
		)
	)
	(footprint "Vault:FP-0603-L_1_6_0_2-W_0_8_0-MFG"
		(layer "B.Cu")
		(at 227.3216 71.6162 180)
		(property "Reference" "C20"
			(at -1.336 0.346345 180)
			(unlocked yes)
			(layer "B.SilkS")
			(effects
				(font
					(size 0.762 0.762)
					(thickness 0.2286)
				)
				(justify left bottom mirror)
			)
		)
		(property "Value" "10uF_16V_0603"
			(at 6.5525 -3.826045 0)
			(unlocked yes)
			(layer "B.SilkS")
			(hide yes)
			(effects
				(font
					(size 0.762 0.762)
					(thickness 0.2286)
				)
				(justify left bottom mirror)
			)
		)
		(sheetname "03-POWER")
		(sheetfile "03-POWER.kicad_sch")
		(duplicate_pad_numbers_are_jumpers no)
		(fp_line
			(start 0.9 0.825)
			(end -0.9 0.825)
			(stroke
				(width 0.2)
				(type solid)
			)
			(layer "B.SilkS")
		)
		(fp_line
			(start 0.9 -0.825)
			(end -0.9 -0.825)
			(stroke
				(width 0.2)
				(type solid)
			)
			(layer "B.SilkS")
		)
		(fp_line
			(start 1.15 0.6)
			(end -1.15 0.6)
			(stroke
				(width 0.2)
				(type solid)
			)
			(layer "B.CrtYd")
		)
		(fp_line
			(start 1.15 -0.6)
			(end 1.15 0.6)
			(stroke
				(width 0.2)
				(type solid)
			)
			(layer "B.CrtYd")
		)
		(fp_line
			(start 1.15 -0.6)
			(end -1.15 -0.6)
			(stroke
				(width 0.2)
				(type solid)
			)
			(layer "B.CrtYd")
		)
		(fp_line
			(start -1.15 -0.6)
			(end -1.15 0.6)
			(stroke
				(width 0.2)
				(type solid)
			)
			(layer "B.CrtYd")
		)
		(fp_line
			(start 1.15 0.6)
			(end -1.15 0.6)
			(stroke
				(width 0.2)
				(type solid)
			)
			(layer "B.Fab")
		)
		(fp_line
			(start 1.15 -0.6)
			(end 1.15 0.6)
			(stroke
				(width 0.2)
				(type solid)
			)
			(layer "B.Fab")
		)
		(fp_line
			(start 1.15 -0.6)
			(end -1.15 -0.6)
			(stroke
				(width 0.2)
				(type solid)
			)
			(layer "B.Fab")
		)
		(fp_line
			(start 0.5 0)
			(end -0.5 0)
			(stroke
				(width 0.1)
				(type solid)
			)
			(layer "B.Fab")
		)
		(fp_line
			(start 0 -0.5)
			(end 0 0.5)
			(stroke
				(width 0.1)
				(type solid)
			)
			(layer "B.Fab")
		)
		(fp_line
			(start -1.15 -0.6)
			(end -1.15 0.6)
			(stroke
				(width 0.2)
				(type solid)
			)
			(layer "B.Fab")
		)
		(fp_text user "${REFERENCE}"
			(at -0.00001 -0.09602 360)
			(unlocked yes)
			(layer "B.Fab")
			(effects
				(font
					(face "Arial")
					(size 0.63 0.63)
					(thickness 0.1)
				)
				(justify left bottom mirror)
			)
		)
		(pad "1" smd rect
			(at -0.7 0 180)
			(size 0.7 0.7)
			(layers "B.Cu" "B.Mask" "B.Paste")
			(net "+3.3V")
			(solder_mask_margin 0)
			(solder_paste_margin 0)
		)
		(pad "2" smd rect
			(at 0.7 0 180)
			(size 0.7 0.7)
			(layers "B.Cu" "B.Mask" "B.Paste")
			(net "GND")
			(solder_mask_margin 0)
			(solder_paste_margin 0)
		)
	)
	(footprint "Vault:FP-RT0402-MFG"
		(layer "B.Cu")
		(at 86.55491 63.6412 90)
		(property "Reference" "R27"
			(at -1.7464 -0.160241 270)
			(unlocked yes)
			(layer "B.SilkS")
			(effects
				(font
					(size 0.762 0.762)
					(thickness 0.2286)
				)
				(justify mirror)
			)
		)
		(property "Value" "160_0.5%_0402"
			(at -3.087871 -2.37404 0)
			(unlocked yes)
			(layer "B.SilkS")
			(hide yes)
			(effects
				(font
					(size 0.762 0.762)
					(thickness 0.2286)
				)
				(justify mirror)
			)
		)
		(sheetname "03-POWER")
		(sheetfile "03-POWER.kicad_sch")
		(duplicate_pad_numbers_are_jumpers no)
		(fp_line
			(start -0.5 -0.711)
			(end 0.5 -0.711)
			(stroke
				(width 0.2)
				(type solid)
			)
			(layer "B.SilkS")
		)
		(fp_line
			(start -0.5 0.7)
			(end 0.5 0.7)
			(stroke
				(width 0.2)
				(type solid)
			)
			(layer "B.SilkS")
		)
		(fp_line
			(start 0.85 -0.4)
			(end 0.85 0.4)
			(stroke
				(width 0.2)
				(type solid)
			)
			(layer "B.CrtYd")
		)
		(fp_line
			(start -0.85 -0.4)
			(end 0.85 -0.4)
			(stroke
				(width 0.2)
				(type solid)
			)
			(layer "B.CrtYd")
		)
		(fp_line
			(start -0.85 -0.4)
			(end -0.85 0.4)
			(stroke
				(width 0.2)
				(type solid)
			)
			(layer "B.CrtYd")
		)
		(fp_line
			(start -0.85 0.4)
			(end 0.85 0.4)
			(stroke
				(width 0.2)
				(type solid)
			)
			(layer "B.CrtYd")
		)
		(fp_line
			(start 0 -0.5)
			(end 0 0.5)
			(stroke
				(width 0.1)
				(type solid)
			)
			(layer "B.Fab")
		)
		(fp_line
			(start 0.85 -0.4)
			(end 0.85 0.4)
			(stroke
				(width 0.2)
				(type solid)
			)
			(layer "B.Fab")
		)
		(fp_line
			(start -0.85 -0.4)
			(end 0.85 -0.4)
			(stroke
				(width 0.2)
				(type solid)
			)
			(layer "B.Fab")
		)
		(fp_line
			(start -0.85 -0.4)
			(end -0.85 0.4)
			(stroke
				(width 0.2)
				(type solid)
			)
			(layer "B.Fab")
		)
		(fp_line
			(start -0.5 0)
			(end 0.5 0)
			(stroke
				(width 0.1)
				(type solid)
			)
			(layer "B.Fab")
		)
		(fp_line
			(start -0.85 0.4)
			(end 0.85 0.4)
			(stroke
				(width 0.2)
				(type solid)
			)
			(layer "B.Fab")
		)
		(fp_text user "${REFERENCE}"
			(at -0.00001 -0.10711 270)
			(unlocked yes)
			(layer "B.Fab")
			(effects
				(font
					(face "Arial")
					(size 0.63 0.63)
					(thickness 0.1)
				)
				(justify left bottom mirror)
			)
		)
		(pad "1" smd rect
			(at -0.5 0 90)
			(size 0.5 0.6)
			(layers "B.Cu" "B.Mask" "B.Paste")
			(net "GND")
			(solder_mask_margin 0)
			(solder_paste_margin 0)
		)
		(pad "2" smd rect
			(at 0.5 0 90)
			(size 0.5 0.6)
			(layers "B.Cu" "B.Mask" "B.Paste")
			(net "NetR26_1")
			(solder_mask_margin 0)
			(solder_paste_margin 0)
		)
	)
	(footprint "Vault:RESC1005X40X25NL05T05"
		(layer "B.Cu")
		(at 222.0216 112.5412 -90)
		(property "Reference" "R125"
			(at -0.2282 -1.173069 270)
			(unlocked yes)
			(layer "B.SilkS")
			(effects
				(font
					(size 0.762 0.762)
					(thickness 0.2032)
				)
				(justify mirror)
			)
		)
		(property "Value" "200_1%_0402"
			(at -2.732271 -8.112675 180)
			(unlocked yes)
			(layer "B.SilkS")
			(hide yes)
			(effects
				(font
					(size 0.762 0.762)
					(thickness 0.2032)
				)
				(justify mirror)
			)
		)
		(sheetname "08-DIPSwitches_I2C")
		(sheetfile "08-DIPSwitches_I2C.kicad_sch")
		(duplicate_pad_numbers_are_jumpers no)
		(pad "1" smd rect
			(at -0.45 0 180)
			(size 0.55 0.55)
			(layers "B.Cu" "B.Mask" "B.Paste")
			(net "NetD24_1")
		)
		(pad "2" smd rect
			(at 0.45 0 180)
			(size 0.55 0.55)
			(layers "B.Cu" "B.Mask" "B.Paste")
			(net "DIP_SW_MACSER_SEL")
		)
	)
	(footprint "Vault:FP-0402-L_1_0_1-W_0_5_0_1-IPC_C"
		(layer "B.Cu")
		(at 198.5216 121.1162 180)
		(property "Reference" "C103"
			(at 0.0968 -1.473069 180)
			(unlocked yes)
			(layer "B.SilkS")
			(effects
				(font
					(size 0.762 0.762)
					(thickness 0.2032)
				)
				(justify mirror)
			)
		)
		(property "Value" "0.1uF_25V_0402"
			(at -2.465551 -9.813815 90)
			(unlocked yes)
			(layer "B.SilkS")
			(hide yes)
			(effects
				(font
					(size 0.762 0.762)
					(thickness 0.2032)
				)
				(justify mirror)
			)
		)
		(sheetname "10-M2_GPS")
		(sheetfile "10-M2_GPS.kicad_sch")
		(duplicate_pad_numbers_are_jumpers no)
		(fp_line
			(start 0.65607 0.7)
			(end -0.65607 0.7)
			(stroke
				(width 0.2)
				(type solid)
			)
			(layer "B.SilkS")
		)
		(fp_line
			(start 0.65607 -0.7)
			(end -0.65607 -0.7)
			(stroke
				(width 0.2)
				(type solid)
			)
			(layer "B.SilkS")
		)
		(fp_line
			(start 0.75607 0.4)
			(end -0.75607 0.4)
			(stroke
				(width 0.2)
				(type solid)
			)
			(layer "B.CrtYd")
		)
		(fp_line
			(start 0.75607 -0.4)
			(end 0.75607 0.4)
			(stroke
				(width 0.2)
				(type solid)
			)
			(layer "B.CrtYd")
		)
		(fp_line
			(start 0.75607 -0.4)
			(end -0.75607 -0.4)
			(stroke
				(width 0.2)
				(type solid)
			)
			(layer "B.CrtYd")
		)
		(fp_line
			(start -0.75607 -0.4)
			(end -0.75607 0.4)
			(stroke
				(width 0.2)
				(type solid)
			)
			(layer "B.CrtYd")
		)
		(fp_line
			(start 0.75607 0.4)
			(end -0.75607 0.4)
			(stroke
				(width 0.2)
				(type solid)
			)
			(layer "B.Fab")
		)
		(fp_line
			(start 0.75607 -0.4)
			(end 0.75607 0.4)
			(stroke
				(width 0.2)
				(type solid)
			)
			(layer "B.Fab")
		)
		(fp_line
			(start 0.75607 -0.4)
			(end -0.75607 -0.4)
			(stroke
				(width 0.2)
				(type solid)
			)
			(layer "B.Fab")
		)
		(fp_line
			(start 0.5 0)
			(end -0.5 0)
			(stroke
				(width 0.1)
				(type solid)
			)
			(layer "B.Fab")
		)
		(fp_line
			(start 0 -0.5)
			(end 0 0.5)
			(stroke
				(width 0.1)
				(type solid)
			)
			(layer "B.Fab")
		)
		(fp_line
			(start -0.75607 -0.4)
			(end -0.75607 0.4)
			(stroke
				(width 0.2)
				(type solid)
			)
			(layer "B.Fab")
		)
		(fp_text user "${REFERENCE}"
			(at -0.00001 -0.09602 360)
			(unlocked yes)
			(layer "B.Fab")
			(effects
				(font
					(face "Arial")
					(size 0.63 0.63)
					(thickness 0.1)
				)
				(justify left bottom mirror)
			)
		)
		(pad "1" smd rect
			(at -0.36554 0 180)
			(size 0.58106 0.51213)
			(layers "B.Cu" "B.Mask" "B.Paste")
			(net "GNSS2_P3V3")
			(solder_mask_margin 0)
			(solder_paste_margin 0)
		)
		(pad "2" smd rect
			(at 0.36554 0 180)
			(size 0.58106 0.51213)
			(layers "B.Cu" "B.Mask" "B.Paste")
			(net "GND")
			(solder_mask_margin 0)
			(solder_paste_margin 0)
		)
	)
	(footprint "Vault:FP-0402-L_1_0_1-W_0_5_0_1-IPC_C"
		(layer "B.Cu")
		(at 198.4216 119.2162 180)
		(property "Reference" "C101"
			(at 2.4032 -0.526931 0)
			(unlocked yes)
			(layer "B.SilkS")
			(effects
				(font
					(size 0.762 0.762)
					(thickness 0.2032)
				)
				(justify mirror)
			)
		)
		(property "Value" "0.1uF_25V_0402"
			(at -2.465551 -9.813805 90)
			(unlocked yes)
			(layer "B.SilkS")
			(hide yes)
			(effects
				(font
					(size 0.762 0.762)
					(thickness 0.2032)
				)
				(justify mirror)
			)
		)
		(sheetname "10-M2_GPS")
		(sheetfile "10-M2_GPS.kicad_sch")
		(duplicate_pad_numbers_are_jumpers no)
		(fp_line
			(start 0.65607 0.7)
			(end -0.65606 0.7)
			(stroke
				(width 0.2)
				(type solid)
			)
			(layer "B.SilkS")
		)
		(fp_line
			(start 0.65607 -0.7)
			(end -0.65606 -0.7)
			(stroke
				(width 0.2)
				(type solid)
			)
			(layer "B.SilkS")
		)
		(fp_line
			(start 0.75607 0.4)
			(end -0.75606 0.4)
			(stroke
				(width 0.2)
				(type solid)
			)
			(layer "B.CrtYd")
		)
		(fp_line
			(start 0.75607 -0.4)
			(end 0.75607 0.4)
			(stroke
				(width 0.2)
				(type solid)
			)
			(layer "B.CrtYd")
		)
		(fp_line
			(start 0.75607 -0.4)
			(end -0.75606 -0.4)
			(stroke
				(width 0.2)
				(type solid)
			)
			(layer "B.CrtYd")
		)
		(fp_line
			(start -0.75606 -0.4)
			(end -0.75606 0.4)
			(stroke
				(width 0.2)
				(type solid)
			)
			(layer "B.CrtYd")
		)
		(fp_line
			(start 0.75607 0.4)
			(end -0.75606 0.4)
			(stroke
				(width 0.2)
				(type solid)
			)
			(layer "B.Fab")
		)
		(fp_line
			(start 0.75607 -0.4)
			(end 0.75607 0.4)
			(stroke
				(width 0.2)
				(type solid)
			)
			(layer "B.Fab")
		)
		(fp_line
			(start 0.75607 -0.4)
			(end -0.75606 -0.4)
			(stroke
				(width 0.2)
				(type solid)
			)
			(layer "B.Fab")
		)
		(fp_line
			(start 0.5 0)
			(end -0.5 0)
			(stroke
				(width 0.1)
				(type solid)
			)
			(layer "B.Fab")
		)
		(fp_line
			(start 0 -0.5)
			(end 0 0.5)
			(stroke
				(width 0.1)
				(type solid)
			)
			(layer "B.Fab")
		)
		(fp_line
			(start -0.75606 -0.4)
			(end -0.75606 0.4)
			(stroke
				(width 0.2)
				(type solid)
			)
			(layer "B.Fab")
		)
		(fp_text user "${REFERENCE}"
			(at -0.00001 -0.09602 360)
			(unlocked yes)
			(layer "B.Fab")
			(effects
				(font
					(face "Arial")
					(size 0.63 0.63)
					(thickness 0.1)
				)
				(justify left bottom mirror)
			)
		)
		(pad "1" smd rect
			(at -0.36553 0 180)
			(size 0.58106 0.51213)
			(layers "B.Cu" "B.Mask" "B.Paste")
			(net "GNSS2_P3V3")
			(solder_mask_margin 0)
			(solder_paste_margin 0)
		)
		(pad "2" smd rect
			(at 0.36554 0 180)
			(size 0.58106 0.51213)
			(layers "B.Cu" "B.Mask" "B.Paste")
			(net "GND")
			(solder_mask_margin 0)
			(solder_paste_margin 0)
		)
	)
	(footprint "Vault:RESC1005X40X25NL10T10"
		(layer "B.Cu")
		(at 78.5216 130.0162)
		(property "Reference" "R17"
			(at 1.5714 0.126921 0)
			(unlocked yes)
			(layer "B.SilkS")
			(effects
				(font
					(size 0.762 0.762)
					(thickness 0.2286)
				)
				(justify mirror)
			)
		)
		(property "Value" "4.7K_1%_0402"
			(at -2.884671 -3.186595 270)
			(unlocked yes)
			(layer "B.SilkS")
			(hide yes)
			(effects
				(font
					(size 0.762 0.762)
					(thickness 0.2286)
				)
				(justify mirror)
			)
		)
		(sheetname "01-USER_IO")
		(sheetfile "01-USER_IO.kicad_sch")
		(duplicate_pad_numbers_are_jumpers no)
		(pad "1" smd rect
			(at -0.425 0 270)
			(size 0.6 0.65)
			(layers "B.Cu" "B.Mask" "B.Paste")
			(net "+3.3V")
		)
		(pad "2" smd rect
			(at 0.425 0 270)
			(size 0.6 0.65)
			(layers "B.Cu" "B.Mask" "B.Paste")
			(net "ANT3_IO_OUT")
		)
	)
	(footprint "Capacitors:CAPC1005X06N"
		(layer "B.Cu")
		(at 127.5802 151.7886 90)
		(property "Reference" "C46"
			(at 2.41349 -0.563055 270)
			(unlocked yes)
			(layer "B.SilkS")
			(effects
				(font
					(size 0.762 0.762)
					(thickness 0.2286)
				)
				(justify left bottom mirror)
			)
		)
		(property "Value" "CAP_0402_0.1UF_50V"
			(at -3.382645 0.2921 0)
			(unlocked yes)
			(layer "B.SilkS")
			(hide yes)
			(effects
				(font
					(size 0.762 0.762)
					(thickness 0.2286)
				)
				(justify left bottom mirror)
			)
		)
		(sheetname "04-PCIe_JTAG")
		(sheetfile "04-PCIe_JTAG.kicad_sch")
		(duplicate_pad_numbers_are_jumpers no)
		(pad "1" smd rect
			(at -0.43 0)
			(size 0.64 0.68)
			(layers "B.Cu" "B.Mask" "B.Paste")
			(net "NetC46_1")
		)
		(pad "2" smd rect
			(at 0.43 0)
			(size 0.64 0.68)
			(layers "B.Cu" "B.Mask" "B.Paste")
			(net "PCIE_TX0_P")
		)
	)
	(footprint "Vault:RESC1608X55X30NL15T15"
		(layer "B.Cu")
		(at 79.4216 50.9662 180)
		(property "Reference" "R35"
			(at -3.0714 -0.176931 0)
			(unlocked yes)
			(layer "B.SilkS")
			(effects
				(font
					(size 0.762 0.762)
					(thickness 0.2286)
				)
				(justify mirror)
			)
		)
		(property "Value" "200 OHM"
			(at -2.935471 -4.78626 90)
			(unlocked yes)
			(layer "B.SilkS")
			(hide yes)
			(effects
				(font
					(size 0.762 0.762)
					(thickness 0.2286)
				)
				(justify mirror)
			)
		)
		(sheetname "02-USER_IO_STATUS")
		(sheetfile "02-USER_IO_STATUS.kicad_sch")
		(duplicate_pad_numbers_are_jumpers no)
		(pad "1" smd rect
			(at -0.675 0 90)
			(size 0.95 0.8)
			(layers "B.Cu" "B.Mask" "B.Paste")
			(net "LED1")
		)
		(pad "2" smd rect
			(at 0.675 0 90)
			(size 0.95 0.8)
			(layers "B.Cu" "B.Mask" "B.Paste")
			(net "NetD3_1")
		)
	)
	(footprint "Vault:RESC1005X40X25ML05T05"
		(layer "B.Cu")
		(at 216.13831 124.41792)
		(property "Reference" "R180"
			(at -0.07071 -1.074789 0)
			(unlocked yes)
			(layer "B.SilkS")
			(effects
				(font
					(size 0.762 0.762)
					(thickness 0.254)
				)
				(justify mirror)
			)
		)
		(property "Value" "10K_5%_0402"
			(at -2.884671 -8.061875 270)
			(unlocked yes)
			(layer "B.SilkS")
			(hide yes)
			(effects
				(font
					(size 0.762 0.762)
					(thickness 0.254)
				)
				(justify mirror)
			)
		)
		(sheetname "09-USBUart_PPSMUX_UARTMUX")
		(sheetfile "09-USBUart_PPSMUX_UARTMUX.kicad_sch")
		(duplicate_pad_numbers_are_jumpers no)
		(pad "1" smd rect
			(at -0.5 0 270)
			(size 0.65 0.65)
			(layers "B.Cu" "B.Mask" "B.Paste")
			(net "NetR180_1")
		)
		(pad "2" smd rect
			(at 0.5 0 270)
			(size 0.65 0.65)
			(layers "B.Cu" "B.Mask" "B.Paste")
			(net "+5.0V")
		)
	)
	(footprint "Vault:FP-0402-L_1_0_1-W_0_5_0_1-IPC_C"
		(layer "B.Cu")
		(at 217.7466 121.4412)
		(property "Reference" "C105"
			(at 0.6718 -1.398079 0)
			(unlocked yes)
			(layer "B.SilkS")
			(effects
				(font
					(size 0.762 0.762)
					(thickness 0.2032)
				)
				(justify mirror)
			)
		)
		(property "Value" "0.1uF_25V_0402"
			(at -2.465551 -9.813815 270)
			(unlocked yes)
			(layer "B.SilkS")
			(hide yes)
			(effects
				(font
					(size 0.762 0.762)
					(thickness 0.2032)
				)
				(justify mirror)
			)
		)
		(sheetname "10-M2_GPS")
		(sheetfile "10-M2_GPS.kicad_sch")
		(duplicate_pad_numbers_are_jumpers no)
		(fp_line
			(start -0.65607 -0.7)
			(end 0.65607 -0.7)
			(stroke
				(width 0.2)
				(type solid)
			)
			(layer "B.SilkS")
		)
		(fp_line
			(start -0.65607 0.7)
			(end 0.65607 0.7)
			(stroke
				(width 0.2)
				(type solid)
			)
			(layer "B.SilkS")
		)
		(fp_line
			(start -0.75607 -0.4)
			(end 0.75607 -0.4)
			(stroke
				(width 0.2)
				(type solid)
			)
			(layer "B.CrtYd")
		)
		(fp_line
			(start -0.75607 0.4)
			(end -0.75607 -0.4)
			(stroke
				(width 0.2)
				(type solid)
			)
			(layer "B.CrtYd")
		)
		(fp_line
			(start -0.75607 0.4)
			(end 0.75607 0.4)
			(stroke
				(width 0.2)
				(type solid)
			)
			(layer "B.CrtYd")
		)
		(fp_line
			(start 0.75607 0.4)
			(end 0.75607 -0.4)
			(stroke
				(width 0.2)
				(type solid)
			)
			(layer "B.CrtYd")
		)
		(fp_line
			(start -0.75607 -0.4)
			(end 0.75607 -0.4)
			(stroke
				(width 0.2)
				(type solid)
			)
			(layer "B.Fab")
		)
		(fp_line
			(start -0.75607 0.4)
			(end -0.75607 -0.4)
			(stroke
				(width 0.2)
				(type solid)
			)
			(layer "B.Fab")
		)
		(fp_line
			(start -0.75607 0.4)
			(end 0.75607 0.4)
			(stroke
				(width 0.2)
				(type solid)
			)
			(layer "B.Fab")
		)
		(fp_line
			(start -0.5 0)
			(end 0.5 0)
			(stroke
				(width 0.1)
				(type solid)
			)
			(layer "B.Fab")
		)
		(fp_line
			(start 0 0.5)
			(end 0 -0.5)
			(stroke
				(width 0.1)
				(type solid)
			)
			(layer "B.Fab")
		)
		(fp_line
			(start 0.75607 0.4)
			(end 0.75607 -0.4)
			(stroke
				(width 0.2)
				(type solid)
			)
			(layer "B.Fab")
		)
		(fp_text user "${REFERENCE}"
			(at -0.00002 -0.09602 180)
			(unlocked yes)
			(layer "B.Fab")
			(effects
				(font
					(face "Arial")
					(size 0.63 0.63)
					(thickness 0.1)
				)
				(justify left bottom mirror)
			)
		)
		(pad "1" smd rect
			(at -0.36554 0)
			(size 0.58106 0.51213)
			(layers "B.Cu" "B.Mask" "B.Paste")
			(net "GNSS2_P3V3")
			(solder_mask_margin 0)
			(solder_paste_margin 0)
		)
		(pad "2" smd rect
			(at 0.36554 0)
			(size 0.58106 0.51213)
			(layers "B.Cu" "B.Mask" "B.Paste")
			(net "GND")
			(solder_mask_margin 0)
			(solder_paste_margin 0)
		)
	)
	(footprint "Vault:RESC1005X40X25ML10T10"
		(layer "B.Cu")
		(at 180.2716 90.1662 180)
		(property "Reference" "R61"
			(at 0.278605 -0.976921 0)
			(unlocked yes)
			(layer "B.SilkS")
			(effects
				(font
					(size 0.762 0.762)
					(thickness 0.2286)
				)
				(justify mirror)
			)
		)
		(property "Value" "2.2K_0.5%_0402"
			(at -2.732271 -9.534615 90)
			(unlocked yes)
			(layer "B.SilkS")
			(hide yes)
			(effects
				(font
					(size 0.762 0.762)
					(thickness 0.2286)
				)
				(justify mirror)
			)
		)
		(sheetname "03-POWER")
		(sheetfile "03-POWER.kicad_sch")
		(duplicate_pad_numbers_are_jumpers no)
		(pad "1" smd rect
			(at -0.475 0 90)
			(size 0.7 0.75)
			(layers "B.Cu" "B.Mask" "B.Paste")
			(net "NetR61_1")
		)
		(pad "2" smd rect
			(at 0.475 0 90)
			(size 0.7 0.75)
			(layers "B.Cu" "B.Mask" "B.Paste")
			(net "NetR61_2")
		)
	)
	(footprint "Vault:RESC1005X40X25LL05T10"
		(layer "B.Cu")
		(at 83.65354 94.32502)
		(property "Reference" "R186"
			(at 2.244598 -2.75504 270)
			(unlocked yes)
			(layer "B.SilkS")
			(effects
				(font
					(size 1.524 1.524)
					(thickness 0.254)
				)
				(justify mirror)
			)
		)
		(property "Value" "10K_1%_0402"
			(at -2.606802 -8.087315 270)
			(unlocked yes)
			(layer "B.SilkS")
			(hide yes)
			(effects
				(font
					(size 1.524 1.524)
					(thickness 0.254)
				)
				(justify mirror)
			)
		)
		(sheetname "05-GPS_IMU_SENSORS")
		(sheetfile "05-GPS_IMU_SENSORS.kicad_sch")
		(duplicate_pad_numbers_are_jumpers no)
		(pad "1" smd rect
			(at -0.375 0 270)
			(size 0.45 0.5)
			(layers "B.Cu" "B.Mask" "B.Paste")
			(net "+3.3V")
		)
		(pad "2" smd rect
			(at 0.375 0 270)
			(size 0.45 0.5)
			(layers "B.Cu" "B.Mask" "B.Paste")
			(net "MAC_FREQ_CTRL")
		)
	)
	(footprint "Vault:FP-0402-L_1_0_1-W_0_5_0_1-IPC_C"
		(layer "B.Cu")
		(at 168.1216 114.2912)
		(property "Reference" "C70"
			(at -0.3286 1.651931 0)
			(unlocked yes)
			(layer "B.SilkS")
			(effects
				(font
					(size 0.762 0.762)
					(thickness 0.2286)
				)
				(justify mirror)
			)
		)
		(property "Value" "0.1uF_25V_0402"
			(at -2.744961 -9.813805 270)
			(unlocked yes)
			(layer "B.SilkS")
			(hide yes)
			(effects
				(font
					(size 0.762 0.762)
					(thickness 0.2286)
				)
				(justify mirror)
			)
		)
		(sheetname "08-DIPSwitches_I2C")
		(sheetfile "08-DIPSwitches_I2C.kicad_sch")
		(duplicate_pad_numbers_are_jumpers no)
		(fp_line
			(start -0.65607 -0.7)
			(end 0.65606 -0.7)
			(stroke
				(width 0.2)
				(type solid)
			)
			(layer "B.SilkS")
		)
		(fp_line
			(start -0.65607 0.7)
			(end 0.65606 0.7)
			(stroke
				(width 0.2)
				(type solid)
			)
			(layer "B.SilkS")
		)
		(fp_line
			(start -0.75607 -0.4)
			(end 0.75606 -0.4)
			(stroke
				(width 0.2)
				(type solid)
			)
			(layer "B.CrtYd")
		)
		(fp_line
			(start -0.75607 0.4)
			(end -0.75607 -0.4)
			(stroke
				(width 0.2)
				(type solid)
			)
			(layer "B.CrtYd")
		)
		(fp_line
			(start -0.75607 0.4)
			(end 0.75606 0.4)
			(stroke
				(width 0.2)
				(type solid)
			)
			(layer "B.CrtYd")
		)
		(fp_line
			(start 0.75606 0.4)
			(end 0.75606 -0.4)
			(stroke
				(width 0.2)
				(type solid)
			)
			(layer "B.CrtYd")
		)
		(fp_line
			(start -0.75607 -0.4)
			(end 0.75606 -0.4)
			(stroke
				(width 0.2)
				(type solid)
			)
			(layer "B.Fab")
		)
		(fp_line
			(start -0.75607 0.4)
			(end -0.75607 -0.4)
			(stroke
				(width 0.2)
				(type solid)
			)
			(layer "B.Fab")
		)
		(fp_line
			(start -0.75607 0.4)
			(end 0.75606 0.4)
			(stroke
				(width 0.2)
				(type solid)
			)
			(layer "B.Fab")
		)
		(fp_line
			(start -0.5 0)
			(end 0.5 0)
			(stroke
				(width 0.1)
				(type solid)
			)
			(layer "B.Fab")
		)
		(fp_line
			(start 0 0.5)
			(end 0 -0.5)
			(stroke
				(width 0.1)
				(type solid)
			)
			(layer "B.Fab")
		)
		(fp_line
			(start 0.75606 0.4)
			(end 0.75606 -0.4)
			(stroke
				(width 0.2)
				(type solid)
			)
			(layer "B.Fab")
		)
		(fp_text user "${REFERENCE}"
			(at -0.00002 -0.09601 180)
			(unlocked yes)
			(layer "B.Fab")
			(effects
				(font
					(face "Arial")
					(size 0.63 0.63)
					(thickness 0.1)
				)
				(justify left bottom mirror)
			)
		)
		(pad "1" smd rect
			(at -0.36554 0)
			(size 0.58106 0.51213)
			(layers "B.Cu" "B.Mask" "B.Paste")
			(net "+3.3V")
			(solder_mask_margin 0)
			(solder_paste_margin 0)
		)
		(pad "2" smd rect
			(at 0.36553 0)
			(size 0.58106 0.51213)
			(layers "B.Cu" "B.Mask" "B.Paste")
			(net "GND")
			(solder_mask_margin 0)
			(solder_paste_margin 0)
		)
	)
	(footprint "Vault:CAPC1005X56X25NL10T15"
		(layer "B.Cu")
		(at 114.90572 84.8412 -90)
		(property "Reference" "C67"
			(at 0.2036 -2.542811 90)
			(unlocked yes)
			(layer "B.SilkS")
			(effects
				(font
					(size 0.762 0.762)
					(thickness 0.2286)
				)
				(justify mirror)
			)
		)
		(property "Value" "0.1uF_25V_0402"
			(at 2.069025 -2.567191 90)
			(unlocked yes)
			(layer "B.SilkS")
			(hide yes)
			(effects
				(font
					(size 0.762 0.762)
					(thickness 0.2286)
				)
				(justify mirror)
			)
		)
		(sheetname "05-GPS_IMU_SENSORS")
		(sheetfile "05-GPS_IMU_SENSORS.kicad_sch")
		(duplicate_pad_numbers_are_jumpers no)
		(pad "1" smd rect
			(at -0.44 0 180)
			(size 0.64 0.68)
			(layers "B.Cu" "B.Mask" "B.Paste")
			(net "GND")
		)
		(pad "2" smd rect
			(at 0.44 0 180)
			(size 0.64 0.68)
			(layers "B.Cu" "B.Mask" "B.Paste")
			(net "BNO_P3V3")
		)
	)
	(footprint "Vault:FP-0402-L_1_0_1-W_0_5_0_1-IPC_C"
		(layer "B.Cu")
		(at 120.3216 79.1162 -90)
		(property "Reference" "C107"
			(at -0.2032 -1.573069 270)
			(unlocked yes)
			(layer "B.SilkS")
			(effects
				(font
					(size 0.762 0.762)
					(thickness 0.2032)
				)
				(justify mirror)
			)
		)
		(property "Value" "0.1uF_25V_0402"
			(at -2.465551 -9.813815 180)
			(unlocked yes)
			(layer "B.SilkS")
			(hide yes)
			(effects
				(font
					(size 0.762 0.762)
					(thickness 0.2032)
				)
				(justify mirror)
			)
		)
		(sheetname "11-M2_RCB_MUX")
		(sheetfile "11-M2_RCB_MUX.kicad_sch")
		(duplicate_pad_numbers_are_jumpers no)
		(fp_line
			(start 0.65607 0.7)
			(end -0.65607 0.7)
			(stroke
				(width 0.2)
				(type solid)
			)
			(layer "B.SilkS")
		)
		(fp_line
			(start 0.65607 -0.7)
			(end -0.65607 -0.7)
			(stroke
				(width 0.2)
				(type solid)
			)
			(layer "B.SilkS")
		)
		(fp_line
			(start -0.75607 0.4)
			(end -0.75607 -0.4)
			(stroke
				(width 0.2)
				(type solid)
			)
			(layer "B.CrtYd")
		)
		(fp_line
			(start 0.75607 0.4)
			(end -0.75607 0.4)
			(stroke
				(width 0.2)
				(type solid)
			)
			(layer "B.CrtYd")
		)
		(fp_line
			(start 0.75607 0.4)
			(end 0.75607 -0.4)
			(stroke
				(width 0.2)
				(type solid)
			)
			(layer "B.CrtYd")
		)
		(fp_line
			(start 0.75607 -0.4)
			(end -0.75607 -0.4)
			(stroke
				(width 0.2)
				(type solid)
			)
			(layer "B.CrtYd")
		)
		(fp_line
			(start 0 0.5)
			(end 0 -0.5)
			(stroke
				(width 0.1)
				(type solid)
			)
			(layer "B.Fab")
		)
		(fp_line
			(start -0.75607 0.4)
			(end -0.75607 -0.4)
			(stroke
				(width 0.2)
				(type solid)
			)
			(layer "B.Fab")
		)
		(fp_line
			(start 0.75607 0.4)
			(end -0.75607 0.4)
			(stroke
				(width 0.2)
				(type solid)
			)
			(layer "B.Fab")
		)
		(fp_line
			(start 0.75607 0.4)
			(end 0.75607 -0.4)
			(stroke
				(width 0.2)
				(type solid)
			)
			(layer "B.Fab")
		)
		(fp_line
			(start 0.5 0)
			(end -0.5 0)
			(stroke
				(width 0.1)
				(type solid)
			)
			(layer "B.Fab")
		)
		(fp_line
			(start 0.75607 -0.4)
			(end -0.75607 -0.4)
			(stroke
				(width 0.2)
				(type solid)
			)
			(layer "B.Fab")
		)
		(fp_text user "${REFERENCE}"
			(at -0.00001 -0.09602 90)
			(unlocked yes)
			(layer "B.Fab")
			(effects
				(font
					(face "Arial")
					(size 0.63 0.63)
					(thickness 0.1)
				)
				(justify left bottom mirror)
			)
		)
		(pad "1" smd rect
			(at -0.36554 0 270)
			(size 0.58106 0.51213)
			(layers "B.Cu" "B.Mask" "B.Paste")
			(net "+3.3V")
			(solder_mask_margin 0)
			(solder_paste_margin 0)
		)
		(pad "2" smd rect
			(at 0.36554 0 270)
			(size 0.58106 0.51213)
			(layers "B.Cu" "B.Mask" "B.Paste")
			(net "GND")
			(solder_mask_margin 0)
			(solder_paste_margin 0)
		)
	)
	(footprint "Vault:RESC1005X40X25NL05T05"
		(layer "B.Cu")
		(at 219.9216 116.5412 -90)
		(property "Reference" "R112"
			(at 0.2782 1.273079 90)
			(unlocked yes)
			(layer "B.SilkS")
			(effects
				(font
					(size 0.762 0.762)
					(thickness 0.2032)
				)
				(justify mirror)
			)
		)
		(property "Value" "200_1%_0402"
			(at -2.732271 -8.112675 180)
			(unlocked yes)
			(layer "B.SilkS")
			(hide yes)
			(effects
				(font
					(size 0.762 0.762)
					(thickness 0.2032)
				)
				(justify mirror)
			)
		)
		(sheetname "08-DIPSwitches_I2C")
		(sheetfile "08-DIPSwitches_I2C.kicad_sch")
		(duplicate_pad_numbers_are_jumpers no)
		(pad "1" smd rect
			(at -0.45 0 180)
			(size 0.55 0.55)
			(layers "B.Cu" "B.Mask" "B.Paste")
			(net "NetD21_1")
		)
		(pad "2" smd rect
			(at 0.45 0 180)
			(size 0.55 0.55)
			(layers "B.Cu" "B.Mask" "B.Paste")
			(net "DIP_SW_UART_SEL")
		)
	)
	(footprint "Vault:RESC1005X40X25LL05T10"
		(layer "B.Cu")
		(at 220.4216 107.6162)
		(property "Reference" "R88"
			(at -2.2286 0.126921 0)
			(unlocked yes)
			(layer "B.SilkS")
			(effects
				(font
					(size 0.762 0.762)
					(thickness 0.2286)
				)
				(justify mirror)
			)
		)
		(property "Value" "10K_1%_0402"
			(at -2.579871 -8.061915 270)
			(unlocked yes)
			(layer "B.SilkS")
			(hide yes)
			(effects
				(font
					(size 0.762 0.762)
					(thickness 0.2286)
				)
				(justify mirror)
			)
		)
		(sheetname "08-DIPSwitches_I2C")
		(sheetfile "08-DIPSwitches_I2C.kicad_sch")
		(duplicate_pad_numbers_are_jumpers no)
		(pad "1" smd rect
			(at -0.375 0 270)
			(size 0.45 0.5)
			(layers "B.Cu" "B.Mask" "B.Paste")
			(net "+3.3V")
		)
		(pad "2" smd rect
			(at 0.375 0 270)
			(size 0.45 0.5)
			(layers "B.Cu" "B.Mask" "B.Paste")
			(net "DIP_SW_PPS_SEL")
		)
	)
	(footprint "Vault:FP-0603-L_1_6_0_2-W_0_8_0-MFG"
		(layer "B.Cu")
		(at 98.0216 66.9162 -90)
		(property "Reference" "C15"
			(at 1.3 -0.493345 90)
			(unlocked yes)
			(layer "B.SilkS")
			(effects
				(font
					(size 0.762 0.762)
					(thickness 0.2286)
				)
				(justify left bottom mirror)
			)
		)
		(property "Value" "10uF_16V_0603"
			(at 0.683315 9.5697 0)
			(unlocked yes)
			(layer "B.SilkS")
			(hide yes)
			(effects
				(font
					(size 0.762 0.762)
					(thickness 0.2286)
				)
				(justify left bottom mirror)
			)
		)
		(sheetname "03-POWER")
		(sheetfile "03-POWER.kicad_sch")
		(duplicate_pad_numbers_are_jumpers no)
		(fp_line
			(start 0.9 0.825)
			(end -0.9 0.825)
			(stroke
				(width 0.2)
				(type solid)
			)
			(layer "B.SilkS")
		)
		(fp_line
			(start 0.9 -0.825)
			(end -0.9 -0.825)
			(stroke
				(width 0.2)
				(type solid)
			)
			(layer "B.SilkS")
		)
		(fp_line
			(start -1.15 0.6)
			(end -1.15 -0.6)
			(stroke
				(width 0.2)
				(type solid)
			)
			(layer "B.CrtYd")
		)
		(fp_line
			(start 1.15 0.6)
			(end -1.15 0.6)
			(stroke
				(width 0.2)
				(type solid)
			)
			(layer "B.CrtYd")
		)
		(fp_line
			(start 1.15 0.6)
			(end 1.15 -0.6)
			(stroke
				(width 0.2)
				(type solid)
			)
			(layer "B.CrtYd")
		)
		(fp_line
			(start 1.15 -0.6)
			(end -1.15 -0.6)
			(stroke
				(width 0.2)
				(type solid)
			)
			(layer "B.CrtYd")
		)
		(fp_line
			(start -1.15 0.6)
			(end -1.15 -0.6)
			(stroke
				(width 0.2)
				(type solid)
			)
			(layer "B.Fab")
		)
		(fp_line
			(start 1.15 0.6)
			(end -1.15 0.6)
			(stroke
				(width 0.2)
				(type solid)
			)
			(layer "B.Fab")
		)
		(fp_line
			(start 1.15 0.6)
			(end 1.15 -0.6)
			(stroke
				(width 0.2)
				(type solid)
			)
			(layer "B.Fab")
		)
		(fp_line
			(start 0 0.5)
			(end 0 -0.5)
			(stroke
				(width 0.1)
				(type solid)
			)
			(layer "B.Fab")
		)
		(fp_line
			(start 0.5 0)
			(end -0.5 0)
			(stroke
				(width 0.1)
				(type solid)
			)
			(layer "B.Fab")
		)
		(fp_line
			(start 1.15 -0.6)
			(end -1.15 -0.6)
			(stroke
				(width 0.2)
				(type solid)
			)
			(layer "B.Fab")
		)
		(fp_text user "${REFERENCE}"
			(at -0.00001 -0.09602 90)
			(unlocked yes)
			(layer "B.Fab")
			(effects
				(font
					(face "Arial")
					(size 0.63 0.63)
					(thickness 0.1)
				)
				(justify left bottom mirror)
			)
		)
		(pad "1" smd rect
			(at -0.7 0 270)
			(size 0.7 0.7)
			(layers "B.Cu" "B.Mask" "B.Paste")
			(net "+5.0V")
			(solder_mask_margin 0)
			(solder_paste_margin 0)
		)
		(pad "2" smd rect
			(at 0.7 0 270)
			(size 0.7 0.7)
			(layers "B.Cu" "B.Mask" "B.Paste")
			(net "GND")
			(solder_mask_margin 0)
			(solder_paste_margin 0)
		)
	)
	(footprint "Vault:RESC1005X40X25LL05T10"
		(layer "B.Cu")
		(at 220.8216 105.1162)
		(property "Reference" "R89"
			(at 1.8714 0.026921 0)
			(unlocked yes)
			(layer "B.SilkS")
			(effects
				(font
					(size 0.762 0.762)
					(thickness 0.2286)
				)
				(justify mirror)
			)
		)
		(property "Value" "10K_1%_0402"
			(at -2.579871 -8.061915 270)
			(unlocked yes)
			(layer "B.SilkS")
			(hide yes)
			(effects
				(font
					(size 0.762 0.762)
					(thickness 0.2286)
				)
				(justify mirror)
			)
		)
		(sheetname "08-DIPSwitches_I2C")
		(sheetfile "08-DIPSwitches_I2C.kicad_sch")
		(duplicate_pad_numbers_are_jumpers no)
		(pad "1" smd rect
			(at -0.375 0 270)
			(size 0.45 0.5)
			(layers "B.Cu" "B.Mask" "B.Paste")
			(net "+3.3V")
		)
		(pad "2" smd rect
			(at 0.375 0 270)
			(size 0.45 0.5)
			(layers "B.Cu" "B.Mask" "B.Paste")
			(net "DIP_SW_MACSER_SEL")
		)
	)
	(footprint "Vault:RESC1005X40X25LL05T05"
		(layer "B.Cu")
		(at 168.15457 94.6162 90)
		(property "Reference" "R79"
			(at 0.2286 0.940099 270)
			(unlocked yes)
			(layer "B.SilkS")
			(effects
				(font
					(size 0.762 0.762)
					(thickness 0.2286)
				)
				(justify mirror)
			)
		)
		(property "Value" "0_1%_0402"
			(at -2.579871 -6.66536 0)
			(unlocked yes)
			(layer "B.SilkS")
			(hide yes)
			(effects
				(font
					(size 0.762 0.762)
					(thickness 0.2286)
				)
				(justify mirror)
			)
		)
		(sheetname "03-POWER")
		(sheetfile "03-POWER.kicad_sch")
		(duplicate_pad_numbers_are_jumpers no)
		(pad "1" smd rect
			(at -0.4 0)
			(size 0.45 0.45)
			(layers "B.Cu" "B.Mask" "B.Paste")
			(net "NetR79_1")
		)
		(pad "2" smd rect
			(at 0.4 0)
			(size 0.45 0.45)
			(layers "B.Cu" "B.Mask" "B.Paste")
			(net "GND")
		)
	)
	(footprint "Vault:RESC1005X40X25LL05T05"
		(layer "B.Cu")
		(at 83.5116 66.12847)
		(property "Reference" "R66"
			(at -0.4186 -0.985339 0)
			(unlocked yes)
			(layer "B.SilkS")
			(effects
				(font
					(size 0.762 0.762)
					(thickness 0.2286)
				)
				(justify mirror)
			)
		)
		(property "Value" "0_1%_0402"
			(at -2.579871 -6.66537 270)
			(unlocked yes)
			(layer "B.SilkS")
			(hide yes)
			(effects
				(font
					(size 0.762 0.762)
					(thickness 0.2286)
				)
				(justify mirror)
			)
		)
		(sheetname "03-POWER")
		(sheetfile "03-POWER.kicad_sch")
		(duplicate_pad_numbers_are_jumpers no)
		(pad "1" smd rect
			(at -0.4 0 270)
			(size 0.45 0.45)
			(layers "B.Cu" "B.Mask" "B.Paste")
			(net "NetR66_1")
		)
		(pad "2" smd rect
			(at 0.4 0 270)
			(size 0.45 0.45)
			(layers "B.Cu" "B.Mask" "B.Paste")
			(net "GND")
		)
	)
	(footprint "Vault:FP-0402-L_1_0_1-W_0_5_0_1-IPC_C"
		(layer "B.Cu")
		(at 153.5216 129.7162 180)
		(property "Reference" "C95"
			(at 0.2286 1.455439 0)
			(unlocked yes)
			(layer "B.SilkS")
			(effects
				(font
					(size 0.762 0.762)
					(thickness 0.2286)
				)
				(justify mirror)
			)
		)
		(property "Value" "0.1uF_25V_0402"
			(at -2.465551 -9.839215 90)
			(unlocked yes)
			(layer "B.SilkS")
			(hide yes)
			(effects
				(font
					(size 0.762 0.762)
					(thickness 0.2286)
				)
				(justify mirror)
			)
		)
		(sheetname "09-USBUart_PPSMUX_UARTMUX")
		(sheetfile "09-USBUart_PPSMUX_UARTMUX.kicad_sch")
		(duplicate_pad_numbers_are_jumpers no)
		(fp_line
			(start 0.65607 0.7)
			(end -0.65607 0.7)
			(stroke
				(width 0.2)
				(type solid)
			)
			(layer "B.SilkS")
		)
		(fp_line
			(start 0.65607 -0.7)
			(end -0.65607 -0.7)
			(stroke
				(width 0.2)
				(type solid)
			)
			(layer "B.SilkS")
		)
		(fp_line
			(start 0.75607 0.4)
			(end -0.75607 0.4)
			(stroke
				(width 0.2)
				(type solid)
			)
			(layer "B.CrtYd")
		)
		(fp_line
			(start 0.75607 -0.4)
			(end 0.75607 0.4)
			(stroke
				(width 0.2)
				(type solid)
			)
			(layer "B.CrtYd")
		)
		(fp_line
			(start 0.75607 -0.4)
			(end -0.75607 -0.4)
			(stroke
				(width 0.2)
				(type solid)
			)
			(layer "B.CrtYd")
		)
		(fp_line
			(start -0.75607 -0.4)
			(end -0.75607 0.4)
			(stroke
				(width 0.2)
				(type solid)
			)
			(layer "B.CrtYd")
		)
		(fp_line
			(start 0.75607 0.4)
			(end -0.75607 0.4)
			(stroke
				(width 0.2)
				(type solid)
			)
			(layer "B.Fab")
		)
		(fp_line
			(start 0.75607 -0.4)
			(end 0.75607 0.4)
			(stroke
				(width 0.2)
				(type solid)
			)
			(layer "B.Fab")
		)
		(fp_line
			(start 0.75607 -0.4)
			(end -0.75607 -0.4)
			(stroke
				(width 0.2)
				(type solid)
			)
			(layer "B.Fab")
		)
		(fp_line
			(start 0.5 0)
			(end -0.5 0)
			(stroke
				(width 0.1)
				(type solid)
			)
			(layer "B.Fab")
		)
		(fp_line
			(start 0 -0.5)
			(end 0 0.5)
			(stroke
				(width 0.1)
				(type solid)
			)
			(layer "B.Fab")
		)
		(fp_line
			(start -0.75607 -0.4)
			(end -0.75607 0.4)
			(stroke
				(width 0.2)
				(type solid)
			)
			(layer "B.Fab")
		)
		(fp_text user "${REFERENCE}"
			(at -0.00001 -0.09602 360)
			(unlocked yes)
			(layer "B.Fab")
			(effects
				(font
					(face "Arial")
					(size 0.63 0.63)
					(thickness 0.1)
				)
				(justify left bottom mirror)
			)
		)
		(pad "1" smd rect
			(at -0.36554 0 180)
			(size 0.58106 0.51213)
			(layers "B.Cu" "B.Mask" "B.Paste")
			(net "GNSS2_P3V3")
			(solder_mask_margin 0)
			(solder_paste_margin 0)
		)
		(pad "2" smd rect
			(at 0.36554 0 180)
			(size 0.58106 0.51213)
			(layers "B.Cu" "B.Mask" "B.Paste")
			(net "GND")
			(solder_mask_margin 0)
			(solder_paste_margin 0)
		)
	)
	(footprint "Vault:RESC1005X40X25LL05T05"
		(layer "B.Cu")
		(at 225.37414 75.80021 90)
		(property "Reference" "R62"
			(at -0.0286 -1.573069 90)
			(unlocked yes)
			(layer "B.SilkS")
			(effects
				(font
					(size 0.762 0.762)
					(thickness 0.2286)
				)
				(justify mirror)
			)
		)
		(property "Value" "0_1%_0402"
			(at -2.579871 -6.66536 0)
			(unlocked yes)
			(layer "B.SilkS")
			(hide yes)
			(effects
				(font
					(size 0.762 0.762)
					(thickness 0.2286)
				)
				(justify mirror)
			)
		)
		(sheetname "03-POWER")
		(sheetfile "03-POWER.kicad_sch")
		(duplicate_pad_numbers_are_jumpers no)
		(pad "1" smd rect
			(at -0.4 0)
			(size 0.45 0.45)
			(layers "B.Cu" "B.Mask" "B.Paste")
			(net "NetR62_1")
		)
		(pad "2" smd rect
			(at 0.4 0)
			(size 0.45 0.45)
			(layers "B.Cu" "B.Mask" "B.Paste")
			(net "GND")
		)
	)
	(footprint "Vault:RESC1005X40X25NL10T10"
		(layer "B.Cu")
		(at 177.8867 81.69562 180)
		(property "Reference" "R70"
			(at 2.3937 -0.047511 0)
			(unlocked yes)
			(layer "B.SilkS")
			(effects
				(font
					(size 0.762 0.762)
					(thickness 0.2286)
				)
				(justify mirror)
			)
		)
		(property "Value" "4.7K_1%_0402"
			(at -2.783071 -8.468145 90)
			(unlocked yes)
			(layer "B.SilkS")
			(hide yes)
			(effects
				(font
					(size 0.762 0.762)
					(thickness 0.2286)
				)
				(justify mirror)
			)
		)
		(sheetname "03-POWER")
		(sheetfile "03-POWER.kicad_sch")
		(duplicate_pad_numbers_are_jumpers no)
		(pad "1" smd rect
			(at -0.425 0 90)
			(size 0.6 0.65)
			(layers "B.Cu" "B.Mask" "B.Paste")
			(net "NetR70_1")
		)
		(pad "2" smd rect
			(at 0.425 0 90)
			(size 0.6 0.65)
			(layers "B.Cu" "B.Mask" "B.Paste")
			(net "+12V")
		)
	)
	(footprint "Vault:RESC1005X35X25LL10T10"
		(layer "B.Cu")
		(at 174.3466 88.1162 180)
		(property "Reference" "R68"
			(at 1.0536 1.173079 0)
			(unlocked yes)
			(layer "B.SilkS")
			(effects
				(font
					(size 0.762 0.762)
					(thickness 0.2286)
				)
				(justify mirror)
			)
		)
		(property "Value" "2K_0.5%_0402"
			(at -2.452831 -6.538405 90)
			(unlocked yes)
			(layer "B.SilkS")
			(hide yes)
			(effects
				(font
					(size 0.762 0.762)
					(thickness 0.2286)
				)
				(justify mirror)
			)
		)
		(sheetname "03-POWER")
		(sheetfile "03-POWER.kicad_sch")
		(duplicate_pad_numbers_are_jumpers no)
		(pad "1" smd rect
			(at -0.375 0 90)
			(size 0.5 0.55)
			(layers "B.Cu" "B.Mask" "B.Paste")
			(net "NetR67_2")
		)
		(pad "2" smd rect
			(at 0.375 0 90)
			(size 0.5 0.55)
			(layers "B.Cu" "B.Mask" "B.Paste")
			(net "P3V3_SENSE")
		)
	)
	(footprint "Vault:CAPC1005X56X25NL10T15"
		(layer "B.Cu")
		(at 170.23267 91.0162)
		(property "Reference" "C66"
			(at 0.0786 -2.067801 180)
			(unlocked yes)
			(layer "B.SilkS")
			(effects
				(font
					(size 0.762 0.762)
					(thickness 0.2286)
				)
				(justify mirror)
			)
		)
		(property "Value" "0.1uF_25V_0402"
			(at 2.069035 -2.567191 180)
			(unlocked yes)
			(layer "B.SilkS")
			(hide yes)
			(effects
				(font
					(size 0.762 0.762)
					(thickness 0.2286)
				)
				(justify mirror)
			)
		)
		(sheetname "03-POWER")
		(sheetfile "03-POWER.kicad_sch")
		(duplicate_pad_numbers_are_jumpers no)
		(pad "1" smd rect
			(at -0.44 0 270)
			(size 0.64 0.68)
			(layers "B.Cu" "B.Mask" "B.Paste")
			(net "GND")
		)
		(pad "2" smd rect
			(at 0.44 0 270)
			(size 0.64 0.68)
			(layers "B.Cu" "B.Mask" "B.Paste")
			(net "+3.3V")
		)
	)
	(footprint "Vault:RESC1005X40X25NL05T05"
		(layer "B.Cu")
		(at 221.7216 102.3162 180)
		(property "Reference" "R178"
			(at -2.2968 -0.326921 0)
			(unlocked yes)
			(layer "B.SilkS")
			(effects
				(font
					(size 0.762 0.762)
					(thickness 0.2032)
				)
				(justify mirror)
			)
		)
		(property "Value" "200_1%_0402"
			(at -2.732271 -8.112675 90)
			(unlocked yes)
			(layer "B.SilkS")
			(hide yes)
			(effects
				(font
					(size 0.762 0.762)
					(thickness 0.2032)
				)
				(justify mirror)
			)
		)
		(sheetname "08-DIPSwitches_I2C")
		(sheetfile "08-DIPSwitches_I2C.kicad_sch")
		(duplicate_pad_numbers_are_jumpers no)
		(pad "1" smd rect
			(at -0.45 0 90)
			(size 0.55 0.55)
			(layers "B.Cu" "B.Mask" "B.Paste")
			(net "NetD12_1")
		)
		(pad "2" smd rect
			(at 0.45 0 90)
			(size 0.55 0.55)
			(layers "B.Cu" "B.Mask" "B.Paste")
			(net "DIP_SW_GPS2_SEL")
		)
	)
	(footprint "Vault:FP-MK212BG-MFG"
		(layer "B.Cu")
		(at 109.72193 73.1686 180)
		(property "Reference" "C58"
			(at -1.39967 1.159055 0)
			(unlocked yes)
			(layer "B.SilkS")
			(effects
				(font
					(size 0.762 0.762)
					(thickness 0.2286)
				)
				(justify left bottom mirror)
			)
		)
		(property "Value" "10uF"
			(at -1.5875 -5.233445 0)
			(unlocked yes)
			(layer "B.SilkS")
			(hide yes)
			(effects
				(font
					(size 0.762 0.762)
					(thickness 0.2286)
				)
				(justify left bottom mirror)
			)
		)
		(sheetname "05-GPS_IMU_SENSORS")
		(sheetfile "05-GPS_IMU_SENSORS.kicad_sch")
		(duplicate_pad_numbers_are_jumpers no)
		(fp_line
			(start 0.125 0.725)
			(end -0.125 0.725)
			(stroke
				(width 0.2)
				(type solid)
			)
			(layer "B.SilkS")
		)
		(fp_line
			(start 0.125 -0.725)
			(end -0.125 -0.725)
			(stroke
				(width 0.2)
				(type solid)
			)
			(layer "B.SilkS")
		)
		(fp_line
			(start 1.6 0.825)
			(end -1.6 0.825)
			(stroke
				(width 0.2)
				(type solid)
			)
			(layer "B.CrtYd")
		)
		(fp_line
			(start 1.6 -0.825)
			(end 1.6 0.825)
			(stroke
				(width 0.2)
				(type solid)
			)
			(layer "B.CrtYd")
		)
		(fp_line
			(start 1.6 -0.825)
			(end -1.6 -0.825)
			(stroke
				(width 0.2)
				(type solid)
			)
			(layer "B.CrtYd")
		)
		(fp_line
			(start -1.6 -0.825)
			(end -1.6 0.825)
			(stroke
				(width 0.2)
				(type solid)
			)
			(layer "B.CrtYd")
		)
		(fp_line
			(start 1.6 0.825)
			(end -1.6 0.825)
			(stroke
				(width 0.2)
				(type solid)
			)
			(layer "B.Fab")
		)
		(fp_line
			(start 1.6 -0.825)
			(end 1.6 0.825)
			(stroke
				(width 0.2)
				(type solid)
			)
			(layer "B.Fab")
		)
		(fp_line
			(start 1.6 -0.825)
			(end -1.6 -0.825)
			(stroke
				(width 0.2)
				(type solid)
			)
			(layer "B.Fab")
		)
		(fp_line
			(start 0.5 0)
			(end -0.5 0)
			(stroke
				(width 0.1)
				(type solid)
			)
			(layer "B.Fab")
		)
		(fp_line
			(start 0 -0.5)
			(end 0 0.5)
			(stroke
				(width 0.1)
				(type solid)
			)
			(layer "B.Fab")
		)
		(fp_line
			(start -1.6 -0.825)
			(end -1.6 0.825)
			(stroke
				(width 0.2)
				(type solid)
			)
			(layer "B.Fab")
		)
		(fp_text user "${REFERENCE}"
			(at -0.00001 -0.09601 360)
			(unlocked yes)
			(layer "B.Fab")
			(effects
				(font
					(face "Arial")
					(size 0.63 0.63)
					(thickness 0.1)
				)
				(justify left bottom mirror)
			)
		)
		(pad "1" smd rect
			(at -1 0 180)
			(size 1 1.25)
			(layers "B.Cu" "B.Mask" "B.Paste")
			(net "+3.3V")
			(solder_mask_margin 0)
			(solder_paste_margin 0)
		)
		(pad "2" smd rect
			(at 1 0 180)
			(size 1 1.25)
			(layers "B.Cu" "B.Mask" "B.Paste")
			(net "GND")
			(solder_mask_margin 0)
			(solder_paste_margin 0)
		)
	)
	(footprint "Vault:FP-RT0402-MFG"
		(layer "B.Cu")
		(at 176.3216 88.0162 180)
		(property "Reference" "R67"
			(at 0.3286 -1.626921 0)
			(unlocked yes)
			(layer "B.SilkS")
			(effects
				(font
					(size 0.762 0.762)
					(thickness 0.2286)
				)
				(justify mirror)
			)
		)
		(property "Value" "88.7K_0.5%_0402"
			(at -2.452831 -6.538405 90)
			(unlocked yes)
			(layer "B.SilkS")
			(hide yes)
			(effects
				(font
					(size 0.762 0.762)
					(thickness 0.2286)
				)
				(justify mirror)
			)
		)
		(sheetname "03-POWER")
		(sheetfile "03-POWER.kicad_sch")
		(duplicate_pad_numbers_are_jumpers no)
		(fp_line
			(start 0.5 0.7)
			(end -0.5 0.7)
			(stroke
				(width 0.2)
				(type solid)
			)
			(layer "B.SilkS")
		)
		(fp_line
			(start 0.5 -0.711)
			(end -0.5 -0.711)
			(stroke
				(width 0.2)
				(type solid)
			)
			(layer "B.SilkS")
		)
		(fp_line
			(start 0.85 0.4)
			(end -0.85 0.4)
			(stroke
				(width 0.2)
				(type solid)
			)
			(layer "B.CrtYd")
		)
		(fp_line
			(start 0.85 -0.4)
			(end 0.85 0.4)
			(stroke
				(width 0.2)
				(type solid)
			)
			(layer "B.CrtYd")
		)
		(fp_line
			(start 0.85 -0.4)
			(end -0.85 -0.4)
			(stroke
				(width 0.2)
				(type solid)
			)
			(layer "B.CrtYd")
		)
		(fp_line
			(start -0.85 -0.4)
			(end -0.85 0.4)
			(stroke
				(width 0.2)
				(type solid)
			)
			(layer "B.CrtYd")
		)
		(fp_line
			(start 0.85 0.4)
			(end -0.85 0.4)
			(stroke
				(width 0.2)
				(type solid)
			)
			(layer "B.Fab")
		)
		(fp_line
			(start 0.85 -0.4)
			(end 0.85 0.4)
			(stroke
				(width 0.2)
				(type solid)
			)
			(layer "B.Fab")
		)
		(fp_line
			(start 0.85 -0.4)
			(end -0.85 -0.4)
			(stroke
				(width 0.2)
				(type solid)
			)
			(layer "B.Fab")
		)
		(fp_line
			(start 0.5 0)
			(end -0.5 0)
			(stroke
				(width 0.1)
				(type solid)
			)
			(layer "B.Fab")
		)
		(fp_line
			(start 0 -0.5)
			(end 0 0.5)
			(stroke
				(width 0.1)
				(type solid)
			)
			(layer "B.Fab")
		)
		(fp_line
			(start -0.85 -0.4)
			(end -0.85 0.4)
			(stroke
				(width 0.2)
				(type solid)
			)
			(layer "B.Fab")
		)
		(fp_text user "${REFERENCE}"
			(at -0.00001 -0.09602 360)
			(unlocked yes)
			(layer "B.Fab")
			(effects
				(font
					(face "Arial")
					(size 0.63 0.63)
					(thickness 0.1)
				)
				(justify left bottom mirror)
			)
		)
		(pad "1" smd rect
			(at -0.5 0 180)
			(size 0.5 0.6)
			(layers "B.Cu" "B.Mask" "B.Paste")
			(net "P3V3_MUN_FB")
			(solder_mask_margin 0)
			(solder_paste_margin 0)
		)
		(pad "2" smd rect
			(at 0.5 0 180)
			(size 0.5 0.6)
			(layers "B.Cu" "B.Mask" "B.Paste")
			(net "NetR67_2")
			(solder_mask_margin 0)
			(solder_paste_margin 0)
		)
	)
	(footprint "Vault:RESC1005X40X25LL05T05"
		(layer "B.Cu")
		(at 83.6216 92.9162)
		(property "Reference" "R48"
			(at -0.1714 1.473069 180)
			(unlocked yes)
			(layer "B.SilkS")
			(effects
				(font
					(size 0.762 0.762)
					(thickness 0.2286)
				)
				(justify mirror)
			)
		)
		(property "Value" "DNI_0_1%_0402"
			(at -2.579871 -6.66536 270)
			(unlocked yes)
			(layer "B.SilkS")
			(hide yes)
			(effects
				(font
					(size 0.762 0.762)
					(thickness 0.2286)
				)
				(justify mirror)
			)
		)
		(sheetname "05-GPS_IMU_SENSORS")
		(sheetfile "05-GPS_IMU_SENSORS.kicad_sch")
		(duplicate_pad_numbers_are_jumpers no)
		(pad "1" smd rect
			(at -0.4 0 270)
			(size 0.45 0.45)
			(layers "B.Cu" "B.Mask" "B.Paste")
			(net "NetP1_5")
		)
		(pad "2" smd rect
			(at 0.4 0 270)
			(size 0.45 0.45)
			(layers "B.Cu" "B.Mask" "B.Paste")
			(net "MAC_FREQ_CTRL")
		)
	)
	(footprint "Vault:RESC1005X40X25LL05T05"
		(layer "B.Cu")
		(at 166.88457 94.6162 90)
		(property "Reference" "R80"
			(at -0.1286 -1.136039 90)
			(unlocked yes)
			(layer "B.SilkS")
			(effects
				(font
					(size 0.762 0.762)
					(thickness 0.2286)
				)
				(justify mirror)
			)
		)
		(property "Value" "0_1%_0402"
			(at -2.579871 -6.66536 0)
			(unlocked yes)
			(layer "B.SilkS")
			(hide yes)
			(effects
				(font
					(size 0.762 0.762)
					(thickness 0.2286)
				)
				(justify mirror)
			)
		)
		(sheetname "03-POWER")
		(sheetfile "03-POWER.kicad_sch")
		(duplicate_pad_numbers_are_jumpers no)
		(pad "1" smd rect
			(at -0.4 0)
			(size 0.45 0.45)
			(layers "B.Cu" "B.Mask" "B.Paste")
			(net "NetR80_1")
		)
		(pad "2" smd rect
			(at 0.4 0)
			(size 0.45 0.45)
			(layers "B.Cu" "B.Mask" "B.Paste")
			(net "+3.3V")
		)
	)
	(footprint "Resistors:RESC1608X50N"
		(layer "B.Cu")
		(at 145.9216 124.6162)
		(property "Reference" "R22"
			(at 1.06 -0.906655 0)
			(unlocked yes)
			(layer "B.SilkS")
			(effects
				(font
					(size 0.762 0.762)
					(thickness 0.2286)
				)
				(justify left bottom mirror)
			)
		)
		(property "Value" "ERJ-3EKF4701V"
			(at 0.4445 3.636645 0)
			(unlocked yes)
			(layer "B.SilkS")
			(hide yes)
			(effects
				(font
					(size 0.762 0.762)
					(thickness 0.2286)
				)
				(justify left bottom mirror)
			)
		)
		(sheetname "04-PCIe_JTAG")
		(sheetfile "04-PCIe_JTAG.kicad_sch")
		(duplicate_pad_numbers_are_jumpers no)
		(fp_line
			(start 0 0.5)
			(end 0 -0.5)
			(stroke
				(width 0.1524)
				(type solid)
			)
			(layer "B.SilkS")
		)
		(pad "1" smd rect
			(at -0.69 0 270)
			(size 1 0.72)
			(layers "B.Cu" "B.Mask" "B.Paste")
			(net "PCIE_PERST")
		)
		(pad "2" smd rect
			(at 0.69 0 270)
			(size 1 0.72)
			(layers "B.Cu" "B.Mask" "B.Paste")
			(net "+3.3V")
		)
	)
	(footprint "Vault:RESC1005X40X25LL05T05"
		(layer "B.Cu")
		(at 179.7216 81.9162 180)
		(property "Reference" "R69"
			(at -1.7968 -0.026921 0)
			(unlocked yes)
			(layer "B.SilkS")
			(effects
				(font
					(size 0.762 0.762)
					(thickness 0.2032)
				)
				(justify mirror)
			)
		)
		(property "Value" "0_1%_0402"
			(at -2.579871 -6.63996 90)
			(unlocked yes)
			(layer "B.SilkS")
			(hide yes)
			(effects
				(font
					(size 0.762 0.762)
					(thickness 0.2032)
				)
				(justify mirror)
			)
		)
		(sheetname "03-POWER")
		(sheetfile "03-POWER.kicad_sch")
		(duplicate_pad_numbers_are_jumpers no)
		(pad "1" smd rect
			(at -0.4 0 90)
			(size 0.45 0.45)
			(layers "B.Cu" "B.Mask" "B.Paste")
			(net "+12V")
		)
		(pad "2" smd rect
			(at 0.4 0 90)
			(size 0.45 0.45)
			(layers "B.Cu" "B.Mask" "B.Paste")
			(net "NetR69_2")
		)
	)
	(footprint "LotusSound:IC_TPS2116"
		(layer "B.Cu")
		(at 207.7266 124.8862 180)
		(property "Reference" "U32"
			(at 9.18034 -6.934171 0)
			(unlocked yes)
			(layer "B.SilkS")
			(hide yes)
			(effects
				(font
					(size 0.762 0.762)
					(thickness 0.2032)
				)
				(justify mirror)
			)
		)
		(property "Value" "TPS2116DRLR"
			(at 15.033155 -12.638271 0)
			(unlocked yes)
			(layer "B.SilkS")
			(hide yes)
			(effects
				(font
					(size 0.762 0.762)
					(thickness 0.2032)
				)
				(justify mirror)
			)
		)
		(sheetname "09-USBUart_PPSMUX_UARTMUX")
		(sheetfile "09-USBUart_PPSMUX_UARTMUX.kicad_sch")
		(duplicate_pad_numbers_are_jumpers no)
		(fp_line
			(start 0.6 1.23)
			(end -0.6 1.23)
			(stroke
				(width 0.127)
				(type solid)
			)
			(layer "B.SilkS")
		)
		(fp_line
			(start 0.6 -1.23)
			(end -0.6 -1.23)
			(stroke
				(width 0.127)
				(type solid)
			)
			(layer "B.SilkS")
		)
		(fp_circle
			(center -1.6 0.75)
			(end -1.6 0.85)
			(stroke
				(width 0.2)
				(type solid)
			)
			(fill no)
			(layer "B.SilkS")
		)
		(pad "1" smd roundrect
			(at -0.735 0.75 180)
			(size 0.66 0.32)
			(layers "B.Cu" "B.Mask" "B.Paste")
			(roundrect_rratio 0.125)
			(net "GND")
		)
		(pad "2" smd roundrect
			(at -0.735 0.25 180)
			(size 0.66 0.32)
			(layers "B.Cu" "B.Mask" "B.Paste")
			(roundrect_rratio 0.125)
			(net "GNSS2_P3V3")
		)
		(pad "3" smd roundrect
			(at -0.735 -0.25 180)
			(size 0.66 0.32)
			(layers "B.Cu" "B.Mask" "B.Paste")
			(roundrect_rratio 0.125)
			(net "+3.3V")
		)
		(pad "4" smd roundrect
			(at -0.735 -0.75 180)
			(size 0.66 0.32)
			(layers "B.Cu" "B.Mask" "B.Paste")
			(roundrect_rratio 0.125)
			(net "NetR49_1")
		)
		(pad "5" smd roundrect
			(at 0.735 -0.75 180)
			(size 0.66 0.32)
			(layers "B.Cu" "B.Mask" "B.Paste")
			(roundrect_rratio 0.125)
			(net "+3.3V")
		)
		(pad "6" smd roundrect
			(at 0.735 -0.25 180)
			(size 0.66 0.32)
			(layers "B.Cu" "B.Mask" "B.Paste")
			(roundrect_rratio 0.125)
			(net "FTDI_P3V3")
		)
		(pad "7" smd roundrect
			(at 0.735 0.25 180)
			(size 0.66 0.32)
			(layers "B.Cu" "B.Mask" "B.Paste")
			(roundrect_rratio 0.125)
			(net "GNSS2_P3V3")
		)
		(pad "8" smd roundrect
			(at 0.735 0.75 180)
			(size 0.66 0.32)
			(layers "B.Cu" "B.Mask" "B.Paste")
			(roundrect_rratio 0.125)
		)
	)
	(footprint "Vault:RESC1608X55X30NL15T15"
		(layer "B.Cu")
		(at 79.4216 56.2162 180)
		(property "Reference" "R39"
			(at -2.4714 -0.026931 0)
			(unlocked yes)
			(layer "B.SilkS")
			(effects
				(font
					(size 0.762 0.762)
					(thickness 0.2286)
				)
				(justify mirror)
			)
		)
		(property "Value" "200 OHM"
			(at -2.935471 -4.78626 90)
			(unlocked yes)
			(layer "B.SilkS")
			(hide yes)
			(effects
				(font
					(size 0.762 0.762)
					(thickness 0.2286)
				)
				(justify mirror)
			)
		)
		(sheetname "02-USER_IO_STATUS")
		(sheetfile "02-USER_IO_STATUS.kicad_sch")
		(duplicate_pad_numbers_are_jumpers no)
		(pad "1" smd rect
			(at -0.675 0 90)
			(size 0.95 0.8)
			(layers "B.Cu" "B.Mask" "B.Paste")
			(net "LED4")
		)
		(pad "2" smd rect
			(at 0.675 0 90)
			(size 0.95 0.8)
			(layers "B.Cu" "B.Mask" "B.Paste")
			(net "NetD11_1")
		)
	)
	(footprint "Vault:RESC1005X40X25LL05T05"
		(layer "B.Cu")
		(at 112.58072 85.9662 180)
		(property "Reference" "R58"
			(at 0.23052 -6.523069 180)
			(unlocked yes)
			(layer "B.SilkS")
			(effects
				(font
					(size 0.762 0.762)
					(thickness 0.2286)
				)
				(justify mirror)
			)
		)
		(property "Value" "4.7K_0402"
			(at -3.024401 -2.374035 90)
			(unlocked yes)
			(layer "B.SilkS")
			(hide yes)
			(effects
				(font
					(size 0.762 0.762)
					(thickness 0.2286)
				)
				(justify mirror)
			)
		)
		(sheetname "05-GPS_IMU_SENSORS")
		(sheetfile "05-GPS_IMU_SENSORS.kicad_sch")
		(duplicate_pad_numbers_are_jumpers no)
		(pad "1" smd rect
			(at -0.4 0 90)
			(size 0.45 0.45)
			(layers "B.Cu" "B.Mask" "B.Paste")
			(net "BNO_P3V3")
		)
		(pad "2" smd rect
			(at 0.4 0 90)
			(size 0.45 0.45)
			(layers "B.Cu" "B.Mask" "B.Paste")
			(net "NetR58_2")
		)
	)
	(footprint "Vault:RESC1005X40X25LL05T10"
		(layer "B.Cu")
		(at 221.9216 100.1162 90)
		(property "Reference" "R140"
			(at 0.2032 1.073069 270)
			(unlocked yes)
			(layer "B.SilkS")
			(effects
				(font
					(size 0.762 0.762)
					(thickness 0.2032)
				)
				(justify mirror)
			)
		)
		(property "Value" "10K_1%_0402"
			(at -2.579871 -8.036515 0)
			(unlocked yes)
			(layer "B.SilkS")
			(hide yes)
			(effects
				(font
					(size 0.762 0.762)
					(thickness 0.2032)
				)
				(justify mirror)
			)
		)
		(sheetname "08-DIPSwitches_I2C")
		(sheetfile "08-DIPSwitches_I2C.kicad_sch")
		(duplicate_pad_numbers_are_jumpers no)
		(pad "1" smd rect
			(at -0.375 0)
			(size 0.45 0.5)
			(layers "B.Cu" "B.Mask" "B.Paste")
			(net "+3.3V")
		)
		(pad "2" smd rect
			(at 0.375 0)
			(size 0.45 0.5)
			(layers "B.Cu" "B.Mask" "B.Paste")
			(net "DIP_SW_GPS2_SEL")
		)
	)
	(footprint "Vault:FP-711AT-MFG"
		(layer "B.Cu")
		(at 221.8933 126.23428)
		(property "Reference" "U33"
			(at 0.27272 -1.591149 0)
			(unlocked yes)
			(layer "B.SilkS")
			(effects
				(font
					(size 0.762 0.762)
					(thickness 0.254)
				)
				(justify mirror)
			)
		)
		(property "Value" "NCP176AMX330TCG"
			(at 10.067525 -2.579871 180)
			(unlocked yes)
			(layer "B.SilkS")
			(hide yes)
			(effects
				(font
					(size 0.762 0.762)
					(thickness 0.254)
				)
				(justify mirror)
			)
		)
		(sheetname "09-USBUart_PPSMUX_UARTMUX")
		(sheetfile "09-USBUart_PPSMUX_UARTMUX.kicad_sch")
		(duplicate_pad_numbers_are_jumpers no)
		(fp_line
			(start -0.625 0.925)
			(end 0.625 0.925)
			(stroke
				(width 0.2)
				(type solid)
			)
			(layer "B.SilkS")
		)
		(fp_line
			(start -0.615 -0.925)
			(end 0.635 -0.925)
			(stroke
				(width 0.2)
				(type solid)
			)
			(layer "B.SilkS")
		)
		(fp_circle
			(center -1.225 0.4)
			(end -1.225 0.275)
			(stroke
				(width 0.25)
				(type solid)
			)
			(fill no)
			(layer "B.SilkS")
		)
		(fp_line
			(start -0.8 -0.725)
			(end 0.8 -0.725)
			(stroke
				(width 0.2)
				(type solid)
			)
			(layer "B.CrtYd")
		)
		(fp_line
			(start -0.8 0.725)
			(end -0.8 -0.725)
			(stroke
				(width 0.2)
				(type solid)
			)
			(layer "B.CrtYd")
		)
		(fp_line
			(start -0.8 0.725)
			(end 0.8 0.725)
			(stroke
				(width 0.2)
				(type solid)
			)
			(layer "B.CrtYd")
		)
		(fp_line
			(start 0.8 0.725)
			(end 0.8 -0.725)
			(stroke
				(width 0.2)
				(type solid)
			)
			(layer "B.CrtYd")
		)
		(fp_line
			(start -0.8 -0.725)
			(end 0.8 -0.725)
			(stroke
				(width 0.2)
				(type solid)
			)
			(layer "B.Fab")
		)
		(fp_line
			(start -0.8 0.725)
			(end -0.8 -0.725)
			(stroke
				(width 0.2)
				(type solid)
			)
			(layer "B.Fab")
		)
		(fp_line
			(start -0.8 0.725)
			(end 0.8 0.725)
			(stroke
				(width 0.2)
				(type solid)
			)
			(layer "B.Fab")
		)
		(fp_line
			(start -0.5 0)
			(end 0.5 0)
			(stroke
				(width 0.1)
				(type solid)
			)
			(layer "B.Fab")
		)
		(fp_line
			(start 0 0.5)
			(end 0 -0.5)
			(stroke
				(width 0.1)
				(type solid)
			)
			(layer "B.Fab")
		)
		(fp_line
			(start 0.8 0.725)
			(end 0.8 -0.725)
			(stroke
				(width 0.2)
				(type solid)
			)
			(layer "B.Fab")
		)
		(fp_text user "${REFERENCE}"
			(at 0 -0.28425 180)
			(unlocked yes)
			(layer "B.Fab")
			(effects
				(font
					(face "Arial")
					(size 0.63 0.63)
					(thickness 0.1)
				)
				(justify left bottom mirror)
			)
		)
		(pad "1" smd rect
			(at -0.515 0.4)
			(size 0.37 0.24)
			(layers "B.Cu" "B.Mask" "B.Paste")
			(net "FTDI_P3V3")
			(solder_mask_margin 0)
			(solder_paste_margin 0)
		)
		(pad "2" smd rect
			(at -0.515 0)
			(size 0.37 0.24)
			(layers "B.Cu" "B.Mask" "B.Paste")
			(net "FTDI_P3V3")
			(solder_mask_margin 0)
			(solder_paste_margin 0)
		)
		(pad "3" smd rect
			(at -0.515 -0.4)
			(size 0.37 0.24)
			(layers "B.Cu" "B.Mask" "B.Paste")
			(net "GND")
			(solder_mask_margin 0)
			(solder_paste_margin 0)
		)
		(pad "4" smd rect
			(at 0.515 -0.4)
			(size 0.37 0.24)
			(layers "B.Cu" "B.Mask" "B.Paste")
			(net "FTDI_VBUS")
			(solder_mask_margin 0)
			(solder_paste_margin 0)
		)
		(pad "5" smd rect
			(at 0.515 0)
			(size 0.37 0.24)
			(layers "B.Cu" "B.Mask" "B.Paste")
			(solder_mask_margin 0)
			(solder_paste_margin 0)
		)
		(pad "6" smd rect
			(at 0.515 0.4)
			(size 0.37 0.24)
			(layers "B.Cu" "B.Mask" "B.Paste")
			(net "FTDI_VBUS")
			(solder_mask_margin 0)
			(solder_paste_margin 0)
		)
		(pad "7" smd rect
			(at 0 0)
			(size 0.4 1.08)
			(layers "B.Cu" "B.Mask" "B.Paste")
			(net "GND")
			(solder_mask_margin 0)
			(solder_paste_margin 0)
		)
	)
	(footprint "Vault:FP-0402-L_1_0_1-W_0_5_0_1-IPC_C"
		(layer "B.Cu")
		(at 193.50119 131.4145 -90)
		(property "Reference" "C108"
			(at 0.2049 1.452669 90)
			(unlocked yes)
			(layer "B.SilkS")
			(effects
				(font
					(size 0.762 0.762)
					(thickness 0.2032)
				)
				(justify mirror)
			)
		)
		(property "Value" "0.1uF_25V_0402"
			(at -2.465551 -9.813805 180)
			(unlocked yes)
			(layer "B.SilkS")
			(hide yes)
			(effects
				(font
					(size 0.762 0.762)
					(thickness 0.2032)
				)
				(justify mirror)
			)
		)
		(sheetname "11-M2_RCB_MUX")
		(sheetfile "11-M2_RCB_MUX.kicad_sch")
		(duplicate_pad_numbers_are_jumpers no)
		(fp_line
			(start 0.65607 0.7)
			(end -0.65607 0.7)
			(stroke
				(width 0.2)
				(type solid)
			)
			(layer "B.SilkS")
		)
		(fp_line
			(start 0.65607 -0.7)
			(end -0.65607 -0.7)
			(stroke
				(width 0.2)
				(type solid)
			)
			(layer "B.SilkS")
		)
		(fp_line
			(start -0.75607 0.4)
			(end -0.75607 -0.4)
			(stroke
				(width 0.2)
				(type solid)
			)
			(layer "B.CrtYd")
		)
		(fp_line
			(start 0.75607 0.4)
			(end -0.75607 0.4)
			(stroke
				(width 0.2)
				(type solid)
			)
			(layer "B.CrtYd")
		)
		(fp_line
			(start 0.75607 0.4)
			(end 0.75607 -0.4)
			(stroke
				(width 0.2)
				(type solid)
			)
			(layer "B.CrtYd")
		)
		(fp_line
			(start 0.75607 -0.4)
			(end -0.75607 -0.4)
			(stroke
				(width 0.2)
				(type solid)
			)
			(layer "B.CrtYd")
		)
		(fp_line
			(start 0 0.5)
			(end 0 -0.5)
			(stroke
				(width 0.1)
				(type solid)
			)
			(layer "B.Fab")
		)
		(fp_line
			(start -0.75607 0.4)
			(end -0.75607 -0.4)
			(stroke
				(width 0.2)
				(type solid)
			)
			(layer "B.Fab")
		)
		(fp_line
			(start 0.75607 0.4)
			(end -0.75607 0.4)
			(stroke
				(width 0.2)
				(type solid)
			)
			(layer "B.Fab")
		)
		(fp_line
			(start 0.75607 0.4)
			(end 0.75607 -0.4)
			(stroke
				(width 0.2)
				(type solid)
			)
			(layer "B.Fab")
		)
		(fp_line
			(start 0.5 0)
			(end -0.5 0)
			(stroke
				(width 0.1)
				(type solid)
			)
			(layer "B.Fab")
		)
		(fp_line
			(start 0.75607 -0.4)
			(end -0.75607 -0.4)
			(stroke
				(width 0.2)
				(type solid)
			)
			(layer "B.Fab")
		)
		(fp_text user "${REFERENCE}"
			(at -0.00001 -0.09601 90)
			(unlocked yes)
			(layer "B.Fab")
			(effects
				(font
					(face "Arial")
					(size 0.63 0.63)
					(thickness 0.1)
				)
				(justify left bottom mirror)
			)
		)
		(pad "1" smd rect
			(at -0.36554 0 270)
			(size 0.58106 0.51213)
			(layers "B.Cu" "B.Mask" "B.Paste")
			(net "+3.3V")
			(solder_mask_margin 0)
			(solder_paste_margin 0)
		)
		(pad "2" smd rect
			(at 0.36554 0 270)
			(size 0.58106 0.51213)
			(layers "B.Cu" "B.Mask" "B.Paste")
			(net "GND")
			(solder_mask_margin 0)
			(solder_paste_margin 0)
		)
	)
	(footprint "Vault:FP-0603-L_1_6_0_2-W_0_8_0-MFG"
		(layer "B.Cu")
		(at 114.0216 80.9162 -90)
		(property "Reference" "C6"
			(at -3 -0.493345 90)
			(unlocked yes)
			(layer "B.SilkS")
			(effects
				(font
					(size 0.762 0.762)
					(thickness 0.2286)
				)
				(justify left bottom mirror)
			)
		)
		(property "Value" "10uF_16V_0603"
			(at 5.449845 12.8601 0)
			(unlocked yes)
			(layer "B.SilkS")
			(hide yes)
			(effects
				(font
					(size 0.762 0.762)
					(thickness 0.2286)
				)
				(justify left bottom mirror)
			)
		)
		(sheetname "05-GPS_IMU_SENSORS")
		(sheetfile "05-GPS_IMU_SENSORS.kicad_sch")
		(duplicate_pad_numbers_are_jumpers no)
		(fp_line
			(start 0.9 0.825)
			(end -0.9 0.825)
			(stroke
				(width 0.2)
				(type solid)
			)
			(layer "B.SilkS")
		)
		(fp_line
			(start 0.9 -0.825)
			(end -0.9 -0.825)
			(stroke
				(width 0.2)
				(type solid)
			)
			(layer "B.SilkS")
		)
		(fp_line
			(start -1.15 0.6)
			(end -1.15 -0.6)
			(stroke
				(width 0.2)
				(type solid)
			)
			(layer "B.CrtYd")
		)
		(fp_line
			(start 1.15 0.6)
			(end -1.15 0.6)
			(stroke
				(width 0.2)
				(type solid)
			)
			(layer "B.CrtYd")
		)
		(fp_line
			(start 1.15 0.6)
			(end 1.15 -0.6)
			(stroke
				(width 0.2)
				(type solid)
			)
			(layer "B.CrtYd")
		)
		(fp_line
			(start 1.15 -0.6)
			(end -1.15 -0.6)
			(stroke
				(width 0.2)
				(type solid)
			)
			(layer "B.CrtYd")
		)
		(fp_line
			(start -1.15 0.6)
			(end -1.15 -0.6)
			(stroke
				(width 0.2)
				(type solid)
			)
			(layer "B.Fab")
		)
		(fp_line
			(start 1.15 0.6)
			(end -1.15 0.6)
			(stroke
				(width 0.2)
				(type solid)
			)
			(layer "B.Fab")
		)
		(fp_line
			(start 1.15 0.6)
			(end 1.15 -0.6)
			(stroke
				(width 0.2)
				(type solid)
			)
			(layer "B.Fab")
		)
		(fp_line
			(start 0 0.5)
			(end 0 -0.5)
			(stroke
				(width 0.1)
				(type solid)
			)
			(layer "B.Fab")
		)
		(fp_line
			(start 0.5 0)
			(end -0.5 0)
			(stroke
				(width 0.1)
				(type solid)
			)
			(layer "B.Fab")
		)
		(fp_line
			(start 1.15 -0.6)
			(end -1.15 -0.6)
			(stroke
				(width 0.2)
				(type solid)
			)
			(layer "B.Fab")
		)
		(fp_text user "${REFERENCE}"
			(at -0.00002 -0.09602 90)
			(unlocked yes)
			(layer "B.Fab")
			(effects
				(font
					(face "Arial")
					(size 0.63 0.63)
					(thickness 0.1)
				)
				(justify left bottom mirror)
			)
		)
		(pad "1" smd rect
			(at -0.7 0 270)
			(size 0.7 0.7)
			(layers "B.Cu" "B.Mask" "B.Paste")
			(net "+5.0V")
			(solder_mask_margin 0)
			(solder_paste_margin 0)
		)
		(pad "2" smd rect
			(at 0.7 0 270)
			(size 0.7 0.7)
			(layers "B.Cu" "B.Mask" "B.Paste")
			(net "GND")
			(solder_mask_margin 0)
			(solder_paste_margin 0)
		)
	)
	(footprint "Vault:FP-MK212BG-MFG"
		(layer "B.Cu")
		(at 213.6216 139.0162 180)
		(property "Reference" "C56"
			(at 0.8286 1.273079 0)
			(unlocked yes)
			(layer "B.SilkS")
			(effects
				(font
					(size 0.762 0.762)
					(thickness 0.2286)
				)
				(justify mirror)
			)
		)
		(property "Value" "10uF"
			(at -3.240271 -2.22164 90)
			(unlocked yes)
			(layer "B.SilkS")
			(hide yes)
			(effects
				(font
					(size 0.762 0.762)
					(thickness 0.2286)
				)
				(justify mirror)
			)
		)
		(sheetname "05-GPS_IMU_SENSORS")
		(sheetfile "05-GPS_IMU_SENSORS.kicad_sch")
		(duplicate_pad_numbers_are_jumpers no)
		(fp_line
			(start 0.125 0.725)
			(end -0.125 0.725)
			(stroke
				(width 0.2)
				(type solid)
			)
			(layer "B.SilkS")
		)
		(fp_line
			(start 0.125 -0.725)
			(end -0.125 -0.725)
			(stroke
				(width 0.2)
				(type solid)
			)
			(layer "B.SilkS")
		)
		(fp_line
			(start 1.6 0.825)
			(end -1.6 0.825)
			(stroke
				(width 0.2)
				(type solid)
			)
			(layer "B.CrtYd")
		)
		(fp_line
			(start 1.6 -0.825)
			(end 1.6 0.825)
			(stroke
				(width 0.2)
				(type solid)
			)
			(layer "B.CrtYd")
		)
		(fp_line
			(start 1.6 -0.825)
			(end -1.6 -0.825)
			(stroke
				(width 0.2)
				(type solid)
			)
			(layer "B.CrtYd")
		)
		(fp_line
			(start -1.6 -0.825)
			(end -1.6 0.825)
			(stroke
				(width 0.2)
				(type solid)
			)
			(layer "B.CrtYd")
		)
		(fp_line
			(start 1.6 0.825)
			(end -1.6 0.825)
			(stroke
				(width 0.2)
				(type solid)
			)
			(layer "B.Fab")
		)
		(fp_line
			(start 1.6 -0.825)
			(end 1.6 0.825)
			(stroke
				(width 0.2)
				(type solid)
			)
			(layer "B.Fab")
		)
		(fp_line
			(start 1.6 -0.825)
			(end -1.6 -0.825)
			(stroke
				(width 0.2)
				(type solid)
			)
			(layer "B.Fab")
		)
		(fp_line
			(start 0.5 0)
			(end -0.5 0)
			(stroke
				(width 0.1)
				(type solid)
			)
			(layer "B.Fab")
		)
		(fp_line
			(start 0 -0.5)
			(end 0 0.5)
			(stroke
				(width 0.1)
				(type solid)
			)
			(layer "B.Fab")
		)
		(fp_line
			(start -1.6 -0.825)
			(end -1.6 0.825)
			(stroke
				(width 0.2)
				(type solid)
			)
			(layer "B.Fab")
		)
		(fp_text user "${REFERENCE}"
			(at -0.00001 -0.09602 360)
			(unlocked yes)
			(layer "B.Fab")
			(effects
				(font
					(face "Arial")
					(size 0.63 0.63)
					(thickness 0.1)
				)
				(justify left bottom mirror)
			)
		)
		(pad "1" smd rect
			(at -1 0 180)
			(size 1 1.25)
			(layers "B.Cu" "B.Mask" "B.Paste")
			(net "GNSS2_P5V0")
			(solder_mask_margin 0)
			(solder_paste_margin 0)
		)
		(pad "2" smd rect
			(at 1 0 180)
			(size 1 1.25)
			(layers "B.Cu" "B.Mask" "B.Paste")
			(net "GND")
			(solder_mask_margin 0)
			(solder_paste_margin 0)
		)
	)
	(footprint "Capacitors:CAPC1005X06N"
		(layer "B.Cu")
		(at 136.4956 151.7886 90)
		(property "Reference" "C50"
			(at 2.41349 -0.766255 270)
			(unlocked yes)
			(layer "B.SilkS")
			(effects
				(font
					(size 0.762 0.762)
					(thickness 0.2286)
				)
				(justify left bottom mirror)
			)
		)
		(property "Value" "CAP_0402_0.1UF_50V"
			(at -3.382645 0.2921 0)
			(unlocked yes)
			(layer "B.SilkS")
			(hide yes)
			(effects
				(font
					(size 0.762 0.762)
					(thickness 0.2286)
				)
				(justify left bottom mirror)
			)
		)
		(sheetname "04-PCIe_JTAG")
		(sheetfile "04-PCIe_JTAG.kicad_sch")
		(duplicate_pad_numbers_are_jumpers no)
		(pad "1" smd rect
			(at -0.43 0)
			(size 0.64 0.68)
			(layers "B.Cu" "B.Mask" "B.Paste")
			(net "NetC50_1")
		)
		(pad "2" smd rect
			(at 0.43 0)
			(size 0.64 0.68)
			(layers "B.Cu" "B.Mask" "B.Paste")
			(net "PCIE_TX2_P")
		)
	)
	(footprint "Vault:RESC1005X40X25NL10T10"
		(layer "B.Cu")
		(at 207.95084 120.1412 180)
		(property "Reference" "R135"
			(at 2.63244 -0.001921 0)
			(unlocked yes)
			(layer "B.SilkS")
			(effects
				(font
					(size 0.762 0.762)
					(thickness 0.2032)
				)
				(justify mirror)
			)
		)
		(property "Value" "4.7K_1%_0402"
			(at -2.732271 -8.747465 90)
			(unlocked yes)
			(layer "B.SilkS")
			(hide yes)
			(effects
				(font
					(size 0.762 0.762)
					(thickness 0.2032)
				)
				(justify mirror)
			)
		)
		(sheetname "10-M2_GPS")
		(sheetfile "10-M2_GPS.kicad_sch")
		(duplicate_pad_numbers_are_jumpers no)
		(pad "1" smd rect
			(at -0.425 0 90)
			(size 0.6 0.65)
			(layers "B.Cu" "B.Mask" "B.Paste")
			(net "GPS2_PIN13")
		)
		(pad "2" smd rect
			(at 0.425 0 90)
			(size 0.6 0.65)
			(layers "B.Cu" "B.Mask" "B.Paste")
			(net "GNSS2_P3V3")
		)
	)
	(footprint "Capacitors:CAPC1005X06N"
		(layer "B.Cu")
		(at 141.5756 151.7886 90)
		(property "Reference" "C53"
			(at 2.41349 0.046545 270)
			(unlocked yes)
			(layer "B.SilkS")
			(effects
				(font
					(size 0.762 0.762)
					(thickness 0.2286)
				)
				(justify left bottom mirror)
			)
		)
		(property "Value" "CAP_0402_0.1UF_50V"
			(at -3.382645 0.2921 0)
			(unlocked yes)
			(layer "B.SilkS")
			(hide yes)
			(effects
				(font
					(size 0.762 0.762)
					(thickness 0.2286)
				)
				(justify left bottom mirror)
			)
		)
		(sheetname "04-PCIe_JTAG")
		(sheetfile "04-PCIe_JTAG.kicad_sch")
		(duplicate_pad_numbers_are_jumpers no)
		(pad "1" smd rect
			(at -0.43 0)
			(size 0.64 0.68)
			(layers "B.Cu" "B.Mask" "B.Paste")
			(net "NetC53_1")
		)
		(pad "2" smd rect
			(at 0.43 0)
			(size 0.64 0.68)
			(layers "B.Cu" "B.Mask" "B.Paste")
			(net "PCIE_TX3_N")
		)
	)
	(footprint "Vault:FP-0402-L_1_0_1-W_0_5_0_1-IPC_C"
		(layer "B.Cu")
		(at 213.58331 126.42791 180)
		(property "Reference" "C113"
			(at -0.29229 -1.461359 180)
			(unlocked yes)
			(layer "B.SilkS")
			(effects
				(font
					(size 0.762 0.762)
					(thickness 0.254)
				)
				(justify mirror)
			)
		)
		(property "Value" "0.1uF_25V_0402"
			(at -2.465551 -9.864615 90)
			(unlocked yes)
			(layer "B.SilkS")
			(hide yes)
			(effects
				(font
					(size 0.762 0.762)
					(thickness 0.254)
				)
				(justify mirror)
			)
		)
		(sheetname "09-USBUart_PPSMUX_UARTMUX")
		(sheetfile "09-USBUart_PPSMUX_UARTMUX.kicad_sch")
		(duplicate_pad_numbers_are_jumpers no)
		(fp_line
			(start 0.65607 0.7)
			(end -0.65606 0.7)
			(stroke
				(width 0.2)
				(type solid)
			)
			(layer "B.SilkS")
		)
		(fp_line
			(start 0.65607 -0.7)
			(end -0.65606 -0.7)
			(stroke
				(width 0.2)
				(type solid)
			)
			(layer "B.SilkS")
		)
		(fp_line
			(start 0.75607 0.4)
			(end -0.75606 0.4)
			(stroke
				(width 0.2)
				(type solid)
			)
			(layer "B.CrtYd")
		)
		(fp_line
			(start 0.75607 -0.4)
			(end 0.75607 0.4)
			(stroke
				(width 0.2)
				(type solid)
			)
			(layer "B.CrtYd")
		)
		(fp_line
			(start 0.75607 -0.4)
			(end -0.75606 -0.4)
			(stroke
				(width 0.2)
				(type solid)
			)
			(layer "B.CrtYd")
		)
		(fp_line
			(start -0.75606 -0.4)
			(end -0.75606 0.4)
			(stroke
				(width 0.2)
				(type solid)
			)
			(layer "B.CrtYd")
		)
		(fp_line
			(start 0.75607 0.4)
			(end -0.75606 0.4)
			(stroke
				(width 0.2)
				(type solid)
			)
			(layer "B.Fab")
		)
		(fp_line
			(start 0.75607 -0.4)
			(end 0.75607 0.4)
			(stroke
				(width 0.2)
				(type solid)
			)
			(layer "B.Fab")
		)
		(fp_line
			(start 0.75607 -0.4)
			(end -0.75606 -0.4)
			(stroke
				(width 0.2)
				(type solid)
			)
			(layer "B.Fab")
		)
		(fp_line
			(start 0.5 0)
			(end -0.5 0)
			(stroke
				(width 0.1)
				(type solid)
			)
			(layer "B.Fab")
		)
		(fp_line
			(start 0 -0.5)
			(end 0 0.5)
			(stroke
				(width 0.1)
				(type solid)
			)
			(layer "B.Fab")
		)
		(fp_line
			(start -0.75606 -0.4)
			(end -0.75606 0.4)
			(stroke
				(width 0.2)
				(type solid)
			)
			(layer "B.Fab")
		)
		(fp_text user "${REFERENCE}"
			(at -0.00001 -0.09602 360)
			(unlocked yes)
			(layer "B.Fab")
			(effects
				(font
					(face "Arial")
					(size 0.63 0.63)
					(thickness 0.1)
				)
				(justify left bottom mirror)
			)
		)
		(pad "1" smd rect
			(at -0.36553 0 180)
			(size 0.58106 0.51213)
			(layers "B.Cu" "B.Mask" "B.Paste")
			(net "GNSS2_P5V0")
			(solder_mask_margin 0)
			(solder_paste_margin 0)
		)
		(pad "2" smd rect
			(at 0.36554 0 180)
			(size 0.58106 0.51213)
			(layers "B.Cu" "B.Mask" "B.Paste")
			(net "GND")
			(solder_mask_margin 0)
			(solder_paste_margin 0)
		)
	)
	(footprint "Vault:FP-0402-L_1_0_1-W_0_5_0_1-IPC_C"
		(layer "B.Cu")
		(at 154.8216 116.0162 180)
		(property "Reference" "C69"
			(at 0.2286 1.573069 0)
			(unlocked yes)
			(layer "B.SilkS")
			(effects
				(font
					(size 0.762 0.762)
					(thickness 0.2286)
				)
				(justify mirror)
			)
		)
		(property "Value" "0.1uF_25V_0402"
			(at -2.744951 -8.290305 90)
			(unlocked yes)
			(layer "B.SilkS")
			(hide yes)
			(effects
				(font
					(size 0.762 0.762)
					(thickness 0.2286)
				)
				(justify mirror)
			)
		)
		(sheetname "08-DIPSwitches_I2C")
		(sheetfile "08-DIPSwitches_I2C.kicad_sch")
		(duplicate_pad_numbers_are_jumpers no)
		(fp_line
			(start 0.65607 0.7)
			(end -0.65607 0.7)
			(stroke
				(width 0.2)
				(type solid)
			)
			(layer "B.SilkS")
		)
		(fp_line
			(start 0.65607 -0.7)
			(end -0.65607 -0.7)
			(stroke
				(width 0.2)
				(type solid)
			)
			(layer "B.SilkS")
		)
		(fp_line
			(start 0.75607 0.4)
			(end -0.75607 0.4)
			(stroke
				(width 0.2)
				(type solid)
			)
			(layer "B.CrtYd")
		)
		(fp_line
			(start 0.75607 -0.4)
			(end 0.75607 0.4)
			(stroke
				(width 0.2)
				(type solid)
			)
			(layer "B.CrtYd")
		)
		(fp_line
			(start 0.75607 -0.4)
			(end -0.75607 -0.4)
			(stroke
				(width 0.2)
				(type solid)
			)
			(layer "B.CrtYd")
		)
		(fp_line
			(start -0.75607 -0.4)
			(end -0.75607 0.4)
			(stroke
				(width 0.2)
				(type solid)
			)
			(layer "B.CrtYd")
		)
		(fp_line
			(start 0.75607 0.4)
			(end -0.75607 0.4)
			(stroke
				(width 0.2)
				(type solid)
			)
			(layer "B.Fab")
		)
		(fp_line
			(start 0.75607 -0.4)
			(end 0.75607 0.4)
			(stroke
				(width 0.2)
				(type solid)
			)
			(layer "B.Fab")
		)
		(fp_line
			(start 0.75607 -0.4)
			(end -0.75607 -0.4)
			(stroke
				(width 0.2)
				(type solid)
			)
			(layer "B.Fab")
		)
		(fp_line
			(start 0.5 0)
			(end -0.5 0)
			(stroke
				(width 0.1)
				(type solid)
			)
			(layer "B.Fab")
		)
		(fp_line
			(start 0 -0.5)
			(end 0 0.5)
			(stroke
				(width 0.1)
				(type solid)
			)
			(layer "B.Fab")
		)
		(fp_line
			(start -0.75607 -0.4)
			(end -0.75607 0.4)
			(stroke
				(width 0.2)
				(type solid)
			)
			(layer "B.Fab")
		)
		(fp_text user "${REFERENCE}"
			(at -0.00001 -0.09602 360)
			(unlocked yes)
			(layer "B.Fab")
			(effects
				(font
					(face "Arial")
					(size 0.63 0.63)
					(thickness 0.1)
				)
				(justify left bottom mirror)
			)
		)
		(pad "1" smd rect
			(at -0.36554 0 180)
			(size 0.58106 0.51213)
			(layers "B.Cu" "B.Mask" "B.Paste")
			(net "+3.3V")
			(solder_mask_margin 0)
			(solder_paste_margin 0)
		)
		(pad "2" smd rect
			(at 0.36554 0 180)
			(size 0.58106 0.51213)
			(layers "B.Cu" "B.Mask" "B.Paste")
			(net "GND")
			(solder_mask_margin 0)
			(solder_paste_margin 0)
		)
	)
	(footprint "Vault:FP-0603-L_1_6_0_2-W_0_8_0-MFG"
		(layer "B.Cu")
		(at 88.5116 69.33347 90)
		(property "Reference" "C22"
			(at -0.98273 1.316655 270)
			(unlocked yes)
			(layer "B.SilkS")
			(effects
				(font
					(size 0.762 0.762)
					(thickness 0.2286)
				)
				(justify left bottom mirror)
			)
		)
		(property "Value" "10uF_16V_0603"
			(at 1.606965 -21.7043 0)
			(unlocked yes)
			(layer "B.SilkS")
			(hide yes)
			(effects
				(font
					(size 0.762 0.762)
					(thickness 0.2286)
				)
				(justify left bottom mirror)
			)
		)
		(sheetname "03-POWER")
		(sheetfile "03-POWER.kicad_sch")
		(duplicate_pad_numbers_are_jumpers no)
		(fp_line
			(start -0.9 -0.825)
			(end 0.9 -0.825)
			(stroke
				(width 0.2)
				(type solid)
			)
			(layer "B.SilkS")
		)
		(fp_line
			(start -0.9 0.825)
			(end 0.9 0.825)
			(stroke
				(width 0.2)
				(type solid)
			)
			(layer "B.SilkS")
		)
		(fp_line
			(start 1.15 -0.6)
			(end 1.15 0.6)
			(stroke
				(width 0.2)
				(type solid)
			)
			(layer "B.CrtYd")
		)
		(fp_line
			(start -1.15 -0.6)
			(end 1.15 -0.6)
			(stroke
				(width 0.2)
				(type solid)
			)
			(layer "B.CrtYd")
		)
		(fp_line
			(start -1.15 -0.6)
			(end -1.15 0.6)
			(stroke
				(width 0.2)
				(type solid)
			)
			(layer "B.CrtYd")
		)
		(fp_line
			(start -1.15 0.6)
			(end 1.15 0.6)
			(stroke
				(width 0.2)
				(type solid)
			)
			(layer "B.CrtYd")
		)
		(fp_line
			(start 1.15 -0.6)
			(end 1.15 0.6)
			(stroke
				(width 0.2)
				(type solid)
			)
			(layer "B.Fab")
		)
		(fp_line
			(start -1.15 -0.6)
			(end 1.15 -0.6)
			(stroke
				(width 0.2)
				(type solid)
			)
			(layer "B.Fab")
		)
		(fp_line
			(start -1.15 -0.6)
			(end -1.15 0.6)
			(stroke
				(width 0.2)
				(type solid)
			)
			(layer "B.Fab")
		)
		(fp_line
			(start 0 -0.5)
			(end 0 0.5)
			(stroke
				(width 0.1)
				(type solid)
			)
			(layer "B.Fab")
		)
		(fp_line
			(start -0.49999 0)
			(end 0.5 0)
			(stroke
				(width 0.1)
				(type solid)
			)
			(layer "B.Fab")
		)
		(fp_line
			(start -1.15 0.6)
			(end 1.15 0.6)
			(stroke
				(width 0.2)
				(type solid)
			)
			(layer "B.Fab")
		)
		(fp_text user "${REFERENCE}"
			(at -0.00001 -0.09601 270)
			(unlocked yes)
			(layer "B.Fab")
			(effects
				(font
					(face "Arial")
					(size 0.63 0.63)
					(thickness 0.1)
				)
				(justify left bottom mirror)
			)
		)
		(pad "1" smd rect
			(at -0.7 0 90)
			(size 0.7 0.7)
			(layers "B.Cu" "B.Mask" "B.Paste")
			(net "+3.3V")
			(solder_mask_margin 0)
			(solder_paste_margin 0)
		)
		(pad "2" smd rect
			(at 0.70001 0 90)
			(size 0.7 0.7)
			(layers "B.Cu" "B.Mask" "B.Paste")
			(net "GND")
			(solder_mask_margin 0)
			(solder_paste_margin 0)
		)
	)
	(footprint "Vault:FP-MK212BG-MFG"
		(layer "B.Cu")
		(at 103.1216 64.3162 180)
		(property "Reference" "C60"
			(at -1 0.906655 0)
			(unlocked yes)
			(layer "B.SilkS")
			(effects
				(font
					(size 0.762 0.762)
					(thickness 0.2286)
				)
				(justify left bottom mirror)
			)
		)
		(property "Value" "10uF"
			(at -1.5875 -3.433445 0)
			(unlocked yes)
			(layer "B.SilkS")
			(hide yes)
			(effects
				(font
					(size 0.762 0.762)
					(thickness 0.2286)
				)
				(justify left bottom mirror)
			)
		)
		(sheetname "05-GPS_IMU_SENSORS")
		(sheetfile "05-GPS_IMU_SENSORS.kicad_sch")
		(duplicate_pad_numbers_are_jumpers no)
		(fp_line
			(start 0.125 0.725)
			(end -0.125 0.725)
			(stroke
				(width 0.2)
				(type solid)
			)
			(layer "B.SilkS")
		)
		(fp_line
			(start 0.125 -0.725)
			(end -0.125 -0.725)
			(stroke
				(width 0.2)
				(type solid)
			)
			(layer "B.SilkS")
		)
		(fp_line
			(start 1.6 0.825)
			(end -1.6 0.825)
			(stroke
				(width 0.2)
				(type solid)
			)
			(layer "B.CrtYd")
		)
		(fp_line
			(start 1.6 -0.825)
			(end 1.6 0.825)
			(stroke
				(width 0.2)
				(type solid)
			)
			(layer "B.CrtYd")
		)
		(fp_line
			(start 1.6 -0.825)
			(end -1.6 -0.825)
			(stroke
				(width 0.2)
				(type solid)
			)
			(layer "B.CrtYd")
		)
		(fp_line
			(start -1.6 -0.825)
			(end -1.6 0.825)
			(stroke
				(width 0.2)
				(type solid)
			)
			(layer "B.CrtYd")
		)
		(fp_line
			(start 1.6 0.825)
			(end -1.6 0.825)
			(stroke
				(width 0.2)
				(type solid)
			)
			(layer "B.Fab")
		)
		(fp_line
			(start 1.6 -0.825)
			(end 1.6 0.825)
			(stroke
				(width 0.2)
				(type solid)
			)
			(layer "B.Fab")
		)
		(fp_line
			(start 1.6 -0.825)
			(end -1.6 -0.825)
			(stroke
				(width 0.2)
				(type solid)
			)
			(layer "B.Fab")
		)
		(fp_line
			(start 0.5 0)
			(end -0.5 0)
			(stroke
				(width 0.1)
				(type solid)
			)
			(layer "B.Fab")
		)
		(fp_line
			(start 0 -0.5)
			(end 0 0.5)
			(stroke
				(width 0.1)
				(type solid)
			)
			(layer "B.Fab")
		)
		(fp_line
			(start -1.6 -0.825)
			(end -1.6 0.825)
			(stroke
				(width 0.2)
				(type solid)
			)
			(layer "B.Fab")
		)
		(fp_text user "${REFERENCE}"
			(at -0.00001 -0.09601 360)
			(unlocked yes)
			(layer "B.Fab")
			(effects
				(font
					(face "Arial")
					(size 0.63 0.63)
					(thickness 0.1)
				)
				(justify left bottom mirror)
			)
		)
		(pad "1" smd rect
			(at -1 0 180)
			(size 1 1.25)
			(layers "B.Cu" "B.Mask" "B.Paste")
			(net "+5.0V")
			(solder_mask_margin 0)
			(solder_paste_margin 0)
		)
		(pad "2" smd rect
			(at 1 0 180)
			(size 1 1.25)
			(layers "B.Cu" "B.Mask" "B.Paste")
			(net "GND")
			(solder_mask_margin 0)
			(solder_paste_margin 0)
		)
	)
	(footprint "Capacitors:CAPC1005X06N"
		(layer "B.Cu")
		(at 132.5586 151.7886 90)
		(property "Reference" "C48"
			(at 2.41349 -0.867855 270)
			(unlocked yes)
			(layer "B.SilkS")
			(effects
				(font
					(size 0.762 0.762)
					(thickness 0.2286)
				)
				(justify left bottom mirror)
			)
		)
		(property "Value" "CAP_0402_0.1UF_50V"
			(at -3.382645 0.2921 0)
			(unlocked yes)
			(layer "B.SilkS")
			(hide yes)
			(effects
				(font
					(size 0.762 0.762)
					(thickness 0.2286)
				)
				(justify left bottom mirror)
			)
		)
		(sheetname "04-PCIe_JTAG")
		(sheetfile "04-PCIe_JTAG.kicad_sch")
		(duplicate_pad_numbers_are_jumpers no)
		(pad "1" smd rect
			(at -0.43 0)
			(size 0.64 0.68)
			(layers "B.Cu" "B.Mask" "B.Paste")
			(net "NetC48_1")
		)
		(pad "2" smd rect
			(at 0.43 0)
			(size 0.64 0.68)
			(layers "B.Cu" "B.Mask" "B.Paste")
			(net "PCIE_TX1_P")
		)
	)
	(footprint "Vault:CAPC1608X87X45ML20T05"
		(layer "B.Cu")
		(at 207.5216 141.2162 180)
		(property "Reference" "C37"
			(at -0.1286 -1.273069 180)
			(unlocked yes)
			(layer "B.SilkS")
			(effects
				(font
					(size 0.762 0.762)
					(thickness 0.2286)
				)
				(justify mirror)
			)
		)
		(property "Value" "0.1uF"
			(at 2.069035 -2.630671 0)
			(unlocked yes)
			(layer "B.SilkS")
			(hide yes)
			(effects
				(font
					(size 0.762 0.762)
					(thickness 0.2286)
				)
				(justify mirror)
			)
		)
		(sheetname "05-GPS_IMU_SENSORS")
		(sheetfile "05-GPS_IMU_SENSORS.kicad_sch")
		(duplicate_pad_numbers_are_jumpers no)
		(pad "1" smd rect
			(at -0.7 0 90)
			(size 1.1 1.05)
			(layers "B.Cu" "B.Mask" "B.Paste")
			(net "GND")
		)
		(pad "2" smd rect
			(at 0.7 0 90)
			(size 1.1 1.05)
			(layers "B.Cu" "B.Mask" "B.Paste")
			(net "GNSS2_P5V0")
		)
	)
	(footprint "Vault:RESC1005X40X25ML05T05"
		(layer "B.Cu")
		(at 209.8216 126.2162 90)
		(property "Reference" "R181"
			(at 0.22626 0.873069 270)
			(unlocked yes)
			(layer "B.SilkS")
			(effects
				(font
					(size 0.762 0.762)
					(thickness 0.254)
				)
				(justify mirror)
			)
		)
		(property "Value" "10K_5%_0402"
			(at -2.884671 -8.061875 0)
			(unlocked yes)
			(layer "B.SilkS")
			(hide yes)
			(effects
				(font
					(size 0.762 0.762)
					(thickness 0.254)
				)
				(justify mirror)
			)
		)
		(sheetname "09-USBUart_PPSMUX_UARTMUX")
		(sheetfile "09-USBUart_PPSMUX_UARTMUX.kicad_sch")
		(duplicate_pad_numbers_are_jumpers no)
		(pad "1" smd rect
			(at -0.5 0)
			(size 0.65 0.65)
			(layers "B.Cu" "B.Mask" "B.Paste")
			(net "GND")
		)
		(pad "2" smd rect
			(at 0.5 0)
			(size 0.65 0.65)
			(layers "B.Cu" "B.Mask" "B.Paste")
			(net "NetR49_1")
		)
	)
	(footprint "Capacitors:CAPC1005X06N"
		(layer "B.Cu")
		(at 125.5736 151.7886 90)
		(property "Reference" "C45"
			(at 2.835 -0.445345 270)
			(unlocked yes)
			(layer "B.SilkS")
			(effects
				(font
					(size 0.762 0.762)
					(thickness 0.2286)
				)
				(justify left bottom mirror)
			)
		)
		(property "Value" "CAP_0402_0.1UF_50V"
			(at -3.382645 0.2921 0)
			(unlocked yes)
			(layer "B.SilkS")
			(hide yes)
			(effects
				(font
					(size 0.762 0.762)
					(thickness 0.2286)
				)
				(justify left bottom mirror)
			)
		)
		(sheetname "04-PCIe_JTAG")
		(sheetfile "04-PCIe_JTAG.kicad_sch")
		(duplicate_pad_numbers_are_jumpers no)
		(pad "1" smd rect
			(at -0.43 0)
			(size 0.64 0.68)
			(layers "B.Cu" "B.Mask" "B.Paste")
			(net "NetC45_1")
		)
		(pad "2" smd rect
			(at 0.43 0)
			(size 0.64 0.68)
			(layers "B.Cu" "B.Mask" "B.Paste")
			(net "PCIE_CLK_N")
		)
	)
	(footprint "Vault:RESC1005X40X25NL10T10"
		(layer "B.Cu")
		(at 183.19649 92.2162 -90)
		(property "Reference" "R184"
			(at 2.396998 -2.70424 180)
			(unlocked yes)
			(layer "B.SilkS")
			(effects
				(font
					(size 1.524 1.524)
					(thickness 0.254)
				)
				(justify mirror)
			)
		)
		(property "Value" "10K_1%_0402"
			(at -2.759202 -8.036515 180)
			(unlocked yes)
			(layer "B.SilkS")
			(hide yes)
			(effects
				(font
					(size 1.524 1.524)
					(thickness 0.254)
				)
				(justify mirror)
			)
		)
		(sheetname "03-POWER")
		(sheetfile "03-POWER.kicad_sch")
		(duplicate_pad_numbers_are_jumpers no)
		(pad "1" smd rect
			(at -0.425 0 180)
			(size 0.6 0.65)
			(layers "B.Cu" "B.Mask" "B.Paste")
			(net "GND")
		)
		(pad "2" smd rect
			(at 0.425 0 180)
			(size 0.6 0.65)
			(layers "B.Cu" "B.Mask" "B.Paste")
			(net "NetR183_2")
		)
	)
	(footprint "Vault:FP-0402-L_1_0_1-W_0_5_0_1-IPC_C"
		(layer "B.Cu")
		(at 126.5216 55.9162 90)
		(property "Reference" "C98"
			(at 2.30817 0.615561 90)
			(unlocked yes)
			(layer "B.SilkS")
			(effects
				(font
					(size 0.762 0.762)
					(thickness 0.2032)
				)
				(justify mirror)
			)
		)
		(property "Value" "0.1uF_25V_0402"
			(at -2.465551 -9.813815 0)
			(unlocked yes)
			(layer "B.SilkS")
			(hide yes)
			(effects
				(font
					(size 0.762 0.762)
					(thickness 0.2032)
				)
				(justify mirror)
			)
		)
		(sheetname "10-M2_GPS")
		(sheetfile "10-M2_GPS.kicad_sch")
		(duplicate_pad_numbers_are_jumpers no)
		(fp_line
			(start -0.65607 -0.7)
			(end 0.65607 -0.7)
			(stroke
				(width 0.2)
				(type solid)
			)
			(layer "B.SilkS")
		)
		(fp_line
			(start -0.65607 0.7)
			(end 0.65607 0.7)
			(stroke
				(width 0.2)
				(type solid)
			)
			(layer "B.SilkS")
		)
		(fp_line
			(start 0.75607 -0.4)
			(end 0.75607 0.4)
			(stroke
				(width 0.2)
				(type solid)
			)
			(layer "B.CrtYd")
		)
		(fp_line
			(start -0.75607 -0.4)
			(end 0.75607 -0.4)
			(stroke
				(width 0.2)
				(type solid)
			)
			(layer "B.CrtYd")
		)
		(fp_line
			(start -0.75607 -0.4)
			(end -0.75607 0.4)
			(stroke
				(width 0.2)
				(type solid)
			)
			(layer "B.CrtYd")
		)
		(fp_line
			(start -0.75607 0.4)
			(end 0.75607 0.4)
			(stroke
				(width 0.2)
				(type solid)
			)
			(layer "B.CrtYd")
		)
		(fp_line
			(start 0 -0.5)
			(end 0 0.5)
			(stroke
				(width 0.1)
				(type solid)
			)
			(layer "B.Fab")
		)
		(fp_line
			(start 0.75607 -0.4)
			(end 0.75607 0.4)
			(stroke
				(width 0.2)
				(type solid)
			)
			(layer "B.Fab")
		)
		(fp_line
			(start -0.75607 -0.4)
			(end 0.75607 -0.4)
			(stroke
				(width 0.2)
				(type solid)
			)
			(layer "B.Fab")
		)
		(fp_line
			(start -0.75607 -0.4)
			(end -0.75607 0.4)
			(stroke
				(width 0.2)
				(type solid)
			)
			(layer "B.Fab")
		)
		(fp_line
			(start -0.5 0)
			(end 0.5 0)
			(stroke
				(width 0.1)
				(type solid)
			)
			(layer "B.Fab")
		)
		(fp_line
			(start -0.75607 0.4)
			(end 0.75607 0.4)
			(stroke
				(width 0.2)
				(type solid)
			)
			(layer "B.Fab")
		)
		(fp_text user "${REFERENCE}"
			(at -0.00002 -0.09602 270)
			(unlocked yes)
			(layer "B.Fab")
			(effects
				(font
					(face "Arial")
					(size 0.63 0.63)
					(thickness 0.1)
				)
				(justify left bottom mirror)
			)
		)
		(pad "1" smd rect
			(at -0.36554 0 90)
			(size 0.58106 0.51213)
			(layers "B.Cu" "B.Mask" "B.Paste")
			(net "+3.3V")
			(solder_mask_margin 0)
			(solder_paste_margin 0)
		)
		(pad "2" smd rect
			(at 0.36554 0 90)
			(size 0.58106 0.51213)
			(layers "B.Cu" "B.Mask" "B.Paste")
			(net "GND")
			(solder_mask_margin 0)
			(solder_paste_margin 0)
		)
	)
	(footprint "Vault:RESC1005X40X25LL05T05"
		(layer "B.Cu")
		(at 95.2756 58.4511 180)
		(property "Reference" "R4"
			(at -0.646 0.641555 0)
			(unlocked yes)
			(layer "B.SilkS")
			(effects
				(font
					(size 0.762 0.762)
					(thickness 0.2286)
				)
				(justify left bottom mirror)
			)
		)
		(property "Value" "0_1%_0402"
			(at -0.2227 8.970755 0)
			(unlocked yes)
			(layer "B.SilkS")
			(hide yes)
			(effects
				(font
					(size 0.762 0.762)
					(thickness 0.2286)
				)
				(justify left bottom mirror)
			)
		)
		(sheetname "03-POWER")
		(sheetfile "03-POWER.kicad_sch")
		(duplicate_pad_numbers_are_jumpers no)
		(pad "1" smd rect
			(at -0.4 0 90)
			(size 0.45 0.45)
			(layers "B.Cu" "B.Mask" "B.Paste")
			(net "+12V")
		)
		(pad "2" smd rect
			(at 0.4 0 90)
			(size 0.45 0.45)
			(layers "B.Cu" "B.Mask" "B.Paste")
			(net "NetR4_2")
		)
	)
	(footprint "Vault:RESC1005X40X25ML05T05"
		(layer "B.Cu")
		(at 207.81727 126.86632 180)
		(property "Reference" "R49"
			(at -0.18323 -1.047849 180)
			(unlocked yes)
			(layer "B.SilkS")
			(effects
				(font
					(size 0.762 0.762)
					(thickness 0.254)
				)
				(justify mirror)
			)
		)
		(property "Value" "10K_5%_0402"
			(at -2.884671 -8.061875 90)
			(unlocked yes)
			(layer "B.SilkS")
			(hide yes)
			(effects
				(font
					(size 0.762 0.762)
					(thickness 0.254)
				)
				(justify mirror)
			)
		)
		(sheetname "09-USBUart_PPSMUX_UARTMUX")
		(sheetfile "09-USBUart_PPSMUX_UARTMUX.kicad_sch")
		(duplicate_pad_numbers_are_jumpers no)
		(pad "1" smd rect
			(at -0.5 0 90)
			(size 0.65 0.65)
			(layers "B.Cu" "B.Mask" "B.Paste")
			(net "NetR49_1")
		)
		(pad "2" smd rect
			(at 0.5 0 90)
			(size 0.65 0.65)
			(layers "B.Cu" "B.Mask" "B.Paste")
			(net "+3.3V")
		)
	)
	(footprint "Vault:RESC1005X40X25NL10T10"
		(layer "B.Cu")
		(at 184.3216 92.2162 -90)
		(property "Reference" "R183"
			(at 2.396998 -2.70424 180)
			(unlocked yes)
			(layer "B.SilkS")
			(effects
				(font
					(size 1.524 1.524)
					(thickness 0.254)
				)
				(justify mirror)
			)
		)
		(property "Value" "20K_1%_0402"
			(at -2.759202 -8.163475 180)
			(unlocked yes)
			(layer "B.SilkS")
			(hide yes)
			(effects
				(font
					(size 1.524 1.524)
					(thickness 0.254)
				)
				(justify mirror)
			)
		)
		(sheetname "03-POWER")
		(sheetfile "03-POWER.kicad_sch")
		(duplicate_pad_numbers_are_jumpers no)
		(pad "1" smd rect
			(at -0.425 0 180)
			(size 0.6 0.65)
			(layers "B.Cu" "B.Mask" "B.Paste")
			(net "+12V")
		)
		(pad "2" smd rect
			(at 0.425 0 180)
			(size 0.6 0.65)
			(layers "B.Cu" "B.Mask" "B.Paste")
			(net "NetR183_2")
		)
	)
	(footprint "Vault:RESC1608X55X30NL15T15"
		(layer "B.Cu")
		(at 79.4216 54.4662 180)
		(property "Reference" "R38"
			(at -2.9714 -0.176931 0)
			(unlocked yes)
			(layer "B.SilkS")
			(effects
				(font
					(size 0.762 0.762)
					(thickness 0.2286)
				)
				(justify mirror)
			)
		)
		(property "Value" "200 OHM"
			(at -2.935471 -4.78626 90)
			(unlocked yes)
			(layer "B.SilkS")
			(hide yes)
			(effects
				(font
					(size 0.762 0.762)
					(thickness 0.2286)
				)
				(justify mirror)
			)
		)
		(sheetname "02-USER_IO_STATUS")
		(sheetfile "02-USER_IO_STATUS.kicad_sch")
		(duplicate_pad_numbers_are_jumpers no)
		(pad "1" smd rect
			(at -0.675 0 90)
			(size 0.95 0.8)
			(layers "B.Cu" "B.Mask" "B.Paste")
			(net "LED3")
		)
		(pad "2" smd rect
			(at 0.675 0 90)
			(size 0.95 0.8)
			(layers "B.Cu" "B.Mask" "B.Paste")
			(net "NetD10_1")
		)
	)
	(footprint "Vault:RESC1608X55X25LL10T15"
		(layer "B.Cu")
		(at 132.0216 88.6162 180)
		(property "Reference" "R11"
			(at 0.228605 1.273079 0)
			(unlocked yes)
			(layer "B.SilkS")
			(effects
				(font
					(size 0.762 0.762)
					(thickness 0.2286)
				)
				(justify mirror)
			)
		)
		(property "Value" "4.7K"
			(at -2.630671 -2.57723 90)
			(unlocked yes)
			(layer "B.SilkS")
			(hide yes)
			(effects
				(font
					(size 0.762 0.762)
					(thickness 0.2286)
				)
				(justify mirror)
			)
		)
		(sheetname "06-MAC")
		(sheetfile "06-MAC.kicad_sch")
		(duplicate_pad_numbers_are_jumpers no)
		(pad "1" smd rect
			(at -0.65 0 90)
			(size 0.8 0.6)
			(layers "B.Cu" "B.Mask" "B.Paste")
			(net "GND")
		)
		(pad "2" smd rect
			(at 0.65 0 90)
			(size 0.8 0.6)
			(layers "B.Cu" "B.Mask" "B.Paste")
			(net "FPGA_MAC_PPS_DIFF_IN0")
		)
	)
	(footprint "Vault:FP-0402-L_1_0_1-W_0_5_0_1-IPC_C"
		(layer "B.Cu")
		(at 223.56155 125.79915 90)
		(property "Reference" "C115"
			(at 2.32895 0.886971 90)
			(unlocked yes)
			(layer "B.SilkS")
			(effects
				(font
					(size 0.762 0.762)
					(thickness 0.254)
				)
				(justify mirror)
			)
		)
		(property "Value" "0.1uF_25V_0402"
			(at -2.465561 -9.864615 0)
			(unlocked yes)
			(layer "B.SilkS")
			(hide yes)
			(effects
				(font
					(size 0.762 0.762)
					(thickness 0.254)
				)
				(justify mirror)
			)
		)
		(sheetname "09-USBUart_PPSMUX_UARTMUX")
		(sheetfile "09-USBUart_PPSMUX_UARTMUX.kicad_sch")
		(duplicate_pad_numbers_are_jumpers no)
		(fp_line
			(start -0.65607 -0.7)
			(end 0.65606 -0.7)
			(stroke
				(width 0.2)
				(type solid)
			)
			(layer "B.SilkS")
		)
		(fp_line
			(start -0.65607 0.7)
			(end 0.65606 0.7)
			(stroke
				(width 0.2)
				(type solid)
			)
			(layer "B.SilkS")
		)
		(fp_line
			(start 0.75606 -0.4)
			(end 0.75606 0.4)
			(stroke
				(width 0.2)
				(type solid)
			)
			(layer "B.CrtYd")
		)
		(fp_line
			(start -0.75607 -0.4)
			(end 0.75606 -0.4)
			(stroke
				(width 0.2)
				(type solid)
			)
			(layer "B.CrtYd")
		)
		(fp_line
			(start -0.75607 -0.4)
			(end -0.75607 0.4)
			(stroke
				(width 0.2)
				(type solid)
			)
			(layer "B.CrtYd")
		)
		(fp_line
			(start -0.75607 0.4)
			(end 0.75606 0.4)
			(stroke
				(width 0.2)
				(type solid)
			)
			(layer "B.CrtYd")
		)
		(fp_line
			(start 0 -0.5)
			(end 0 0.5)
			(stroke
				(width 0.1)
				(type solid)
			)
			(layer "B.Fab")
		)
		(fp_line
			(start 0.75606 -0.4)
			(end 0.75606 0.4)
			(stroke
				(width 0.2)
				(type solid)
			)
			(layer "B.Fab")
		)
		(fp_line
			(start -0.75607 -0.4)
			(end 0.75606 -0.4)
			(stroke
				(width 0.2)
				(type solid)
			)
			(layer "B.Fab")
		)
		(fp_line
			(start -0.75607 -0.4)
			(end -0.75607 0.4)
			(stroke
				(width 0.2)
				(type solid)
			)
			(layer "B.Fab")
		)
		(fp_line
			(start -0.5 0)
			(end 0.49999 0)
			(stroke
				(width 0.1)
				(type solid)
			)
			(layer "B.Fab")
		)
		(fp_line
			(start -0.75607 0.4)
			(end 0.75606 0.4)
			(stroke
				(width 0.2)
				(type solid)
			)
			(layer "B.Fab")
		)
		(fp_text user "${REFERENCE}"
			(at -0.00002 -0.09602 270)
			(unlocked yes)
			(layer "B.Fab")
			(effects
				(font
					(face "Arial")
					(size 0.63 0.63)
					(thickness 0.1)
				)
				(justify left bottom mirror)
			)
		)
		(pad "1" smd rect
			(at -0.36554 0 90)
			(size 0.58106 0.51213)
			(layers "B.Cu" "B.Mask" "B.Paste")
			(net "FTDI_VBUS")
			(solder_mask_margin 0)
			(solder_paste_margin 0)
		)
		(pad "2" smd rect
			(at 0.36553 0 90)
			(size 0.58106 0.51213)
			(layers "B.Cu" "B.Mask" "B.Paste")
			(net "GND")
			(solder_mask_margin 0)
			(solder_paste_margin 0)
		)
	)
	(footprint "Vault:RESC1005X40X25LL05T05"
		(layer "B.Cu")
		(at 113.78072 88.0662 -90)
		(property "Reference" "R52"
			(at 0.0214 -0.913949 270)
			(unlocked yes)
			(layer "B.SilkS")
			(effects
				(font
					(size 0.762 0.762)
					(thickness 0.2286)
				)
				(justify mirror)
			)
		)
		(property "Value" "4.7K_0402"
			(at -3.024391 -2.374045 180)
			(unlocked yes)
			(layer "B.SilkS")
			(hide yes)
			(effects
				(font
					(size 0.762 0.762)
					(thickness 0.2286)
				)
				(justify mirror)
			)
		)
		(sheetname "05-GPS_IMU_SENSORS")
		(sheetfile "05-GPS_IMU_SENSORS.kicad_sch")
		(duplicate_pad_numbers_are_jumpers no)
		(pad "1" smd rect
			(at -0.4 0 180)
			(size 0.45 0.45)
			(layers "B.Cu" "B.Mask" "B.Paste")
			(net "NetR52_1")
		)
		(pad "2" smd rect
			(at 0.4 0 180)
			(size 0.45 0.45)
			(layers "B.Cu" "B.Mask" "B.Paste")
			(net "BNO_P3V3")
		)
	)
	(footprint "Vault:FP-0402-L_1_0_1-W_0_5_0_1-IPC_C"
		(layer "B.Cu")
		(at 227.8216 115.7162)
		(property "Reference" "C93"
			(at 0.2286 1.473069 180)
			(unlocked yes)
			(layer "B.SilkS")
			(effects
				(font
					(size 0.762 0.762)
					(thickness 0.2286)
				)
				(justify mirror)
			)
		)
		(property "Value" "0.1uF_25V_0402"
			(at -2.465551 -9.839215 270)
			(unlocked yes)
			(layer "B.SilkS")
			(hide yes)
			(effects
				(font
					(size 0.762 0.762)
					(thickness 0.2286)
				)
				(justify mirror)
			)
		)
		(sheetname "09-USBUart_PPSMUX_UARTMUX")
		(sheetfile "09-USBUart_PPSMUX_UARTMUX.kicad_sch")
		(duplicate_pad_numbers_are_jumpers no)
		(fp_line
			(start -0.65607 -0.7)
			(end 0.65607 -0.7)
			(stroke
				(width 0.2)
				(type solid)
			)
			(layer "B.SilkS")
		)
		(fp_line
			(start -0.65607 0.7)
			(end 0.65607 0.7)
			(stroke
				(width 0.2)
				(type solid)
			)
			(layer "B.SilkS")
		)
		(fp_line
			(start -0.75607 -0.4)
			(end 0.75607 -0.4)
			(stroke
				(width 0.2)
				(type solid)
			)
			(layer "B.CrtYd")
		)
		(fp_line
			(start -0.75607 0.4)
			(end -0.75607 -0.4)
			(stroke
				(width 0.2)
				(type solid)
			)
			(layer "B.CrtYd")
		)
		(fp_line
			(start -0.75607 0.4)
			(end 0.75607 0.4)
			(stroke
				(width 0.2)
				(type solid)
			)
			(layer "B.CrtYd")
		)
		(fp_line
			(start 0.75607 0.4)
			(end 0.75607 -0.4)
			(stroke
				(width 0.2)
				(type solid)
			)
			(layer "B.CrtYd")
		)
		(fp_line
			(start -0.75607 -0.4)
			(end 0.75607 -0.4)
			(stroke
				(width 0.2)
				(type solid)
			)
			(layer "B.Fab")
		)
		(fp_line
			(start -0.75607 0.4)
			(end -0.75607 -0.4)
			(stroke
				(width 0.2)
				(type solid)
			)
			(layer "B.Fab")
		)
		(fp_line
			(start -0.75607 0.4)
			(end 0.75607 0.4)
			(stroke
				(width 0.2)
				(type solid)
			)
			(layer "B.Fab")
		)
		(fp_line
			(start -0.5 0)
			(end 0.5 0)
			(stroke
				(width 0.1)
				(type solid)
			)
			(layer "B.Fab")
		)
		(fp_line
			(start 0 0.5)
			(end 0 -0.5)
			(stroke
				(width 0.1)
				(type solid)
			)
			(layer "B.Fab")
		)
		(fp_line
			(start 0.75607 0.4)
			(end 0.75607 -0.4)
			(stroke
				(width 0.2)
				(type solid)
			)
			(layer "B.Fab")
		)
		(fp_text user "${REFERENCE}"
			(at -0.00002 -0.09601 180)
			(unlocked yes)
			(layer "B.Fab")
			(effects
				(font
					(face "Arial")
					(size 0.63 0.63)
					(thickness 0.1)
				)
				(justify left bottom mirror)
			)
		)
		(pad "1" smd rect
			(at -0.36554 0)
			(size 0.58106 0.51213)
			(layers "B.Cu" "B.Mask" "B.Paste")
			(net "NetC92_1")
			(solder_mask_margin 0)
			(solder_paste_margin 0)
		)
		(pad "2" smd rect
			(at 0.36554 0)
			(size 0.58106 0.51213)
			(layers "B.Cu" "B.Mask" "B.Paste")
			(net "GND")
			(solder_mask_margin 0)
			(solder_paste_margin 0)
		)
	)
	(footprint "Vault:FP-0402-L_1_0_1-W_0_5_0_1-IPC_C"
		(layer "B.Cu")
		(at 201.0716 121.19078)
		(property "Reference" "C102"
			(at 2.1468 0.152341 0)
			(unlocked yes)
			(layer "B.SilkS")
			(effects
				(font
					(size 0.762 0.762)
					(thickness 0.2032)
				)
				(justify mirror)
			)
		)
		(property "Value" "0.1uF_25V_0402"
			(at -2.465551 -9.813805 270)
			(unlocked yes)
			(layer "B.SilkS")
			(hide yes)
			(effects
				(font
					(size 0.762 0.762)
					(thickness 0.2032)
				)
				(justify mirror)
			)
		)
		(sheetname "10-M2_GPS")
		(sheetfile "10-M2_GPS.kicad_sch")
		(duplicate_pad_numbers_are_jumpers no)
		(fp_line
			(start -0.65607 -0.7)
			(end 0.65606 -0.7)
			(stroke
				(width 0.2)
				(type solid)
			)
			(layer "B.SilkS")
		)
		(fp_line
			(start -0.65607 0.70001)
			(end 0.65606 0.70001)
			(stroke
				(width 0.2)
				(type solid)
			)
			(layer "B.SilkS")
		)
		(fp_line
			(start -0.75607 -0.4)
			(end 0.75606 -0.4)
			(stroke
				(width 0.2)
				(type solid)
			)
			(layer "B.CrtYd")
		)
		(fp_line
			(start -0.75607 0.4)
			(end -0.75607 -0.4)
			(stroke
				(width 0.2)
				(type solid)
			)
			(layer "B.CrtYd")
		)
		(fp_line
			(start -0.75607 0.4)
			(end 0.75606 0.4)
			(stroke
				(width 0.2)
				(type solid)
			)
			(layer "B.CrtYd")
		)
		(fp_line
			(start 0.75606 0.4)
			(end 0.75606 -0.4)
			(stroke
				(width 0.2)
				(type solid)
			)
			(layer "B.CrtYd")
		)
		(fp_line
			(start -0.75607 -0.4)
			(end 0.75606 -0.4)
			(stroke
				(width 0.2)
				(type solid)
			)
			(layer "B.Fab")
		)
		(fp_line
			(start -0.75607 0.4)
			(end -0.75607 -0.4)
			(stroke
				(width 0.2)
				(type solid)
			)
			(layer "B.Fab")
		)
		(fp_line
			(start -0.75607 0.4)
			(end 0.75606 0.4)
			(stroke
				(width 0.2)
				(type solid)
			)
			(layer "B.Fab")
		)
		(fp_line
			(start -0.5 0)
			(end 0.5 0)
			(stroke
				(width 0.1)
				(type solid)
			)
			(layer "B.Fab")
		)
		(fp_line
			(start 0 0.5)
			(end 0 -0.49999)
			(stroke
				(width 0.1)
				(type solid)
			)
			(layer "B.Fab")
		)
		(fp_line
			(start 0.75606 0.4)
			(end 0.75606 -0.4)
			(stroke
				(width 0.2)
				(type solid)
			)
			(layer "B.Fab")
		)
		(fp_text user "${REFERENCE}"
			(at -0.00001 -0.09601 180)
			(unlocked yes)
			(layer "B.Fab")
			(effects
				(font
					(face "Arial")
					(size 0.63 0.63)
					(thickness 0.1)
				)
				(justify left bottom mirror)
			)
		)
		(pad "1" smd rect
			(at -0.36554 0)
			(size 0.58106 0.51213)
			(layers "B.Cu" "B.Mask" "B.Paste")
			(net "GNSS2_P3V3")
			(solder_mask_margin 0)
			(solder_paste_margin 0)
		)
		(pad "2" smd rect
			(at 0.36553 0)
			(size 0.58106 0.51213)
			(layers "B.Cu" "B.Mask" "B.Paste")
			(net "GND")
			(solder_mask_margin 0)
			(solder_paste_margin 0)
		)
	)
	(footprint "Capacitors:CAPC1005X06N"
		(layer "B.Cu")
		(at 140.5596 151.7886 90)
		(property "Reference" "C52"
			(at 2.41349 -0.613855 270)
			(unlocked yes)
			(layer "B.SilkS")
			(effects
				(font
					(size 0.762 0.762)
					(thickness 0.2286)
				)
				(justify left bottom mirror)
			)
		)
		(property "Value" "CAP_0402_0.1UF_50V"
			(at -3.382645 0.2921 0)
			(unlocked yes)
			(layer "B.SilkS")
			(hide yes)
			(effects
				(font
					(size 0.762 0.762)
					(thickness 0.2286)
				)
				(justify left bottom mirror)
			)
		)
		(sheetname "04-PCIe_JTAG")
		(sheetfile "04-PCIe_JTAG.kicad_sch")
		(duplicate_pad_numbers_are_jumpers no)
		(pad "1" smd rect
			(at -0.43 0)
			(size 0.64 0.68)
			(layers "B.Cu" "B.Mask" "B.Paste")
			(net "NetC52_1")
		)
		(pad "2" smd rect
			(at 0.43 0)
			(size 0.64 0.68)
			(layers "B.Cu" "B.Mask" "B.Paste")
			(net "PCIE_TX3_P")
		)
	)
	(footprint "Vault:FP-0402-L_1_0_1-W_0_5_0_1-IPC_C"
		(layer "B.Cu")
		(at 125.3216 54.4162 90)
		(property "Reference" "C74"
			(at 2.4968 0.026931 90)
			(unlocked yes)
			(layer "B.SilkS")
			(effects
				(font
					(size 0.762 0.762)
					(thickness 0.2032)
				)
				(justify mirror)
			)
		)
		(property "Value" "0.1uF_25V_0402"
			(at -2.465551 -9.813815 0)
			(unlocked yes)
			(layer "B.SilkS")
			(hide yes)
			(effects
				(font
					(size 0.762 0.762)
					(thickness 0.2032)
				)
				(justify mirror)
			)
		)
		(sheetname "10-M2_GPS")
		(sheetfile "10-M2_GPS.kicad_sch")
		(duplicate_pad_numbers_are_jumpers no)
		(fp_line
			(start -0.65607 -0.7)
			(end 0.65607 -0.7)
			(stroke
				(width 0.2)
				(type solid)
			)
			(layer "B.SilkS")
		)
		(fp_line
			(start -0.65607 0.7)
			(end 0.65607 0.7)
			(stroke
				(width 0.2)
				(type solid)
			)
			(layer "B.SilkS")
		)
		(fp_line
			(start 0.75607 -0.4)
			(end 0.75607 0.4)
			(stroke
				(width 0.2)
				(type solid)
			)
			(layer "B.CrtYd")
		)
		(fp_line
			(start -0.75606 -0.4)
			(end 0.75607 -0.4)
			(stroke
				(width 0.2)
				(type solid)
			)
			(layer "B.CrtYd")
		)
		(fp_line
			(start -0.75606 -0.4)
			(end -0.75606 0.4)
			(stroke
				(width 0.2)
				(type solid)
			)
			(layer "B.CrtYd")
		)
		(fp_line
			(start -0.75606 0.4)
			(end 0.75607 0.4)
			(stroke
				(width 0.2)
				(type solid)
			)
			(layer "B.CrtYd")
		)
		(fp_line
			(start 0 -0.5)
			(end 0 0.5)
			(stroke
				(width 0.1)
				(type solid)
			)
			(layer "B.Fab")
		)
		(fp_line
			(start 0.75607 -0.4)
			(end 0.75607 0.4)
			(stroke
				(width 0.2)
				(type solid)
			)
			(layer "B.Fab")
		)
		(fp_line
			(start -0.75606 -0.4)
			(end 0.75607 -0.4)
			(stroke
				(width 0.2)
				(type solid)
			)
			(layer "B.Fab")
		)
		(fp_line
			(start -0.75606 -0.4)
			(end -0.75606 0.4)
			(stroke
				(width 0.2)
				(type solid)
			)
			(layer "B.Fab")
		)
		(fp_line
			(start -0.5 0)
			(end 0.5 0)
			(stroke
				(width 0.1)
				(type solid)
			)
			(layer "B.Fab")
		)
		(fp_line
			(start -0.75606 0.4)
			(end 0.75607 0.4)
			(stroke
				(width 0.2)
				(type solid)
			)
			(layer "B.Fab")
		)
		(fp_text user "${REFERENCE}"
			(at -0.00001 -0.09602 270)
			(unlocked yes)
			(layer "B.Fab")
			(effects
				(font
					(face "Arial")
					(size 0.63 0.63)
					(thickness 0.1)
				)
				(justify left bottom mirror)
			)
		)
		(pad "1" smd rect
			(at -0.36553 0 90)
			(size 0.58106 0.51213)
			(layers "B.Cu" "B.Mask" "B.Paste")
			(net "+3.3V")
			(solder_mask_margin 0)
			(solder_paste_margin 0)
		)
		(pad "2" smd rect
			(at 0.36554 0 90)
			(size 0.58106 0.51213)
			(layers "B.Cu" "B.Mask" "B.Paste")
			(net "GND")
			(solder_mask_margin 0)
			(solder_paste_margin 0)
		)
	)
	(footprint "Vault:FP-0402-L_1_0_1-W_0_5_0_1-IPC_C"
		(layer "B.Cu")
		(at 210.41727 124.16632 90)
		(property "Reference" "C110"
			(at 1.99612 0.131251 90)
			(unlocked yes)
			(layer "B.SilkS")
			(effects
				(font
					(size 0.762 0.762)
					(thickness 0.254)
				)
				(justify mirror)
			)
		)
		(property "Value" "0.1uF_25V_0402"
			(at -2.465551 -9.864615 0)
			(unlocked yes)
			(layer "B.SilkS")
			(hide yes)
			(effects
				(font
					(size 0.762 0.762)
					(thickness 0.254)
				)
				(justify mirror)
			)
		)
		(sheetname "09-USBUart_PPSMUX_UARTMUX")
		(sheetfile "09-USBUart_PPSMUX_UARTMUX.kicad_sch")
		(duplicate_pad_numbers_are_jumpers no)
		(fp_line
			(start -0.65607 -0.7)
			(end 0.65607 -0.7)
			(stroke
				(width 0.2)
				(type solid)
			)
			(layer "B.SilkS")
		)
		(fp_line
			(start -0.65607 0.7)
			(end 0.65607 0.7)
			(stroke
				(width 0.2)
				(type solid)
			)
			(layer "B.SilkS")
		)
		(fp_line
			(start 0.75607 -0.4)
			(end 0.75607 0.4)
			(stroke
				(width 0.2)
				(type solid)
			)
			(layer "B.CrtYd")
		)
		(fp_line
			(start -0.75607 -0.4)
			(end 0.75607 -0.4)
			(stroke
				(width 0.2)
				(type solid)
			)
			(layer "B.CrtYd")
		)
		(fp_line
			(start -0.75607 -0.4)
			(end -0.75607 0.4)
			(stroke
				(width 0.2)
				(type solid)
			)
			(layer "B.CrtYd")
		)
		(fp_line
			(start -0.75607 0.4)
			(end 0.75607 0.4)
			(stroke
				(width 0.2)
				(type solid)
			)
			(layer "B.CrtYd")
		)
		(fp_line
			(start 0 -0.5)
			(end 0 0.5)
			(stroke
				(width 0.1)
				(type solid)
			)
			(layer "B.Fab")
		)
		(fp_line
			(start 0.75607 -0.4)
			(end 0.75607 0.4)
			(stroke
				(width 0.2)
				(type solid)
			)
			(layer "B.Fab")
		)
		(fp_line
			(start -0.75607 -0.4)
			(end 0.75607 -0.4)
			(stroke
				(width 0.2)
				(type solid)
			)
			(layer "B.Fab")
		)
		(fp_line
			(start -0.75607 -0.4)
			(end -0.75607 0.4)
			(stroke
				(width 0.2)
				(type solid)
			)
			(layer "B.Fab")
		)
		(fp_line
			(start -0.5 0)
			(end 0.5 0)
			(stroke
				(width 0.1)
				(type solid)
			)
			(layer "B.Fab")
		)
		(fp_line
			(start -0.75607 0.4)
			(end 0.75607 0.4)
			(stroke
				(width 0.2)
				(type solid)
			)
			(layer "B.Fab")
		)
		(fp_text user "${REFERENCE}"
			(at -0.00001 -0.09602 270)
			(unlocked yes)
			(layer "B.Fab")
			(effects
				(font
					(face "Arial")
					(size 0.63 0.63)
					(thickness 0.1)
				)
				(justify left bottom mirror)
			)
		)
		(pad "1" smd rect
			(at -0.36554 0 90)
			(size 0.58106 0.51213)
			(layers "B.Cu" "B.Mask" "B.Paste")
			(net "GNSS2_P3V3")
			(solder_mask_margin 0)
			(solder_paste_margin 0)
		)
		(pad "2" smd rect
			(at 0.36554 0 90)
			(size 0.58106 0.51213)
			(layers "B.Cu" "B.Mask" "B.Paste")
			(net "GND")
			(solder_mask_margin 0)
			(solder_paste_margin 0)
		)
	)
	(footprint "Vault:RESC1005X40X25NL10T10"
		(layer "B.Cu")
		(at 95.2756 59.4162)
		(property "Reference" "R5"
			(at -0.554 0.906655 180)
			(unlocked yes)
			(layer "B.SilkS")
			(effects
				(font
					(size 0.762 0.762)
					(thickness 0.2286)
				)
				(justify left bottom mirror)
			)
		)
		(property "Value" "4.7K_1%_0402"
			(at -0.6183 32.959045 0)
			(unlocked yes)
			(layer "B.SilkS")
			(hide yes)
			(effects
				(font
					(size 0.762 0.762)
					(thickness 0.2286)
				)
				(justify left bottom mirror)
			)
		)
		(sheetname "03-POWER")
		(sheetfile "03-POWER.kicad_sch")
		(duplicate_pad_numbers_are_jumpers no)
		(pad "1" smd rect
			(at -0.425 0 270)
			(size 0.6 0.65)
			(layers "B.Cu" "B.Mask" "B.Paste")
			(net "NetR5_1")
		)
		(pad "2" smd rect
			(at 0.425 0 270)
			(size 0.6 0.65)
			(layers "B.Cu" "B.Mask" "B.Paste")
			(net "+12V")
		)
	)
	(footprint "Vault:FP-0603-L_1_6_0_2-W_0_8_0-MFG"
		(layer "B.Cu")
		(at 170.15457 89.4162 180)
		(property "Reference" "C85"
			(at 0.36157 1.573069 0)
			(unlocked yes)
			(layer "B.SilkS")
			(effects
				(font
					(size 0.762 0.762)
					(thickness 0.2286)
				)
				(justify mirror)
			)
		)
		(property "Value" "10uF_16V_0603"
			(at -2.871951 -8.95046 90)
			(unlocked yes)
			(layer "B.SilkS")
			(hide yes)
			(effects
				(font
					(size 0.762 0.762)
					(thickness 0.2286)
				)
				(justify mirror)
			)
		)
		(sheetname "03-POWER")
		(sheetfile "03-POWER.kicad_sch")
		(duplicate_pad_numbers_are_jumpers no)
		(fp_line
			(start 0.9 0.825)
			(end -0.9 0.825)
			(stroke
				(width 0.2)
				(type solid)
			)
			(layer "B.SilkS")
		)
		(fp_line
			(start 0.9 -0.825)
			(end -0.9 -0.825)
			(stroke
				(width 0.2)
				(type solid)
			)
			(layer "B.SilkS")
		)
		(fp_line
			(start 1.15 0.6)
			(end -1.15 0.6)
			(stroke
				(width 0.2)
				(type solid)
			)
			(layer "B.CrtYd")
		)
		(fp_line
			(start 1.15 -0.6)
			(end 1.15 0.6)
			(stroke
				(width 0.2)
				(type solid)
			)
			(layer "B.CrtYd")
		)
		(fp_line
			(start 1.15 -0.6)
			(end -1.15 -0.6)
			(stroke
				(width 0.2)
				(type solid)
			)
			(layer "B.CrtYd")
		)
		(fp_line
			(start -1.15 -0.6)
			(end -1.15 0.6)
			(stroke
				(width 0.2)
				(type solid)
			)
			(layer "B.CrtYd")
		)
		(fp_line
			(start 1.15 0.6)
			(end -1.15 0.6)
			(stroke
				(width 0.2)
				(type solid)
			)
			(layer "B.Fab")
		)
		(fp_line
			(start 1.15 -0.6)
			(end 1.15 0.6)
			(stroke
				(width 0.2)
				(type solid)
			)
			(layer "B.Fab")
		)
		(fp_line
			(start 1.15 -0.6)
			(end -1.15 -0.6)
			(stroke
				(width 0.2)
				(type solid)
			)
			(layer "B.Fab")
		)
		(fp_line
			(start 0.5 0)
			(end -0.5 0)
			(stroke
				(width 0.1)
				(type solid)
			)
			(layer "B.Fab")
		)
		(fp_line
			(start 0 -0.5)
			(end 0 0.5)
			(stroke
				(width 0.1)
				(type solid)
			)
			(layer "B.Fab")
		)
		(fp_line
			(start -1.15 -0.6)
			(end -1.15 0.6)
			(stroke
				(width 0.2)
				(type solid)
			)
			(layer "B.Fab")
		)
		(fp_text user "${REFERENCE}"
			(at -0.00001 -0.09602 360)
			(unlocked yes)
			(layer "B.Fab")
			(effects
				(font
					(face "Arial")
					(size 0.63 0.63)
					(thickness 0.1)
				)
				(justify left bottom mirror)
			)
		)
		(pad "1" smd rect
			(at -0.7 0 180)
			(size 0.7 0.7)
			(layers "B.Cu" "B.Mask" "B.Paste")
			(net "+3.3V")
			(solder_mask_margin 0)
			(solder_paste_margin 0)
		)
		(pad "2" smd rect
			(at 0.7 0 180)
			(size 0.7 0.7)
			(layers "B.Cu" "B.Mask" "B.Paste")
			(net "GND")
			(solder_mask_margin 0)
			(solder_paste_margin 0)
		)
	)
	(footprint "Vault:RESC1005X40X25NL10T10"
		(layer "B.Cu")
		(at 207.14172 117.4412 180)
		(property "Reference" "R137"
			(at -2.77668 -0.201921 0)
			(unlocked yes)
			(layer "B.SilkS")
			(effects
				(font
					(size 0.762 0.762)
					(thickness 0.2032)
				)
				(justify mirror)
			)
		)
		(property "Value" "4.7K_1%_0402"
			(at -2.732271 -8.747465 90)
			(unlocked yes)
			(layer "B.SilkS")
			(hide yes)
			(effects
				(font
					(size 0.762 0.762)
					(thickness 0.2032)
				)
				(justify mirror)
			)
		)
		(sheetname "10-M2_GPS")
		(sheetfile "10-M2_GPS.kicad_sch")
		(duplicate_pad_numbers_are_jumpers no)
		(pad "1" smd rect
			(at -0.425 0 90)
			(size 0.6 0.65)
			(layers "B.Cu" "B.Mask" "B.Paste")
			(net "GPS2_PIN15")
		)
		(pad "2" smd rect
			(at 0.425 0 90)
			(size 0.6 0.65)
			(layers "B.Cu" "B.Mask" "B.Paste")
			(net "GNSS2_P3V3")
		)
	)
	(footprint "Vault:RESC1005X40X25NL10T10"
		(layer "B.Cu")
		(at 207.65181 118.8412 180)
		(property "Reference" "R136"
			(at -2.96659 -0.001921 0)
			(unlocked yes)
			(layer "B.SilkS")
			(effects
				(font
					(size 0.762 0.762)
					(thickness 0.2032)
				)
				(justify mirror)
			)
		)
		(property "Value" "4.7K_1%_0402"
			(at -2.732271 -8.747465 90)
			(unlocked yes)
			(layer "B.SilkS")
			(hide yes)
			(effects
				(font
					(size 0.762 0.762)
					(thickness 0.2032)
				)
				(justify mirror)
			)
		)
		(sheetname "10-M2_GPS")
		(sheetfile "10-M2_GPS.kicad_sch")
		(duplicate_pad_numbers_are_jumpers no)
		(pad "1" smd rect
			(at -0.425 0 90)
			(size 0.6 0.65)
			(layers "B.Cu" "B.Mask" "B.Paste")
			(net "GPS2_PIN14")
		)
		(pad "2" smd rect
			(at 0.425 0 90)
			(size 0.6 0.65)
			(layers "B.Cu" "B.Mask" "B.Paste")
			(net "GNSS2_P3V3")
		)
	)
	(footprint "Vault:CAPC1005X56X25NL10T15"
		(layer "B.Cu")
		(at 227.3216 70.3162)
		(property "Reference" "C19"
			(at 1.046 -1.141655 0)
			(unlocked yes)
			(layer "B.SilkS")
			(effects
				(font
					(size 0.762 0.762)
					(thickness 0.2286)
				)
				(justify left bottom mirror)
			)
		)
		(property "Value" "0.1uF_25V_0402"
			(at -9.4735 -2.041355 0)
			(unlocked yes)
			(layer "B.SilkS")
			(hide yes)
			(effects
				(font
					(size 0.762 0.762)
					(thickness 0.2286)
				)
				(justify left bottom mirror)
			)
		)
		(sheetname "03-POWER")
		(sheetfile "03-POWER.kicad_sch")
		(duplicate_pad_numbers_are_jumpers no)
		(pad "1" smd rect
			(at -0.44 0 270)
			(size 0.64 0.68)
			(layers "B.Cu" "B.Mask" "B.Paste")
			(net "GND")
		)
		(pad "2" smd rect
			(at 0.44 0 270)
			(size 0.64 0.68)
			(layers "B.Cu" "B.Mask" "B.Paste")
			(net "+3.3V")
		)
	)
	(footprint "LotusSound:IC_TPS2116"
		(layer "B.Cu")
		(at 216.33831 126.11791)
		(property "Reference" "U34"
			(at -8.29034 6.754171 0)
			(unlocked yes)
			(layer "B.SilkS")
			(hide yes)
			(effects
				(font
					(size 0.762 0.762)
					(thickness 0.2032)
				)
				(justify mirror)
			)
		)
		(property "Value" "TPS2116DRLR"
			(at -14.143155 12.458271 0)
			(unlocked yes)
			(layer "B.SilkS")
			(hide yes)
			(effects
				(font
					(size 0.762 0.762)
					(thickness 0.2032)
				)
				(justify mirror)
			)
		)
		(sheetname "09-USBUart_PPSMUX_UARTMUX")
		(sheetfile "09-USBUart_PPSMUX_UARTMUX.kicad_sch")
		(duplicate_pad_numbers_are_jumpers no)
		(fp_line
			(start -0.6 -1.23)
			(end 0.6 -1.23)
			(stroke
				(width 0.127)
				(type solid)
			)
			(layer "B.SilkS")
		)
		(fp_line
			(start -0.6 1.23)
			(end 0.6 1.23)
			(stroke
				(width 0.127)
				(type solid)
			)
			(layer "B.SilkS")
		)
		(fp_circle
			(center -1.6 0.75001)
			(end -1.6 0.65001)
			(stroke
				(width 0.2)
				(type solid)
			)
			(fill no)
			(layer "B.SilkS")
		)
		(pad "1" smd roundrect
			(at -0.735 0.75001)
			(size 0.66 0.32)
			(layers "B.Cu" "B.Mask" "B.Paste")
			(roundrect_rratio 0.125)
			(net "GND")
		)
		(pad "2" smd roundrect
			(at -0.735 0.25)
			(size 0.66 0.32)
			(layers "B.Cu" "B.Mask" "B.Paste")
			(roundrect_rratio 0.125)
			(net "GNSS2_P5V0")
		)
		(pad "3" smd roundrect
			(at -0.735 -0.25)
			(size 0.66 0.32)
			(layers "B.Cu" "B.Mask" "B.Paste")
			(roundrect_rratio 0.125)
			(net "+5.0V")
		)
		(pad "4" smd roundrect
			(at -0.735 -0.75)
			(size 0.66 0.32)
			(layers "B.Cu" "B.Mask" "B.Paste")
			(roundrect_rratio 0.125)
			(net "NetR180_1")
		)
		(pad "5" smd roundrect
			(at 0.735 -0.75)
			(size 0.66 0.32)
			(layers "B.Cu" "B.Mask" "B.Paste")
			(roundrect_rratio 0.125)
			(net "+5.0V")
		)
		(pad "6" smd roundrect
			(at 0.735 -0.25)
			(size 0.66 0.32)
			(layers "B.Cu" "B.Mask" "B.Paste")
			(roundrect_rratio 0.125)
			(net "FTDI_VBUS")
		)
		(pad "7" smd roundrect
			(at 0.735 0.25)
			(size 0.66 0.32)
			(layers "B.Cu" "B.Mask" "B.Paste")
			(roundrect_rratio 0.125)
			(net "GNSS2_P5V0")
		)
		(pad "8" smd roundrect
			(at 0.735 0.75001)
			(size 0.66 0.32)
			(layers "B.Cu" "B.Mask" "B.Paste")
			(roundrect_rratio 0.125)
		)
	)
	(footprint "Vault:FP-0402-L_1_0_1-W_0_5_0_1-IPC_C"
		(layer "B.Cu")
		(at 143.7216 104.7162 -90)
		(property "Reference" "C96"
			(at 0.2286 1.595239 90)
			(unlocked yes)
			(layer "B.SilkS")
			(effects
				(font
					(size 0.762 0.762)
					(thickness 0.2286)
				)
				(justify mirror)
			)
		)
		(property "Value" "0.1uF_25V_0402"
			(at -2.465551 -9.839205 180)
			(unlocked yes)
			(layer "B.SilkS")
			(hide yes)
			(effects
				(font
					(size 0.762 0.762)
					(thickness 0.2286)
				)
				(justify mirror)
			)
		)
		(sheetname "09-USBUart_PPSMUX_UARTMUX")
		(sheetfile "09-USBUart_PPSMUX_UARTMUX.kicad_sch")
		(duplicate_pad_numbers_are_jumpers no)
		(fp_line
			(start 0.65607 0.7)
			(end -0.65607 0.7)
			(stroke
				(width 0.2)
				(type solid)
			)
			(layer "B.SilkS")
		)
		(fp_line
			(start 0.65607 -0.7)
			(end -0.65607 -0.7)
			(stroke
				(width 0.2)
				(type solid)
			)
			(layer "B.SilkS")
		)
		(fp_line
			(start -0.75607 0.4)
			(end -0.75607 -0.4)
			(stroke
				(width 0.2)
				(type solid)
			)
			(layer "B.CrtYd")
		)
		(fp_line
			(start 0.75607 0.4)
			(end -0.75607 0.4)
			(stroke
				(width 0.2)
				(type solid)
			)
			(layer "B.CrtYd")
		)
		(fp_line
			(start 0.75607 0.4)
			(end 0.75607 -0.4)
			(stroke
				(width 0.2)
				(type solid)
			)
			(layer "B.CrtYd")
		)
		(fp_line
			(start 0.75607 -0.4)
			(end -0.75607 -0.4)
			(stroke
				(width 0.2)
				(type solid)
			)
			(layer "B.CrtYd")
		)
		(fp_line
			(start 0 0.5)
			(end 0 -0.5)
			(stroke
				(width 0.1)
				(type solid)
			)
			(layer "B.Fab")
		)
		(fp_line
			(start -0.75607 0.4)
			(end -0.75607 -0.4)
			(stroke
				(width 0.2)
				(type solid)
			)
			(layer "B.Fab")
		)
		(fp_line
			(start 0.75607 0.4)
			(end -0.75607 0.4)
			(stroke
				(width 0.2)
				(type solid)
			)
			(layer "B.Fab")
		)
		(fp_line
			(start 0.75607 0.4)
			(end 0.75607 -0.4)
			(stroke
				(width 0.2)
				(type solid)
			)
			(layer "B.Fab")
		)
		(fp_line
			(start 0.5 0)
			(end -0.5 0)
			(stroke
				(width 0.1)
				(type solid)
			)
			(layer "B.Fab")
		)
		(fp_line
			(start 0.75607 -0.4)
			(end -0.75607 -0.4)
			(stroke
				(width 0.2)
				(type solid)
			)
			(layer "B.Fab")
		)
		(fp_text user "${REFERENCE}"
			(at -0.00001 -0.09602 90)
			(unlocked yes)
			(layer "B.Fab")
			(effects
				(font
					(face "Arial")
					(size 0.63 0.63)
					(thickness 0.1)
				)
				(justify left bottom mirror)
			)
		)
		(pad "1" smd rect
			(at -0.36554 0 270)
			(size 0.58106 0.51213)
			(layers "B.Cu" "B.Mask" "B.Paste")
			(net "+3.3V")
			(solder_mask_margin 0)
			(solder_paste_margin 0)
		)
		(pad "2" smd rect
			(at 0.36554 0 270)
			(size 0.58106 0.51213)
			(layers "B.Cu" "B.Mask" "B.Paste")
			(net "GND")
			(solder_mask_margin 0)
			(solder_paste_margin 0)
		)
	)
	(footprint "Vault:CAPC1608X87X45ML20T05"
		(layer "B.Cu")
		(at 103.9741 71.7286 180)
		(property "Reference" "C61"
			(at -1.39159 1.120785 0)
			(unlocked yes)
			(layer "B.SilkS")
			(effects
				(font
					(size 0.762 0.762)
					(thickness 0.2286)
				)
				(justify left bottom mirror)
			)
		)
		(property "Value" "0.1uF"
			(at -0.2921 -3.382645 0)
			(unlocked yes)
			(layer "B.SilkS")
			(hide yes)
			(effects
				(font
					(size 0.762 0.762)
					(thickness 0.2286)
				)
				(justify left bottom mirror)
			)
		)
		(sheetname "05-GPS_IMU_SENSORS")
		(sheetfile "05-GPS_IMU_SENSORS.kicad_sch")
		(duplicate_pad_numbers_are_jumpers no)
		(pad "1" smd rect
			(at -0.7 0 90)
			(size 1.1 1.05)
			(layers "B.Cu" "B.Mask" "B.Paste")
			(net "GND")
		)
		(pad "2" smd rect
			(at 0.7 0 90)
			(size 1.1 1.05)
			(layers "B.Cu" "B.Mask" "B.Paste")
			(net "+5.0V")
		)
	)
	(footprint "Vault:FP-C1005-050-0_05-IPC_A"
		(layer "B.Cu")
		(at 111.0216 80.9162 -90)
		(property "Reference" "C9"
			(at -0.7 1.106655 90)
			(unlocked yes)
			(layer "B.SilkS")
			(effects
				(font
					(size 0.762 0.762)
					(thickness 0.2286)
				)
				(justify left bottom mirror)
			)
		)
		(property "Value" "2.2uF_16V_0402"
			(at 5.939845 -3.6529 0)
			(unlocked yes)
			(layer "B.SilkS")
			(hide yes)
			(effects
				(font
					(size 0.762 0.762)
					(thickness 0.2286)
				)
				(justify left bottom mirror)
			)
		)
		(sheetname "05-GPS_IMU_SENSORS")
		(sheetfile "05-GPS_IMU_SENSORS.kicad_sch")
		(duplicate_pad_numbers_are_jumpers no)
		(fp_line
			(start 0.83624 0.73624)
			(end -0.83624 0.73624)
			(stroke
				(width 0.2)
				(type solid)
			)
			(layer "B.SilkS")
		)
		(fp_line
			(start 0.83624 -0.73624)
			(end -0.83624 -0.73624)
			(stroke
				(width 0.2)
				(type solid)
			)
			(layer "B.SilkS")
		)
		(fp_line
			(start -1.03624 0.53624)
			(end -1.03624 -0.53624)
			(stroke
				(width 0.2)
				(type solid)
			)
			(layer "B.CrtYd")
		)
		(fp_line
			(start 1.03623 0.53624)
			(end -1.03624 0.53624)
			(stroke
				(width 0.2)
				(type solid)
			)
			(layer "B.CrtYd")
		)
		(fp_line
			(start 1.03623 0.53624)
			(end 1.03623 -0.53624)
			(stroke
				(width 0.2)
				(type solid)
			)
			(layer "B.CrtYd")
		)
		(fp_line
			(start 1.03623 -0.53624)
			(end -1.03624 -0.53624)
			(stroke
				(width 0.2)
				(type solid)
			)
			(layer "B.CrtYd")
		)
		(fp_line
			(start -1.03624 0.53624)
			(end -1.03624 -0.53624)
			(stroke
				(width 0.2)
				(type solid)
			)
			(layer "B.Fab")
		)
		(fp_line
			(start 1.03623 0.53624)
			(end -1.03624 0.53624)
			(stroke
				(width 0.2)
				(type solid)
			)
			(layer "B.Fab")
		)
		(fp_line
			(start 1.03623 0.53624)
			(end 1.03623 -0.53624)
			(stroke
				(width 0.2)
				(type solid)
			)
			(layer "B.Fab")
		)
		(fp_line
			(start 0 0.5)
			(end 0 -0.5)
			(stroke
				(width 0.1)
				(type solid)
			)
			(layer "B.Fab")
		)
		(fp_line
			(start 0.5 0)
			(end -0.5 0)
			(stroke
				(width 0.1)
				(type solid)
			)
			(layer "B.Fab")
		)
		(fp_line
			(start 1.03623 -0.53624)
			(end -1.03624 -0.53624)
			(stroke
				(width 0.2)
				(type solid)
			)
			(layer "B.Fab")
		)
		(fp_text user "${REFERENCE}"
			(at -0.00001 -0.09601 90)
			(unlocked yes)
			(layer "B.Fab")
			(effects
				(font
					(face "Arial")
					(size 0.63 0.63)
					(thickness 0.1)
				)
				(justify left bottom mirror)
			)
		)
		(pad "1" smd rect
			(at -0.46658 0 270)
			(size 0.73933 0.67248)
			(layers "B.Cu" "B.Mask" "B.Paste")
			(net "BNO_P3V3")
			(solder_mask_margin 0)
			(solder_paste_margin 0)
		)
		(pad "2" smd rect
			(at 0.46657 0 270)
			(size 0.73933 0.67248)
			(layers "B.Cu" "B.Mask" "B.Paste")
			(net "GND")
			(solder_mask_margin 0)
			(solder_paste_margin 0)
		)
	)
	(footprint "Vault:CAPC1005X56X25NL10T15"
		(layer "B.Cu")
		(at 116.04815 86.2424 90)
		(property "Reference" "C84"
			(at 0.09563 1.073079 270)
			(unlocked yes)
			(layer "B.SilkS")
			(effects
				(font
					(size 0.762 0.762)
					(thickness 0.2286)
				)
				(justify mirror)
			)
		)
		(property "Value" "0.1uF_25V_0402"
			(at -2.592551 -7.071595 0)
			(unlocked yes)
			(layer "B.SilkS")
			(hide yes)
			(effects
				(font
					(size 0.762 0.762)
					(thickness 0.2286)
				)
				(justify mirror)
			)
		)
		(sheetname "05-GPS_IMU_SENSORS")
		(sheetfile "05-GPS_IMU_SENSORS.kicad_sch")
		(duplicate_pad_numbers_are_jumpers no)
		(pad "1" smd rect
			(at -0.43999 0)
			(size 0.64 0.68)
			(layers "B.Cu" "B.Mask" "B.Paste")
			(net "GND")
		)
		(pad "2" smd rect
			(at 0.44001 0)
			(size 0.64 0.68)
			(layers "B.Cu" "B.Mask" "B.Paste")
			(net "BNO_P3V3")
		)
	)
	(footprint "Vault:RESC1005X40X25NL10T10"
		(layer "B.Cu")
		(at 187.1466 92.2162 -90)
		(property "Reference" "R129"
			(at -0.7032 1.226931 270)
			(unlocked yes)
			(layer "B.SilkS")
			(effects
				(font
					(size 0.762 0.762)
					(thickness 0.2032)
				)
				(justify mirror)
			)
		)
		(property "Value" "20K_1%_0402"
			(at -2.579871 -9.560015 180)
			(unlocked yes)
			(layer "B.SilkS")
			(hide yes)
			(effects
				(font
					(size 0.762 0.762)
					(thickness 0.2032)
				)
				(justify mirror)
			)
		)
		(sheetname "03-POWER")
		(sheetfile "03-POWER.kicad_sch")
		(duplicate_pad_numbers_are_jumpers no)
		(pad "1" smd rect
			(at -0.425 0 180)
			(size 0.6 0.65)
			(layers "B.Cu" "B.Mask" "B.Paste")
			(net "+12V")
		)
		(pad "2" smd rect
			(at 0.425 0 180)
			(size 0.6 0.65)
			(layers "B.Cu" "B.Mask" "B.Paste")
			(net "NetR129_2")
		)
	)
	(footprint "Vault:RESC1005X40X25ML10T10"
		(layer "B.Cu")
		(at 86.9716 62.0662)
		(property "Reference" "R26"
			(at -0.1786 -1.323079 0)
			(unlocked yes)
			(layer "B.SilkS")
			(effects
				(font
					(size 0.762 0.762)
					(thickness 0.2286)
				)
				(justify mirror)
			)
		)
		(property "Value" "1.2K_0.5%_0402"
			(at -3.087871 -2.374035 270)
			(unlocked yes)
			(layer "B.SilkS")
			(hide yes)
			(effects
				(font
					(size 0.762 0.762)
					(thickness 0.2286)
				)
				(justify mirror)
			)
		)
		(sheetname "03-POWER")
		(sheetfile "03-POWER.kicad_sch")
		(duplicate_pad_numbers_are_jumpers no)
		(pad "1" smd rect
			(at -0.475 0 270)
			(size 0.7 0.75)
			(layers "B.Cu" "B.Mask" "B.Paste")
			(net "NetR26_1")
		)
		(pad "2" smd rect
			(at 0.475 0 270)
			(size 0.7 0.75)
			(layers "B.Cu" "B.Mask" "B.Paste")
			(net "NetR26_2")
		)
	)
	(footprint "Vault:RESC1005X40X25NL10T10"
		(layer "B.Cu")
		(at 125.5216 64.96075 90)
		(property "Reference" "R132"
			(at -0.25865 -1.473069 90)
			(unlocked yes)
			(layer "B.SilkS")
			(effects
				(font
					(size 0.762 0.762)
					(thickness 0.2032)
				)
				(justify mirror)
			)
		)
		(property "Value" "4.7K_1%_0402"
			(at -2.732271 -8.747465 0)
			(unlocked yes)
			(layer "B.SilkS")
			(hide yes)
			(effects
				(font
					(size 0.762 0.762)
					(thickness 0.2032)
				)
				(justify mirror)
			)
		)
		(sheetname "10-M2_GPS")
		(sheetfile "10-M2_GPS.kicad_sch")
		(duplicate_pad_numbers_are_jumpers no)
		(pad "1" smd rect
			(at -0.425 0)
			(size 0.6 0.65)
			(layers "B.Cu" "B.Mask" "B.Paste")
			(net "GPS1_PIN13")
		)
		(pad "2" smd rect
			(at 0.425 0)
			(size 0.6 0.65)
			(layers "B.Cu" "B.Mask" "B.Paste")
			(net "+3.3V")
		)
	)
	(footprint "Vault:FP-MK212BG-MFG"
		(layer "B.Cu")
		(at 109.87414 66.7286 -90)
		(property "Reference" "C41"
			(at -0.267115 1.591871 270)
			(unlocked yes)
			(layer "B.SilkS")
			(effects
				(font
					(size 0.762 0.762)
					(thickness 0.2286)
				)
				(justify mirror)
			)
		)
		(property "Value" "10uF"
			(at 1.45964 -2.478281 90)
			(unlocked yes)
			(layer "B.SilkS")
			(hide yes)
			(effects
				(font
					(size 0.762 0.762)
					(thickness 0.2286)
				)
				(justify mirror)
			)
		)
		(sheetname "05-GPS_IMU_SENSORS")
		(sheetfile "05-GPS_IMU_SENSORS.kicad_sch")
		(duplicate_pad_numbers_are_jumpers no)
		(fp_line
			(start 0.125 0.72499)
			(end -0.125 0.72499)
			(stroke
				(width 0.2)
				(type solid)
			)
			(layer "B.SilkS")
		)
		(fp_line
			(start 0.125 -0.725)
			(end -0.125 -0.725)
			(stroke
				(width 0.2)
				(type solid)
			)
			(layer "B.SilkS")
		)
		(fp_line
			(start -1.6 0.82499)
			(end -1.6 -0.825)
			(stroke
				(width 0.2)
				(type solid)
			)
			(layer "B.CrtYd")
		)
		(fp_line
			(start 1.6 0.82499)
			(end -1.6 0.82499)
			(stroke
				(width 0.2)
				(type solid)
			)
			(layer "B.CrtYd")
		)
		(fp_line
			(start 1.6 0.82499)
			(end 1.6 -0.825)
			(stroke
				(width 0.2)
				(type solid)
			)
			(layer "B.CrtYd")
		)
		(fp_line
			(start 1.6 -0.825)
			(end -1.6 -0.825)
			(stroke
				(width 0.2)
				(type solid)
			)
			(layer "B.CrtYd")
		)
		(fp_line
			(start -1.6 0.82499)
			(end -1.6 -0.825)
			(stroke
				(width 0.2)
				(type solid)
			)
			(layer "B.Fab")
		)
		(fp_line
			(start 1.6 0.82499)
			(end -1.6 0.82499)
			(stroke
				(width 0.2)
				(type solid)
			)
			(layer "B.Fab")
		)
		(fp_line
			(start 1.6 0.82499)
			(end 1.6 -0.825)
			(stroke
				(width 0.2)
				(type solid)
			)
			(layer "B.Fab")
		)
		(fp_line
			(start 0 0.49999)
			(end 0 -0.5)
			(stroke
				(width 0.1)
				(type solid)
			)
			(layer "B.Fab")
		)
		(fp_line
			(start 0.5 0)
			(end -0.5 0)
			(stroke
				(width 0.1)
				(type solid)
			)
			(layer "B.Fab")
		)
		(fp_line
			(start 1.6 -0.825)
			(end -1.6 -0.825)
			(stroke
				(width 0.2)
				(type solid)
			)
			(layer "B.Fab")
		)
		(fp_text user "${REFERENCE}"
			(at -0.00001 -0.09602 90)
			(unlocked yes)
			(layer "B.Fab")
			(effects
				(font
					(face "Arial")
					(size 0.63 0.63)
					(thickness 0.1)
				)
				(justify left bottom mirror)
			)
		)
		(pad "1" smd rect
			(at -1 0 270)
			(size 1 1.25)
			(layers "B.Cu" "B.Mask" "B.Paste")
			(net "+3.3V")
			(solder_mask_margin 0)
			(solder_paste_margin 0)
		)
		(pad "2" smd rect
			(at 1 0 270)
			(size 1 1.25)
			(layers "B.Cu" "B.Mask" "B.Paste")
			(net "GND")
			(solder_mask_margin 0)
			(solder_paste_margin 0)
		)
	)
	(footprint "Vault:FP-MK212BG-MFG"
		(layer "B.Cu")
		(at 103.9741 74.05812)
		(property "Reference" "C42"
			(at 0.2761 1.531149 180)
			(unlocked yes)
			(layer "B.SilkS")
			(effects
				(font
					(size 0.762 0.762)
					(thickness 0.2286)
				)
				(justify mirror)
			)
		)
		(property "Value" "10uF"
			(at -3.240271 -2.22164 270)
			(unlocked yes)
			(layer "B.SilkS")
			(hide yes)
			(effects
				(font
					(size 0.762 0.762)
					(thickness 0.2286)
				)
				(justify mirror)
			)
		)
		(sheetname "05-GPS_IMU_SENSORS")
		(sheetfile "05-GPS_IMU_SENSORS.kicad_sch")
		(duplicate_pad_numbers_are_jumpers no)
		(fp_line
			(start -0.125 -0.725)
			(end 0.125 -0.725)
			(stroke
				(width 0.2)
				(type solid)
			)
			(layer "B.SilkS")
		)
		(fp_line
			(start -0.125 0.725)
			(end 0.125 0.725)
			(stroke
				(width 0.2)
				(type solid)
			)
			(layer "B.SilkS")
		)
		(fp_line
			(start -1.6 -0.825)
			(end 1.6 -0.825)
			(stroke
				(width 0.2)
				(type solid)
			)
			(layer "B.CrtYd")
		)
		(fp_line
			(start -1.6 0.825)
			(end -1.6 -0.825)
			(stroke
				(width 0.2)
				(type solid)
			)
			(layer "B.CrtYd")
		)
		(fp_line
			(start -1.6 0.825)
			(end 1.6 0.825)
			(stroke
				(width 0.2)
				(type solid)
			)
			(layer "B.CrtYd")
		)
		(fp_line
			(start 1.6 0.825)
			(end 1.6 -0.825)
			(stroke
				(width 0.2)
				(type solid)
			)
			(layer "B.CrtYd")
		)
		(fp_line
			(start -1.6 -0.825)
			(end 1.6 -0.825)
			(stroke
				(width 0.2)
				(type solid)
			)
			(layer "B.Fab")
		)
		(fp_line
			(start -1.6 0.825)
			(end -1.6 -0.825)
			(stroke
				(width 0.2)
				(type solid)
			)
			(layer "B.Fab")
		)
		(fp_line
			(start -1.6 0.825)
			(end 1.6 0.825)
			(stroke
				(width 0.2)
				(type solid)
			)
			(layer "B.Fab")
		)
		(fp_line
			(start -0.5 0)
			(end 0.5 0)
			(stroke
				(width 0.1)
				(type solid)
			)
			(layer "B.Fab")
		)
		(fp_line
			(start 0 0.5)
			(end 0 -0.5)
			(stroke
				(width 0.1)
				(type solid)
			)
			(layer "B.Fab")
		)
		(fp_line
			(start 1.6 0.825)
			(end 1.6 -0.825)
			(stroke
				(width 0.2)
				(type solid)
			)
			(layer "B.Fab")
		)
		(fp_text user "${REFERENCE}"
			(at -0.00001 -0.09602 180)
			(unlocked yes)
			(layer "B.Fab")
			(effects
				(font
					(face "Arial")
					(size 0.63 0.63)
					(thickness 0.1)
				)
				(justify left bottom mirror)
			)
		)
		(pad "1" smd rect
			(at -1 0)
			(size 1 1.25)
			(layers "B.Cu" "B.Mask" "B.Paste")
			(net "+5.0V")
			(solder_mask_margin 0)
			(solder_paste_margin 0)
		)
		(pad "2" smd rect
			(at 1 0)
			(size 1 1.25)
			(layers "B.Cu" "B.Mask" "B.Paste")
			(net "GND")
			(solder_mask_margin 0)
			(solder_paste_margin 0)
		)
	)
	(footprint "Vault:CAPC1608X87X45ML20T05"
		(layer "B.Cu")
		(at 109.4216 75.5162)
		(property "Reference" "C59"
			(at -0.71236 0.906655 180)
			(unlocked yes)
			(layer "B.SilkS")
			(effects
				(font
					(size 0.762 0.762)
					(thickness 0.2286)
				)
				(justify left bottom mirror)
			)
		)
		(property "Value" "0.1uF"
			(at 0.2921 3.382645 0)
			(unlocked yes)
			(layer "B.SilkS")
			(hide yes)
			(effects
				(font
					(size 0.762 0.762)
					(thickness 0.2286)
				)
				(justify left bottom mirror)
			)
		)
		(sheetname "05-GPS_IMU_SENSORS")
		(sheetfile "05-GPS_IMU_SENSORS.kicad_sch")
		(duplicate_pad_numbers_are_jumpers no)
		(pad "1" smd rect
			(at -0.7 0 270)
			(size 1.1 1.05)
			(layers "B.Cu" "B.Mask" "B.Paste")
			(net "GND")
		)
		(pad "2" smd rect
			(at 0.7 0 270)
			(size 1.1 1.05)
			(layers "B.Cu" "B.Mask" "B.Paste")
			(net "+3.3V")
		)
	)
	(footprint "Vault:FP-0402-L_1_0_0_05-W_0_5-IPC_A"
		(layer "B.Cu")
		(at 96.4216 74.7162)
		(property "Reference" "C17"
			(at 0.8 -1.106655 0)
			(unlocked yes)
			(layer "B.SilkS")
			(effects
				(font
					(size 0.762 0.762)
					(thickness 0.2286)
				)
				(justify left bottom mirror)
			)
		)
		(property "Value" "1uF_16V_0402"
			(at -14.9272 10.507645 0)
			(unlocked yes)
			(layer "B.SilkS")
			(hide yes)
			(effects
				(font
					(size 0.762 0.762)
					(thickness 0.2286)
				)
				(justify left bottom mirror)
			)
		)
		(sheetname "03-POWER")
		(sheetfile "03-POWER.kicad_sch")
		(duplicate_pad_numbers_are_jumpers no)
		(fp_line
			(start -0.83624 -0.73624)
			(end 0.83624 -0.73624)
			(stroke
				(width 0.2)
				(type solid)
			)
			(layer "B.SilkS")
		)
		(fp_line
			(start -0.83624 0.73624)
			(end 0.83624 0.73624)
			(stroke
				(width 0.2)
				(type solid)
			)
			(layer "B.SilkS")
		)
		(fp_line
			(start -1.03624 -0.53624)
			(end 1.03624 -0.53624)
			(stroke
				(width 0.2)
				(type solid)
			)
			(layer "B.CrtYd")
		)
		(fp_line
			(start -1.03624 0.53624)
			(end -1.03624 -0.53624)
			(stroke
				(width 0.2)
				(type solid)
			)
			(layer "B.CrtYd")
		)
		(fp_line
			(start -1.03624 0.53624)
			(end 1.03624 0.53624)
			(stroke
				(width 0.2)
				(type solid)
			)
			(layer "B.CrtYd")
		)
		(fp_line
			(start 1.03624 0.53624)
			(end 1.03624 -0.53624)
			(stroke
				(width 0.2)
				(type solid)
			)
			(layer "B.CrtYd")
		)
		(fp_line
			(start -1.03624 -0.53624)
			(end 1.03624 -0.53624)
			(stroke
				(width 0.2)
				(type solid)
			)
			(layer "B.Fab")
		)
		(fp_line
			(start -1.03624 0.53624)
			(end -1.03624 -0.53624)
			(stroke
				(width 0.2)
				(type solid)
			)
			(layer "B.Fab")
		)
		(fp_line
			(start -1.03624 0.53624)
			(end 1.03624 0.53624)
			(stroke
				(width 0.2)
				(type solid)
			)
			(layer "B.Fab")
		)
		(fp_line
			(start -0.5 0)
			(end 0.5 0)
			(stroke
				(width 0.1)
				(type solid)
			)
			(layer "B.Fab")
		)
		(fp_line
			(start 0 0.5)
			(end 0 -0.5)
			(stroke
				(width 0.1)
				(type solid)
			)
			(layer "B.Fab")
		)
		(fp_line
			(start 1.03624 0.53624)
			(end 1.03624 -0.53624)
			(stroke
				(width 0.2)
				(type solid)
			)
			(layer "B.Fab")
		)
		(fp_text user "${REFERENCE}"
			(at -0.00002 -0.09602 180)
			(unlocked yes)
			(layer "B.Fab")
			(effects
				(font
					(face "Arial")
					(size 0.63 0.63)
					(thickness 0.1)
				)
				(justify left bottom mirror)
			)
		)
		(pad "1" smd rect
			(at -0.47856 0)
			(size 0.71535 0.67248)
			(layers "B.Cu" "B.Mask" "B.Paste")
			(net "+5.0V")
			(solder_mask_margin 0)
			(solder_paste_margin 0)
		)
		(pad "2" smd rect
			(at 0.47856 0)
			(size 0.71535 0.67248)
			(layers "B.Cu" "B.Mask" "B.Paste")
			(net "GND")
			(solder_mask_margin 0)
			(solder_paste_margin 0)
		)
	)
	(footprint "Vault:RESC1005X40X25NL10T10"
		(layer "B.Cu")
		(at 128.2216 63.82816 90)
		(property "Reference" "R134"
			(at 2.23367 0.104461 90)
			(unlocked yes)
			(layer "B.SilkS")
			(effects
				(font
					(size 0.762 0.762)
					(thickness 0.2032)
				)
				(justify mirror)
			)
		)
		(property "Value" "4.7K_1%_0402"
			(at -2.732271 -8.747465 0)
			(unlocked yes)
			(layer "B.SilkS")
			(hide yes)
			(effects
				(font
					(size 0.762 0.762)
					(thickness 0.2032)
				)
				(justify mirror)
			)
		)
		(sheetname "10-M2_GPS")
		(sheetfile "10-M2_GPS.kicad_sch")
		(duplicate_pad_numbers_are_jumpers no)
		(pad "1" smd rect
			(at -0.425 0)
			(size 0.6 0.65)
			(layers "B.Cu" "B.Mask" "B.Paste")
			(net "GPS1_PIN15")
		)
		(pad "2" smd rect
			(at 0.425 0)
			(size 0.6 0.65)
			(layers "B.Cu" "B.Mask" "B.Paste")
			(net "+3.3V")
		)
	)
	(footprint "Vault:FP-CL829-IPC_C"
		(layer "B.Cu")
		(at 228.14659 132.0162)
		(property "Reference" "C90"
			(at -0.25359 1.526931 0)
			(unlocked yes)
			(layer "B.SilkS")
			(effects
				(font
					(size 0.762 0.762)
					(thickness 0.2286)
				)
				(justify mirror)
			)
		)
		(property "Value" "4.7uF_16V_0402"
			(at -2.440151 -9.864605 270)
			(unlocked yes)
			(layer "B.SilkS")
			(hide yes)
			(effects
				(font
					(size 0.762 0.762)
					(thickness 0.2286)
				)
				(justify mirror)
			)
		)
		(sheetname "09-USBUart_PPSMUX_UARTMUX")
		(sheetfile "09-USBUart_PPSMUX_UARTMUX.kicad_sch")
		(duplicate_pad_numbers_are_jumpers no)
		(fp_line
			(start -0.63623 -0.675)
			(end 0.63624 -0.675)
			(stroke
				(width 0.2)
				(type solid)
			)
			(layer "B.SilkS")
		)
		(fp_line
			(start -0.63623 0.675)
			(end 0.63624 0.675)
			(stroke
				(width 0.2)
				(type solid)
			)
			(layer "B.SilkS")
		)
		(fp_line
			(start -0.73623 -0.375)
			(end 0.73624 -0.375)
			(stroke
				(width 0.2)
				(type solid)
			)
			(layer "B.CrtYd")
		)
		(fp_line
			(start -0.73623 0.375)
			(end -0.73623 -0.375)
			(stroke
				(width 0.2)
				(type solid)
			)
			(layer "B.CrtYd")
		)
		(fp_line
			(start -0.73623 0.375)
			(end 0.73624 0.375)
			(stroke
				(width 0.2)
				(type solid)
			)
			(layer "B.CrtYd")
		)
		(fp_line
			(start 0.73624 0.375)
			(end 0.73624 -0.375)
			(stroke
				(width 0.2)
				(type solid)
			)
			(layer "B.CrtYd")
		)
		(fp_line
			(start -0.73623 -0.375)
			(end 0.73624 -0.375)
			(stroke
				(width 0.2)
				(type solid)
			)
			(layer "B.Fab")
		)
		(fp_line
			(start -0.73623 0.375)
			(end -0.73623 -0.375)
			(stroke
				(width 0.2)
				(type solid)
			)
			(layer "B.Fab")
		)
		(fp_line
			(start -0.73623 0.375)
			(end 0.73624 0.375)
			(stroke
				(width 0.2)
				(type solid)
			)
			(layer "B.Fab")
		)
		(fp_line
			(start -0.5 0)
			(end 0.5 0)
			(stroke
				(width 0.1)
				(type solid)
			)
			(layer "B.Fab")
		)
		(fp_line
			(start -0.5 0)
			(end 0.5 0)
			(stroke
				(width 0.1)
				(type solid)
			)
			(layer "B.Fab")
		)
		(fp_line
			(start 0 0.5)
			(end 0 -0.5)
			(stroke
				(width 0.1)
				(type solid)
			)
			(layer "B.Fab")
		)
		(fp_line
			(start 0 0.5)
			(end 0 -0.5)
			(stroke
				(width 0.1)
				(type solid)
			)
			(layer "B.Fab")
		)
		(fp_line
			(start 0.73624 0.375)
			(end 0.73624 -0.375)
			(stroke
				(width 0.2)
				(type solid)
			)
			(layer "B.Fab")
		)
		(fp_text user "${REFERENCE}"
			(at 0 -0.28424 180)
			(unlocked yes)
			(layer "B.Fab")
			(effects
				(font
					(face "Arial")
					(size 0.63 0.63)
					(thickness 0.1)
				)
				(justify left bottom mirror)
			)
		)
		(pad "1" smd rect
			(at -0.37856 0)
			(size 0.51535 0.47247)
			(layers "B.Cu" "B.Mask" "B.Paste")
			(net "FTDI_VBUS")
			(solder_mask_margin 0)
			(solder_paste_margin 0)
		)
		(pad "2" smd rect
			(at 0.37857 0)
			(size 0.51535 0.47247)
			(layers "B.Cu" "B.Mask" "B.Paste")
			(net "GND")
			(solder_mask_margin 0)
			(solder_paste_margin 0)
		)
	)
	(footprint "Vault:RESC1005X40X25LL05T10"
		(layer "B.Cu")
		(at 221.91312 95.8124 -90)
		(property "Reference" "R141"
			(at -0.0994 -1.081549 270)
			(unlocked yes)
			(layer "B.SilkS")
			(effects
				(font
					(size 0.762 0.762)
					(thickness 0.2032)
				)
				(justify mirror)
			)
		)
		(property "Value" "10K_1%_0402"
			(at -2.579871 -8.036515 180)
			(unlocked yes)
			(layer "B.SilkS")
			(hide yes)
			(effects
				(font
					(size 0.762 0.762)
					(thickness 0.2032)
				)
				(justify mirror)
			)
		)
		(sheetname "08-DIPSwitches_I2C")
		(sheetfile "08-DIPSwitches_I2C.kicad_sch")
		(duplicate_pad_numbers_are_jumpers no)
		(pad "1" smd rect
			(at -0.375 0 180)
			(size 0.45 0.5)
			(layers "B.Cu" "B.Mask" "B.Paste")
			(net "+3.3V")
		)
		(pad "2" smd rect
			(at 0.375 0 180)
			(size 0.45 0.5)
			(layers "B.Cu" "B.Mask" "B.Paste")
			(net "DIP_SW_GPS1_SEL")
		)
	)
	(footprint "Vault:FP-0402-L_1_0_1-W_0_5_0_1-IPC_C"
		(layer "B.Cu")
		(at 123.8966 55.8662 90)
		(property "Reference" "C97"
			(at 2.3468 -0.148069 90)
			(unlocked yes)
			(layer "B.SilkS")
			(effects
				(font
					(size 0.762 0.762)
					(thickness 0.2032)
				)
				(justify mirror)
			)
		)
		(property "Value" "0.1uF_25V_0402"
			(at -2.465551 -9.813815 0)
			(unlocked yes)
			(layer "B.SilkS")
			(hide yes)
			(effects
				(font
					(size 0.762 0.762)
					(thickness 0.2032)
				)
				(justify mirror)
			)
		)
		(sheetname "10-M2_GPS")
		(sheetfile "10-M2_GPS.kicad_sch")
		(duplicate_pad_numbers_are_jumpers no)
		(fp_line
			(start -0.65607 -0.7)
			(end 0.65607 -0.7)
			(stroke
				(width 0.2)
				(type solid)
			)
			(layer "B.SilkS")
		)
		(fp_line
			(start -0.65607 0.7)
			(end 0.65607 0.7)
			(stroke
				(width 0.2)
				(type solid)
			)
			(layer "B.SilkS")
		)
		(fp_line
			(start 0.75607 -0.4)
			(end 0.75607 0.4)
			(stroke
				(width 0.2)
				(type solid)
			)
			(layer "B.CrtYd")
		)
		(fp_line
			(start -0.75607 -0.4)
			(end 0.75607 -0.4)
			(stroke
				(width 0.2)
				(type solid)
			)
			(layer "B.CrtYd")
		)
		(fp_line
			(start -0.75607 -0.4)
			(end -0.75607 0.4)
			(stroke
				(width 0.2)
				(type solid)
			)
			(layer "B.CrtYd")
		)
		(fp_line
			(start -0.75607 0.4)
			(end 0.75607 0.4)
			(stroke
				(width 0.2)
				(type solid)
			)
			(layer "B.CrtYd")
		)
		(fp_line
			(start 0 -0.5)
			(end 0 0.5)
			(stroke
				(width 0.1)
				(type solid)
			)
			(layer "B.Fab")
		)
		(fp_line
			(start 0.75607 -0.4)
			(end 0.75607 0.4)
			(stroke
				(width 0.2)
				(type solid)
			)
			(layer "B.Fab")
		)
		(fp_line
			(start -0.75607 -0.4)
			(end 0.75607 -0.4)
			(stroke
				(width 0.2)
				(type solid)
			)
			(layer "B.Fab")
		)
		(fp_line
			(start -0.75607 -0.4)
			(end -0.75607 0.4)
			(stroke
				(width 0.2)
				(type solid)
			)
			(layer "B.Fab")
		)
		(fp_line
			(start -0.5 0)
			(end 0.5 0)
			(stroke
				(width 0.1)
				(type solid)
			)
			(layer "B.Fab")
		)
		(fp_line
			(start -0.75607 0.4)
			(end 0.75607 0.4)
			(stroke
				(width 0.2)
				(type solid)
			)
			(layer "B.Fab")
		)
		(fp_text user "${REFERENCE}"
			(at -0.00002 -0.09602 270)
			(unlocked yes)
			(layer "B.Fab")
			(effects
				(font
					(face "Arial")
					(size 0.63 0.63)
					(thickness 0.1)
				)
				(justify left bottom mirror)
			)
		)
		(pad "1" smd rect
			(at -0.36554 0 90)
			(size 0.58106 0.51213)
			(layers "B.Cu" "B.Mask" "B.Paste")
			(net "+3.3V")
			(solder_mask_margin 0)
			(solder_paste_margin 0)
		)
		(pad "2" smd rect
			(at 0.36554 0 90)
			(size 0.58106 0.51213)
			(layers "B.Cu" "B.Mask" "B.Paste")
			(net "GND")
			(solder_mask_margin 0)
			(solder_paste_margin 0)
		)
	)
	(footprint "Vault:FP-0402-L_1_0_0_05-W_0_5-IPC_C"
		(layer "B.Cu")
		(at 110.58072 86.6662 180)
		(property "Reference" "C65"
			(at 2.48772 -0.094851 0)
			(unlocked yes)
			(layer "B.SilkS")
			(effects
				(font
					(size 0.762 0.762)
					(thickness 0.2286)
				)
				(justify mirror)
			)
		)
		(property "Value" "1uF_0402"
			(at -2.795791 -1.459875 90)
			(unlocked yes)
			(layer "B.SilkS")
			(hide yes)
			(effects
				(font
					(size 0.762 0.762)
					(thickness 0.2286)
				)
				(justify mirror)
			)
		)
		(sheetname "05-GPS_IMU_SENSORS")
		(sheetfile "05-GPS_IMU_SENSORS.kicad_sch")
		(duplicate_pad_numbers_are_jumpers no)
		(fp_line
			(start 0.63623 0.675)
			(end -0.63624 0.675)
			(stroke
				(width 0.2)
				(type solid)
			)
			(layer "B.SilkS")
		)
		(fp_line
			(start 0.63623 -0.675)
			(end -0.63624 -0.675)
			(stroke
				(width 0.2)
				(type solid)
			)
			(layer "B.SilkS")
		)
		(fp_line
			(start 0.73623 0.375)
			(end -0.73624 0.375)
			(stroke
				(width 0.2)
				(type solid)
			)
			(layer "B.CrtYd")
		)
		(fp_line
			(start 0.73623 -0.375)
			(end 0.73623 0.375)
			(stroke
				(width 0.2)
				(type solid)
			)
			(layer "B.CrtYd")
		)
		(fp_line
			(start 0.73623 -0.375)
			(end -0.73624 -0.375)
			(stroke
				(width 0.2)
				(type solid)
			)
			(layer "B.CrtYd")
		)
		(fp_line
			(start -0.73624 -0.375)
			(end -0.73624 0.375)
			(stroke
				(width 0.2)
				(type solid)
			)
			(layer "B.CrtYd")
		)
		(fp_line
			(start 0.73623 0.375)
			(end -0.73624 0.375)
			(stroke
				(width 0.2)
				(type solid)
			)
			(layer "B.Fab")
		)
		(fp_line
			(start 0.73623 -0.375)
			(end 0.73623 0.375)
			(stroke
				(width 0.2)
				(type solid)
			)
			(layer "B.Fab")
		)
		(fp_line
			(start 0.73623 -0.375)
			(end -0.73624 -0.375)
			(stroke
				(width 0.2)
				(type solid)
			)
			(layer "B.Fab")
		)
		(fp_line
			(start 0.5 0)
			(end -0.5 0)
			(stroke
				(width 0.1)
				(type solid)
			)
			(layer "B.Fab")
		)
		(fp_line
			(start 0 -0.5)
			(end 0 0.5)
			(stroke
				(width 0.1)
				(type solid)
			)
			(layer "B.Fab")
		)
		(fp_line
			(start -0.73624 -0.375)
			(end -0.73624 0.375)
			(stroke
				(width 0.2)
				(type solid)
			)
			(layer "B.Fab")
		)
		(fp_text user "${REFERENCE}"
			(at -0.00001 -0.09602 360)
			(unlocked yes)
			(layer "B.Fab")
			(effects
				(font
					(face "Arial")
					(size 0.63 0.63)
					(thickness 0.1)
				)
				(justify left bottom mirror)
			)
		)
		(pad "1" smd rect
			(at -0.37856 0 180)
			(size 0.51535 0.47247)
			(layers "B.Cu" "B.Mask" "B.Paste")
			(net "NetC65_1")
			(solder_mask_margin 0)
			(solder_paste_margin 0)
		)
		(pad "2" smd rect
			(at 0.37856 0 180)
			(size 0.51535 0.47247)
			(layers "B.Cu" "B.Mask" "B.Paste")
			(net "GND")
			(solder_mask_margin 0)
			(solder_paste_margin 0)
		)
	)
	(footprint "Vault:RESC1005X40X25LL05T05"
		(layer "B.Cu")
		(at 112.48072 87.8662 180)
		(property "Reference" "R54"
			(at 0.13052 -7.123069 180)
			(unlocked yes)
			(layer "B.SilkS")
			(effects
				(font
					(size 0.762 0.762)
					(thickness 0.2286)
				)
				(justify mirror)
			)
		)
		(property "Value" "0_1%_0402"
			(at -2.579881 -6.66536 90)
			(unlocked yes)
			(layer "B.SilkS")
			(hide yes)
			(effects
				(font
					(size 0.762 0.762)
					(thickness 0.2286)
				)
				(justify mirror)
			)
		)
		(sheetname "05-GPS_IMU_SENSORS")
		(sheetfile "05-GPS_IMU_SENSORS.kicad_sch")
		(duplicate_pad_numbers_are_jumpers no)
		(pad "1" smd rect
			(at -0.4 0 90)
			(size 0.45 0.45)
			(layers "B.Cu" "B.Mask" "B.Paste")
			(net "PCIE_PERST")
		)
		(pad "2" smd rect
			(at 0.4 0 90)
			(size 0.45 0.45)
			(layers "B.Cu" "B.Mask" "B.Paste")
			(net "NetR52_1")
		)
	)
	(footprint "Capacitors:CAPC1005X06N"
		(layer "B.Cu")
		(at 137.3846 151.7886 90)
		(property "Reference" "C51"
			(at 2.41349 0.148145 270)
			(unlocked yes)
			(layer "B.SilkS")
			(effects
				(font
					(size 0.762 0.762)
					(thickness 0.2286)
				)
				(justify left bottom mirror)
			)
		)
		(property "Value" "CAP_0402_0.1UF_50V"
			(at -3.382645 0.2921 0)
			(unlocked yes)
			(layer "B.SilkS")
			(hide yes)
			(effects
				(font
					(size 0.762 0.762)
					(thickness 0.2286)
				)
				(justify left bottom mirror)
			)
		)
		(sheetname "04-PCIe_JTAG")
		(sheetfile "04-PCIe_JTAG.kicad_sch")
		(duplicate_pad_numbers_are_jumpers no)
		(pad "1" smd rect
			(at -0.43 0)
			(size 0.64 0.68)
			(layers "B.Cu" "B.Mask" "B.Paste")
			(net "NetC51_1")
		)
		(pad "2" smd rect
			(at 0.43 0)
			(size 0.64 0.68)
			(layers "B.Cu" "B.Mask" "B.Paste")
			(net "PCIE_TX2_N")
		)
	)
	(footprint "Vault:FP-0402-L_1_0_1-W_0_5_0_1-IPC_C"
		(layer "B.Cu")
		(at 219.66155 125.59915 90)
		(property "Reference" "C112"
			(at 2.02895 0.186971 90)
			(unlocked yes)
			(layer "B.SilkS")
			(effects
				(font
					(size 0.762 0.762)
					(thickness 0.254)
				)
				(justify mirror)
			)
		)
		(property "Value" "0.1uF_25V_0402"
			(at -2.465561 -9.864615 0)
			(unlocked yes)
			(layer "B.SilkS")
			(hide yes)
			(effects
				(font
					(size 0.762 0.762)
					(thickness 0.254)
				)
				(justify mirror)
			)
		)
		(sheetname "09-USBUart_PPSMUX_UARTMUX")
		(sheetfile "09-USBUart_PPSMUX_UARTMUX.kicad_sch")
		(duplicate_pad_numbers_are_jumpers no)
		(fp_line
			(start -0.65607 -0.7)
			(end 0.65606 -0.7)
			(stroke
				(width 0.2)
				(type solid)
			)
			(layer "B.SilkS")
		)
		(fp_line
			(start -0.65607 0.7)
			(end 0.65606 0.7)
			(stroke
				(width 0.2)
				(type solid)
			)
			(layer "B.SilkS")
		)
		(fp_line
			(start 0.75606 -0.4)
			(end 0.75606 0.4)
			(stroke
				(width 0.2)
				(type solid)
			)
			(layer "B.CrtYd")
		)
		(fp_line
			(start -0.75607 -0.4)
			(end 0.75606 -0.4)
			(stroke
				(width 0.2)
				(type solid)
			)
			(layer "B.CrtYd")
		)
		(fp_line
			(start -0.75607 -0.4)
			(end -0.75607 0.4)
			(stroke
				(width 0.2)
				(type solid)
			)
			(layer "B.CrtYd")
		)
		(fp_line
			(start -0.75607 0.4)
			(end 0.75606 0.4)
			(stroke
				(width 0.2)
				(type solid)
			)
			(layer "B.CrtYd")
		)
		(fp_line
			(start 0 -0.5)
			(end 0 0.5)
			(stroke
				(width 0.1)
				(type solid)
			)
			(layer "B.Fab")
		)
		(fp_line
			(start 0.75606 -0.4)
			(end 0.75606 0.4)
			(stroke
				(width 0.2)
				(type solid)
			)
			(layer "B.Fab")
		)
		(fp_line
			(start -0.75607 -0.4)
			(end 0.75606 -0.4)
			(stroke
				(width 0.2)
				(type solid)
			)
			(layer "B.Fab")
		)
		(fp_line
			(start -0.75607 -0.4)
			(end -0.75607 0.4)
			(stroke
				(width 0.2)
				(type solid)
			)
			(layer "B.Fab")
		)
		(fp_line
			(start -0.5 0)
			(end 0.49999 0)
			(stroke
				(width 0.1)
				(type solid)
			)
			(layer "B.Fab")
		)
		(fp_line
			(start -0.75607 0.4)
			(end 0.75606 0.4)
			(stroke
				(width 0.2)
				(type solid)
			)
			(layer "B.Fab")
		)
		(fp_text user "${REFERENCE}"
			(at -0.00002 -0.09602 270)
			(unlocked yes)
			(layer "B.Fab")
			(effects
				(font
					(face "Arial")
					(size 0.63 0.63)
					(thickness 0.1)
				)
				(justify left bottom mirror)
			)
		)
		(pad "1" smd rect
			(at -0.36554 0 90)
			(size 0.58106 0.51213)
			(layers "B.Cu" "B.Mask" "B.Paste")
			(net "FTDI_P3V3")
			(solder_mask_margin 0)
			(solder_paste_margin 0)
		)
		(pad "2" smd rect
			(at 0.36553 0 90)
			(size 0.58106 0.51213)
			(layers "B.Cu" "B.Mask" "B.Paste")
			(net "GND")
			(solder_mask_margin 0)
			(solder_paste_margin 0)
		)
	)
	(footprint "Vault:RESC1005X40X25NL10T10"
		(layer "B.Cu")
		(at 85.1216 55.0162)
		(property "Reference" "R60"
			(at 0.4786 1.123069 180)
			(unlocked yes)
			(layer "B.SilkS")
			(effects
				(font
					(size 0.762 0.762)
					(thickness 0.2286)
				)
				(justify mirror)
			)
		)
		(property "Value" "10K_1%_0402"
			(at -2.732271 -9.407665 270)
			(unlocked yes)
			(layer "B.SilkS")
			(hide yes)
			(effects
				(font
					(size 0.762 0.762)
					(thickness 0.2286)
				)
				(justify mirror)
			)
		)
		(sheetname "03-POWER")
		(sheetfile "03-POWER.kicad_sch")
		(duplicate_pad_numbers_are_jumpers no)
		(pad "1" smd rect
			(at -0.425 0 270)
			(size 0.6 0.65)
			(layers "B.Cu" "B.Mask" "B.Paste")
			(net "GND")
		)
		(pad "2" smd rect
			(at 0.425 0 270)
			(size 0.6 0.65)
			(layers "B.Cu" "B.Mask" "B.Paste")
			(net "NetR6_2")
		)
	)
	(footprint "Vault:RESC1005X40X25LL05T05"
		(layer "B.Cu")
		(at 112.25573 88.6912 180)
		(property "Reference" "R50"
			(at -0.09447 -7.498069 180)
			(unlocked yes)
			(layer "B.SilkS")
			(effects
				(font
					(size 0.762 0.762)
					(thickness 0.2286)
				)
				(justify mirror)
			)
		)
		(property "Value" "4.7K_0402"
			(at -3.024391 -2.374045 90)
			(unlocked yes)
			(layer "B.SilkS")
			(hide yes)
			(effects
				(font
					(size 0.762 0.762)
					(thickness 0.2286)
				)
				(justify mirror)
			)
		)
		(sheetname "05-GPS_IMU_SENSORS")
		(sheetfile "05-GPS_IMU_SENSORS.kicad_sch")
		(duplicate_pad_numbers_are_jumpers no)
		(pad "1" smd rect
			(at -0.39999 0 90)
			(size 0.45 0.45)
			(layers "B.Cu" "B.Mask" "B.Paste")
			(net "BNO_P3V3")
		)
		(pad "2" smd rect
			(at 0.40001 0 90)
			(size 0.45 0.45)
			(layers "B.Cu" "B.Mask" "B.Paste")
			(net "BNO_INT")
		)
	)
	(footprint "Vault:FP-0402-L_1_0_1-W_0_5_0_1-IPC_C"
		(layer "B.Cu")
		(at 215.8716 121.4405 180)
		(property "Reference" "C104"
			(at 1.0408 1.556359 0)
			(unlocked yes)
			(layer "B.SilkS")
			(effects
				(font
					(size 0.762 0.762)
					(thickness 0.2032)
				)
				(justify mirror)
			)
		)
		(property "Value" "0.1uF_25V_0402"
			(at -2.465551 -9.813805 90)
			(unlocked yes)
			(layer "B.SilkS")
			(hide yes)
			(effects
				(font
					(size 0.762 0.762)
					(thickness 0.2032)
				)
				(justify mirror)
			)
		)
		(sheetname "10-M2_GPS")
		(sheetfile "10-M2_GPS.kicad_sch")
		(duplicate_pad_numbers_are_jumpers no)
		(fp_line
			(start 0.65607 0.7)
			(end -0.65607 0.7)
			(stroke
				(width 0.2)
				(type solid)
			)
			(layer "B.SilkS")
		)
		(fp_line
			(start 0.65607 -0.7)
			(end -0.65607 -0.7)
			(stroke
				(width 0.2)
				(type solid)
			)
			(layer "B.SilkS")
		)
		(fp_line
			(start 0.75607 0.4)
			(end -0.75607 0.4)
			(stroke
				(width 0.2)
				(type solid)
			)
			(layer "B.CrtYd")
		)
		(fp_line
			(start 0.75607 -0.4)
			(end 0.75607 0.4)
			(stroke
				(width 0.2)
				(type solid)
			)
			(layer "B.CrtYd")
		)
		(fp_line
			(start 0.75607 -0.4)
			(end -0.75607 -0.4)
			(stroke
				(width 0.2)
				(type solid)
			)
			(layer "B.CrtYd")
		)
		(fp_line
			(start -0.75607 -0.4)
			(end -0.75607 0.4)
			(stroke
				(width 0.2)
				(type solid)
			)
			(layer "B.CrtYd")
		)
		(fp_line
			(start 0.75607 0.4)
			(end -0.75607 0.4)
			(stroke
				(width 0.2)
				(type solid)
			)
			(layer "B.Fab")
		)
		(fp_line
			(start 0.75607 -0.4)
			(end 0.75607 0.4)
			(stroke
				(width 0.2)
				(type solid)
			)
			(layer "B.Fab")
		)
		(fp_line
			(start 0.75607 -0.4)
			(end -0.75607 -0.4)
			(stroke
				(width 0.2)
				(type solid)
			)
			(layer "B.Fab")
		)
		(fp_line
			(start 0.5 0)
			(end -0.5 0)
			(stroke
				(width 0.1)
				(type solid)
			)
			(layer "B.Fab")
		)
		(fp_line
			(start 0 -0.5)
			(end 0 0.5)
			(stroke
				(width 0.1)
				(type solid)
			)
			(layer "B.Fab")
		)
		(fp_line
			(start -0.75607 -0.4)
			(end -0.75607 0.4)
			(stroke
				(width 0.2)
				(type solid)
			)
			(layer "B.Fab")
		)
		(fp_text user "${REFERENCE}"
			(at -0.00001 -0.09601 360)
			(unlocked yes)
			(layer "B.Fab")
			(effects
				(font
					(face "Arial")
					(size 0.63 0.63)
					(thickness 0.1)
				)
				(justify left bottom mirror)
			)
		)
		(pad "1" smd rect
			(at -0.36554 0 180)
			(size 0.58106 0.51213)
			(layers "B.Cu" "B.Mask" "B.Paste")
			(net "GNSS2_P3V3")
			(solder_mask_margin 0)
			(solder_paste_margin 0)
		)
		(pad "2" smd rect
			(at 0.36554 0 180)
			(size 0.58106 0.51213)
			(layers "B.Cu" "B.Mask" "B.Paste")
			(net "GND")
			(solder_mask_margin 0)
			(solder_paste_margin 0)
		)
	)
	(footprint "Vault:RESC1005X40X25ML05T10"
		(layer "B.Cu")
		(at 100.3216 61.1162 -90)
		(property "Reference" "R2"
			(at -0.7 1.106655 90)
			(unlocked yes)
			(layer "B.SilkS")
			(effects
				(font
					(size 0.762 0.762)
					(thickness 0.2286)
				)
				(justify left bottom mirror)
			)
		)
		(property "Value" "147K_1%_0402"
			(at 9.461245 17.0993 0)
			(unlocked yes)
			(layer "B.SilkS")
			(hide yes)
			(effects
				(font
					(size 0.762 0.762)
					(thickness 0.2286)
				)
				(justify left bottom mirror)
			)
		)
		(sheetname "03-POWER")
		(sheetfile "03-POWER.kicad_sch")
		(duplicate_pad_numbers_are_jumpers no)
		(pad "1" smd rect
			(at -0.475 0 180)
			(size 0.65 0.7)
			(layers "B.Cu" "B.Mask" "B.Paste")
			(net "P5V_MUN_FB")
		)
		(pad "2" smd rect
			(at 0.475 0 180)
			(size 0.65 0.7)
			(layers "B.Cu" "B.Mask" "B.Paste")
			(net "NetR2_2")
		)
	)
	(footprint "Vault:CAPC1005X55X25LL05T10"
		(layer "B.Cu")
		(at 225.2116 115.83602 180)
		(property "Reference" "C87"
			(at 0.3186 0.992889 0)
			(unlocked yes)
			(layer "B.SilkS")
			(effects
				(font
					(size 0.762 0.762)
					(thickness 0.2286)
				)
				(justify mirror)
			)
		)
		(property "Value" "47pF_50V_0402"
			(at -2.656031 -9.61078 90)
			(unlocked yes)
			(layer "B.SilkS")
			(hide yes)
			(effects
				(font
					(size 0.762 0.762)
					(thickness 0.2286)
				)
				(justify mirror)
			)
		)
		(sheetname "09-USBUart_PPSMUX_UARTMUX")
		(sheetfile "09-USBUart_PPSMUX_UARTMUX.kicad_sch")
		(duplicate_pad_numbers_are_jumpers no)
		(pad "1" smd rect
			(at -0.39 0 90)
			(size 0.52 0.56)
			(layers "B.Cu" "B.Mask" "B.Paste")
			(net "GND")
		)
		(pad "2" smd rect
			(at 0.39 0 90)
			(size 0.52 0.56)
			(layers "B.Cu" "B.Mask" "B.Paste")
			(net "FTDI_USB_R_P")
		)
	)
	(footprint "Vault:RESC1005X40X25LL05T05"
		(layer "B.Cu")
		(at 224.1216 75.8162 90)
		(property "Reference" "R64"
			(at 0.2286 1.173069 270)
			(unlocked yes)
			(layer "B.SilkS")
			(effects
				(font
					(size 0.762 0.762)
					(thickness 0.2286)
				)
				(justify mirror)
			)
		)
		(property "Value" "0_1%_0402"
			(at -2.579871 -6.66536 0)
			(unlocked yes)
			(layer "B.SilkS")
			(hide yes)
			(effects
				(font
					(size 0.762 0.762)
					(thickness 0.2286)
				)
				(justify mirror)
			)
		)
		(sheetname "03-POWER")
		(sheetfile "03-POWER.kicad_sch")
		(duplicate_pad_numbers_are_jumpers no)
		(pad "1" smd rect
			(at -0.4 0)
			(size 0.45 0.45)
			(layers "B.Cu" "B.Mask" "B.Paste")
			(net "NetR64_1")
		)
		(pad "2" smd rect
			(at 0.4 0)
			(size 0.45 0.45)
			(layers "B.Cu" "B.Mask" "B.Paste")
			(net "GND")
		)
	)
	(footprint "Vault:CAPC1608X87X45ML20T05"
		(layer "B.Cu")
		(at 128.0216 90.2162)
		(property "Reference" "C23"
			(at 0.2286 1.573069 180)
			(unlocked yes)
			(layer "B.SilkS")
			(effects
				(font
					(size 0.762 0.762)
					(thickness 0.2286)
				)
				(justify mirror)
			)
		)
		(property "Value" "0.1uF"
			(at 2.069035 -2.630671 180)
			(unlocked yes)
			(layer "B.SilkS")
			(hide yes)
			(effects
				(font
					(size 0.762 0.762)
					(thickness 0.2286)
				)
				(justify mirror)
			)
		)
		(sheetname "06-MAC")
		(sheetfile "06-MAC.kicad_sch")
		(duplicate_pad_numbers_are_jumpers no)
		(pad "1" smd rect
			(at -0.7 0 270)
			(size 1.1 1.05)
			(layers "B.Cu" "B.Mask" "B.Paste")
			(net "GND")
		)
		(pad "2" smd rect
			(at 0.7 0 270)
			(size 1.1 1.05)
			(layers "B.Cu" "B.Mask" "B.Paste")
			(net "+3.3V")
		)
	)
	(footprint "Vault:RESC1005X40X25NL10T10"
		(layer "B.Cu")
		(at 86.0716 56.5662)
		(property "Reference" "R6"
			(at 0.45 -0.517115 0)
			(unlocked yes)
			(layer "B.SilkS")
			(effects
				(font
					(size 0.762 0.762)
					(thickness 0.2286)
				)
				(justify left bottom mirror)
			)
		)
		(property "Value" "20K_1%_0402"
			(at 10.4447 -4.536755 0)
			(unlocked yes)
			(layer "B.SilkS")
			(hide yes)
			(effects
				(font
					(size 0.762 0.762)
					(thickness 0.2286)
				)
				(justify left bottom mirror)
			)
		)
		(sheetname "03-POWER")
		(sheetfile "03-POWER.kicad_sch")
		(duplicate_pad_numbers_are_jumpers no)
		(pad "1" smd rect
			(at -0.425 0 270)
			(size 0.6 0.65)
			(layers "B.Cu" "B.Mask" "B.Paste")
			(net "+12V")
		)
		(pad "2" smd rect
			(at 0.425 0 270)
			(size 0.6 0.65)
			(layers "B.Cu" "B.Mask" "B.Paste")
			(net "NetR6_2")
		)
	)
	(footprint "Vault:FP-0402-L_1_0_0_05-W_0_5-IPC_A"
		(layer "B.Cu")
		(at 219.66155 127.59915 -90)
		(property "Reference" "C111"
			(at 2.26305 -0.133119 270)
			(unlocked yes)
			(layer "B.SilkS")
			(effects
				(font
					(size 0.762 0.762)
					(thickness 0.254)
				)
				(justify mirror)
			)
		)
		(property "Value" "1uF_16V_0402"
			(at -2.744951 -8.315705 180)
			(unlocked yes)
			(layer "B.SilkS")
			(hide yes)
			(effects
				(font
					(size 0.762 0.762)
					(thickness 0.254)
				)
				(justify mirror)
			)
		)
		(sheetname "09-USBUart_PPSMUX_UARTMUX")
		(sheetfile "09-USBUart_PPSMUX_UARTMUX.kicad_sch")
		(duplicate_pad_numbers_are_jumpers no)
		(fp_line
			(start 0.83624 0.73624)
			(end -0.83623 0.73624)
			(stroke
				(width 0.2)
				(type solid)
			)
			(layer "B.SilkS")
		)
		(fp_line
			(start 0.83624 -0.73623)
			(end -0.83623 -0.73623)
			(stroke
				(width 0.2)
				(type solid)
			)
			(layer "B.SilkS")
		)
		(fp_line
			(start -1.03623 0.53624)
			(end -1.03623 -0.53624)
			(stroke
				(width 0.2)
				(type solid)
			)
			(layer "B.CrtYd")
		)
		(fp_line
			(start 1.03624 0.53624)
			(end -1.03623 0.53624)
			(stroke
				(width 0.2)
				(type solid)
			)
			(layer "B.CrtYd")
		)
		(fp_line
			(start 1.03624 0.53624)
			(end 1.03624 -0.53624)
			(stroke
				(width 0.2)
				(type solid)
			)
			(layer "B.CrtYd")
		)
		(fp_line
			(start 1.03624 -0.53624)
			(end -1.03623 -0.53624)
			(stroke
				(width 0.2)
				(type solid)
			)
			(layer "B.CrtYd")
		)
		(fp_line
			(start -1.03623 0.53624)
			(end -1.03623 -0.53624)
			(stroke
				(width 0.2)
				(type solid)
			)
			(layer "B.Fab")
		)
		(fp_line
			(start 1.03624 0.53624)
			(end -1.03623 0.53624)
			(stroke
				(width 0.2)
				(type solid)
			)
			(layer "B.Fab")
		)
		(fp_line
			(start 1.03624 0.53624)
			(end 1.03624 -0.53624)
			(stroke
				(width 0.2)
				(type solid)
			)
			(layer "B.Fab")
		)
		(fp_line
			(start 0 0.5)
			(end 0 -0.5)
			(stroke
				(width 0.1)
				(type solid)
			)
			(layer "B.Fab")
		)
		(fp_line
			(start 0.5 0)
			(end -0.5 0)
			(stroke
				(width 0.1)
				(type solid)
			)
			(layer "B.Fab")
		)
		(fp_line
			(start 1.03624 -0.53624)
			(end -1.03623 -0.53624)
			(stroke
				(width 0.2)
				(type solid)
			)
			(layer "B.Fab")
		)
		(fp_text user "${REFERENCE}"
			(at -0.00001 -0.09601 90)
			(unlocked yes)
			(layer "B.Fab")
			(effects
				(font
					(face "Arial")
					(size 0.63 0.63)
					(thickness 0.1)
				)
				(justify left bottom mirror)
			)
		)
		(pad "1" smd rect
			(at -0.47856 0 270)
			(size 0.71535 0.67248)
			(layers "B.Cu" "B.Mask" "B.Paste")
			(net "FTDI_P3V3")
			(solder_mask_margin 0)
			(solder_paste_margin 0)
		)
		(pad "2" smd rect
			(at 0.47857 0 270)
			(size 0.71535 0.67248)
			(layers "B.Cu" "B.Mask" "B.Paste")
			(net "GND")
			(solder_mask_margin 0)
			(solder_paste_margin 0)
		)
	)
	(footprint "Vault:FP-MK212BG-MFG"
		(layer "B.Cu")
		(at 207.5592 134.4334)
		(property "Reference" "C34"
			(at 0.17115 1.355879 180)
			(unlocked yes)
			(layer "B.SilkS")
			(effects
				(font
					(size 0.762 0.762)
					(thickness 0.2286)
				)
				(justify mirror)
			)
		)
		(property "Value" "10uF"
			(at -3.240271 -2.22164 270)
			(unlocked yes)
			(layer "B.SilkS")
			(hide yes)
			(effects
				(font
					(size 0.762 0.762)
					(thickness 0.2286)
				)
				(justify mirror)
			)
		)
		(sheetname "05-GPS_IMU_SENSORS")
		(sheetfile "05-GPS_IMU_SENSORS.kicad_sch")
		(duplicate_pad_numbers_are_jumpers no)
		(fp_line
			(start -0.125 -0.725)
			(end 0.125 -0.725)
			(stroke
				(width 0.2)
				(type solid)
			)
			(layer "B.SilkS")
		)
		(fp_line
			(start -0.125 0.725)
			(end 0.125 0.725)
			(stroke
				(width 0.2)
				(type solid)
			)
			(layer "B.SilkS")
		)
		(fp_line
			(start -1.6 -0.825)
			(end 1.6 -0.825)
			(stroke
				(width 0.2)
				(type solid)
			)
			(layer "B.CrtYd")
		)
		(fp_line
			(start -1.6 0.825)
			(end -1.6 -0.825)
			(stroke
				(width 0.2)
				(type solid)
			)
			(layer "B.CrtYd")
		)
		(fp_line
			(start -1.6 0.825)
			(end 1.6 0.825)
			(stroke
				(width 0.2)
				(type solid)
			)
			(layer "B.CrtYd")
		)
		(fp_line
			(start 1.6 0.825)
			(end 1.6 -0.825)
			(stroke
				(width 0.2)
				(type solid)
			)
			(layer "B.CrtYd")
		)
		(fp_line
			(start -1.6 -0.825)
			(end 1.6 -0.825)
			(stroke
				(width 0.2)
				(type solid)
			)
			(layer "B.Fab")
		)
		(fp_line
			(start -1.6 0.825)
			(end -1.6 -0.825)
			(stroke
				(width 0.2)
				(type solid)
			)
			(layer "B.Fab")
		)
		(fp_line
			(start -1.6 0.825)
			(end 1.6 0.825)
			(stroke
				(width 0.2)
				(type solid)
			)
			(layer "B.Fab")
		)
		(fp_line
			(start -0.5 0)
			(end 0.5 0)
			(stroke
				(width 0.1)
				(type solid)
			)
			(layer "B.Fab")
		)
		(fp_line
			(start 0 0.5)
			(end 0 -0.5)
			(stroke
				(width 0.1)
				(type solid)
			)
			(layer "B.Fab")
		)
		(fp_line
			(start 1.6 0.825)
			(end 1.6 -0.825)
			(stroke
				(width 0.2)
				(type solid)
			)
			(layer "B.Fab")
		)
		(fp_text user "${REFERENCE}"
			(at -0.00001 -0.09601 180)
			(unlocked yes)
			(layer "B.Fab")
			(effects
				(font
					(face "Arial")
					(size 0.63 0.63)
					(thickness 0.1)
				)
				(justify left bottom mirror)
			)
		)
		(pad "1" smd rect
			(at -1 0)
			(size 1 1.25)
			(layers "B.Cu" "B.Mask" "B.Paste")
			(net "GNSS2_P3V3")
			(solder_mask_margin 0)
			(solder_paste_margin 0)
		)
		(pad "2" smd rect
			(at 1 0)
			(size 1 1.25)
			(layers "B.Cu" "B.Mask" "B.Paste")
			(net "GND")
			(solder_mask_margin 0)
			(solder_paste_margin 0)
		)
	)
	(footprint "Vault:CAPC1608X87X45ML20T05"
		(layer "B.Cu")
		(at 215.9216 136.2162 180)
		(property "Reference" "C57"
			(at -0.2286 -1.173069 180)
			(unlocked yes)
			(layer "B.SilkS")
			(effects
				(font
					(size 0.762 0.762)
					(thickness 0.2286)
				)
				(justify mirror)
			)
		)
		(property "Value" "0.1uF"
			(at 2.069035 -2.630671 0)
			(unlocked yes)
			(layer "B.SilkS")
			(hide yes)
			(effects
				(font
					(size 0.762 0.762)
					(thickness 0.2286)
				)
				(justify mirror)
			)
		)
		(sheetname "05-GPS_IMU_SENSORS")
		(sheetfile "05-GPS_IMU_SENSORS.kicad_sch")
		(duplicate_pad_numbers_are_jumpers no)
		(pad "1" smd rect
			(at -0.7 0 90)
			(size 1.1 1.05)
			(layers "B.Cu" "B.Mask" "B.Paste")
			(net "GND")
		)
		(pad "2" smd rect
			(at 0.7 0 90)
			(size 1.1 1.05)
			(layers "B.Cu" "B.Mask" "B.Paste")
			(net "GNSS2_P3V3")
		)
	)
	(footprint "Vault:RESC1005X40X25LL05T10"
		(layer "B.Cu")
		(at 220.4216 109.5162)
		(property "Reference" "R78"
			(at -2.3286 0.126931 0)
			(unlocked yes)
			(layer "B.SilkS")
			(effects
				(font
					(size 0.762 0.762)
					(thickness 0.2286)
				)
				(justify mirror)
			)
		)
		(property "Value" "10K_1%_0402"
			(at -2.884671 -8.036475 270)
			(unlocked yes)
			(layer "B.SilkS")
			(hide yes)
			(effects
				(font
					(size 0.762 0.762)
					(thickness 0.2286)
				)
				(justify mirror)
			)
		)
		(sheetname "08-DIPSwitches_I2C")
		(sheetfile "08-DIPSwitches_I2C.kicad_sch")
		(duplicate_pad_numbers_are_jumpers no)
		(pad "1" smd rect
			(at -0.375 0 270)
			(size 0.45 0.5)
			(layers "B.Cu" "B.Mask" "B.Paste")
			(net "+3.3V")
		)
		(pad "2" smd rect
			(at 0.375 0 270)
			(size 0.45 0.5)
			(layers "B.Cu" "B.Mask" "B.Paste")
			(net "DIP_SW_UART_SEL")
		)
	)
	(footprint "Vault:RESC1005X40X25LL05T05"
		(layer "B.Cu")
		(at 100.2216 62.8162 180)
		(property "Reference" "R3"
			(at 1.1 -0.493345 0)
			(unlocked yes)
			(layer "B.SilkS")
			(effects
				(font
					(size 0.762 0.762)
					(thickness 0.2286)
				)
				(justify left bottom mirror)
			)
		)
		(property "Value" "0_1%_0402"
			(at 26.9821 -21.663245 0)
			(unlocked yes)
			(layer "B.SilkS")
			(hide yes)
			(effects
				(font
					(size 0.762 0.762)
					(thickness 0.2286)
				)
				(justify left bottom mirror)
			)
		)
		(sheetname "03-POWER")
		(sheetfile "03-POWER.kicad_sch")
		(duplicate_pad_numbers_are_jumpers no)
		(pad "1" smd rect
			(at -0.4 0 90)
			(size 0.45 0.45)
			(layers "B.Cu" "B.Mask" "B.Paste")
			(net "NetR2_2")
		)
		(pad "2" smd rect
			(at 0.4 0 90)
			(size 0.45 0.45)
			(layers "B.Cu" "B.Mask" "B.Paste")
			(net "P5V_SENSE")
		)
	)
	(footprint "Capacitors:CAPC1005X06N"
		(layer "B.Cu")
		(at 124.5576 151.7886 90)
		(property "Reference" "C44"
			(at 2.885 -1.204345 270)
			(unlocked yes)
			(layer "B.SilkS")
			(effects
				(font
					(size 0.762 0.762)
					(thickness 0.2286)
				)
				(justify left bottom mirror)
			)
		)
		(property "Value" "CAP_0402_0.1UF_50V"
			(at -3.382645 0.2921 0)
			(unlocked yes)
			(layer "B.SilkS")
			(hide yes)
			(effects
				(font
					(size 0.762 0.762)
					(thickness 0.2286)
				)
				(justify left bottom mirror)
			)
		)
		(sheetname "04-PCIe_JTAG")
		(sheetfile "04-PCIe_JTAG.kicad_sch")
		(duplicate_pad_numbers_are_jumpers no)
		(pad "1" smd rect
			(at -0.43 0)
			(size 0.64 0.68)
			(layers "B.Cu" "B.Mask" "B.Paste")
			(net "NetC44_1")
		)
		(pad "2" smd rect
			(at 0.43 0)
			(size 0.64 0.68)
			(layers "B.Cu" "B.Mask" "B.Paste")
			(net "PCIE_CLK_P")
		)
	)
	(footprint "Vault:FP-MK212BG-MFG"
		(layer "B.Cu")
		(at 215.9216 133.8162)
		(property "Reference" "C55"
			(at -0.2286 -1.673069 0)
			(unlocked yes)
			(layer "B.SilkS")
			(effects
				(font
					(size 0.762 0.762)
					(thickness 0.2286)
				)
				(justify mirror)
			)
		)
		(property "Value" "10uF"
			(at -3.240271 -2.22164 270)
			(unlocked yes)
			(layer "B.SilkS")
			(hide yes)
			(effects
				(font
					(size 0.762 0.762)
					(thickness 0.2286)
				)
				(justify mirror)
			)
		)
		(sheetname "05-GPS_IMU_SENSORS")
		(sheetfile "05-GPS_IMU_SENSORS.kicad_sch")
		(duplicate_pad_numbers_are_jumpers no)
		(fp_line
			(start -0.125 -0.725)
			(end 0.125 -0.725)
			(stroke
				(width 0.2)
				(type solid)
			)
			(layer "B.SilkS")
		)
		(fp_line
			(start -0.125 0.725)
			(end 0.125 0.725)
			(stroke
				(width 0.2)
				(type solid)
			)
			(layer "B.SilkS")
		)
		(fp_line
			(start -1.6 -0.825)
			(end 1.6 -0.825)
			(stroke
				(width 0.2)
				(type solid)
			)
			(layer "B.CrtYd")
		)
		(fp_line
			(start -1.6 0.825)
			(end -1.6 -0.825)
			(stroke
				(width 0.2)
				(type solid)
			)
			(layer "B.CrtYd")
		)
		(fp_line
			(start -1.6 0.825)
			(end 1.6 0.825)
			(stroke
				(width 0.2)
				(type solid)
			)
			(layer "B.CrtYd")
		)
		(fp_line
			(start 1.6 0.825)
			(end 1.6 -0.825)
			(stroke
				(width 0.2)
				(type solid)
			)
			(layer "B.CrtYd")
		)
		(fp_line
			(start -1.6 -0.825)
			(end 1.6 -0.825)
			(stroke
				(width 0.2)
				(type solid)
			)
			(layer "B.Fab")
		)
		(fp_line
			(start -1.6 0.825)
			(end -1.6 -0.825)
			(stroke
				(width 0.2)
				(type solid)
			)
			(layer "B.Fab")
		)
		(fp_line
			(start -1.6 0.825)
			(end 1.6 0.825)
			(stroke
				(width 0.2)
				(type solid)
			)
			(layer "B.Fab")
		)
		(fp_line
			(start -0.5 0)
			(end 0.5 0)
			(stroke
				(width 0.1)
				(type solid)
			)
			(layer "B.Fab")
		)
		(fp_line
			(start 0 0.5)
			(end 0 -0.5)
			(stroke
				(width 0.1)
				(type solid)
			)
			(layer "B.Fab")
		)
		(fp_line
			(start 1.6 0.825)
			(end 1.6 -0.825)
			(stroke
				(width 0.2)
				(type solid)
			)
			(layer "B.Fab")
		)
		(fp_text user "${REFERENCE}"
			(at -0.00002 -0.09601 180)
			(unlocked yes)
			(layer "B.Fab")
			(effects
				(font
					(face "Arial")
					(size 0.63 0.63)
					(thickness 0.1)
				)
				(justify left bottom mirror)
			)
		)
		(pad "1" smd rect
			(at -1 0)
			(size 1 1.25)
			(layers "B.Cu" "B.Mask" "B.Paste")
			(net "GNSS2_P3V3")
			(solder_mask_margin 0)
			(solder_paste_margin 0)
		)
		(pad "2" smd rect
			(at 1 0)
			(size 1 1.25)
			(layers "B.Cu" "B.Mask" "B.Paste")
			(net "GND")
			(solder_mask_margin 0)
			(solder_paste_margin 0)
		)
	)
	(footprint "Vault:RESC1005X40X25LL05T05"
		(layer "B.Cu")
		(at 83.5116 67.39847)
		(property "Reference" "R65"
			(at -0.3186 0.944651 0)
			(unlocked yes)
			(layer "B.SilkS")
			(effects
				(font
					(size 0.762 0.762)
					(thickness 0.2286)
				)
				(justify mirror)
			)
		)
		(property "Value" "0_1%_0402"
			(at -2.579871 -6.66537 270)
			(unlocked yes)
			(layer "B.SilkS")
			(hide yes)
			(effects
				(font
					(size 0.762 0.762)
					(thickness 0.2286)
				)
				(justify mirror)
			)
		)
		(sheetname "03-POWER")
		(sheetfile "03-POWER.kicad_sch")
		(duplicate_pad_numbers_are_jumpers no)
		(pad "1" smd rect
			(at -0.4 0 270)
			(size 0.45 0.45)
			(layers "B.Cu" "B.Mask" "B.Paste")
			(net "NetR65_1")
		)
		(pad "2" smd rect
			(at 0.4 0 270)
			(size 0.45 0.45)
			(layers "B.Cu" "B.Mask" "B.Paste")
			(net "+3.3V")
		)
	)
	(footprint "Vault:RESC1005X40X25LL05T05"
		(layer "B.Cu")
		(at 111.88072 89.9662)
		(property "Reference" "R56"
			(at 0.36948 7.423069 180)
			(unlocked yes)
			(layer "B.SilkS")
			(effects
				(font
					(size 0.762 0.762)
					(thickness 0.2286)
				)
				(justify mirror)
			)
		)
		(property "Value" "DNI_4.7K_0402"
			(at -3.151351 -5.29409 270)
			(unlocked yes)
			(layer "B.SilkS")
			(hide yes)
			(effects
				(font
					(size 0.762 0.762)
					(thickness 0.2286)
				)
				(justify mirror)
			)
		)
		(sheetname "05-GPS_IMU_SENSORS")
		(sheetfile "05-GPS_IMU_SENSORS.kicad_sch")
		(duplicate_pad_numbers_are_jumpers no)
		(pad "1" smd rect
			(at -0.4 0 270)
			(size 0.45 0.45)
			(layers "B.Cu" "B.Mask" "B.Paste")
			(net "GND")
		)
		(pad "2" smd rect
			(at 0.4 0 270)
			(size 0.45 0.45)
			(layers "B.Cu" "B.Mask" "B.Paste")
			(net "NetR53_1")
		)
	)
	(footprint "Vault:FP-0402-L_1_0_1-W_0_5_0_1-IPC_C"
		(layer "B.Cu")
		(at 194.1216 122.6162 180)
		(property "Reference" "C106"
			(at 0.6032 1.673069 0)
			(unlocked yes)
			(layer "B.SilkS")
			(effects
				(font
					(size 0.762 0.762)
					(thickness 0.2032)
				)
				(justify mirror)
			)
		)
		(property "Value" "0.1uF_25V_0402"
			(at -2.465551 -9.813815 90)
			(unlocked yes)
			(layer "B.SilkS")
			(hide yes)
			(effects
				(font
					(size 0.762 0.762)
					(thickness 0.2032)
				)
				(justify mirror)
			)
		)
		(sheetname "11-M2_RCB_MUX")
		(sheetfile "11-M2_RCB_MUX.kicad_sch")
		(duplicate_pad_numbers_are_jumpers no)
		(fp_line
			(start 0.65607 0.7)
			(end -0.65607 0.7)
			(stroke
				(width 0.2)
				(type solid)
			)
			(layer "B.SilkS")
		)
		(fp_line
			(start 0.65607 -0.7)
			(end -0.65607 -0.7)
			(stroke
				(width 0.2)
				(type solid)
			)
			(layer "B.SilkS")
		)
		(fp_line
			(start 0.75607 0.4)
			(end -0.75607 0.4)
			(stroke
				(width 0.2)
				(type solid)
			)
			(layer "B.CrtYd")
		)
		(fp_line
			(start 0.75607 -0.4)
			(end 0.75607 0.4)
			(stroke
				(width 0.2)
				(type solid)
			)
			(layer "B.CrtYd")
		)
		(fp_line
			(start 0.75607 -0.4)
			(end -0.75607 -0.4)
			(stroke
				(width 0.2)
				(type solid)
			)
			(layer "B.CrtYd")
		)
		(fp_line
			(start -0.75607 -0.4)
			(end -0.75607 0.4)
			(stroke
				(width 0.2)
				(type solid)
			)
			(layer "B.CrtYd")
		)
		(fp_line
			(start 0.75607 0.4)
			(end -0.75607 0.4)
			(stroke
				(width 0.2)
				(type solid)
			)
			(layer "B.Fab")
		)
		(fp_line
			(start 0.75607 -0.4)
			(end 0.75607 0.4)
			(stroke
				(width 0.2)
				(type solid)
			)
			(layer "B.Fab")
		)
		(fp_line
			(start 0.75607 -0.4)
			(end -0.75607 -0.4)
			(stroke
				(width 0.2)
				(type solid)
			)
			(layer "B.Fab")
		)
		(fp_line
			(start 0.5 0)
			(end -0.5 0)
			(stroke
				(width 0.1)
				(type solid)
			)
			(layer "B.Fab")
		)
		(fp_line
			(start 0 -0.5)
			(end 0 0.5)
			(stroke
				(width 0.1)
				(type solid)
			)
			(layer "B.Fab")
		)
		(fp_line
			(start -0.75607 -0.4)
			(end -0.75607 0.4)
			(stroke
				(width 0.2)
				(type solid)
			)
			(layer "B.Fab")
		)
		(fp_text user "${REFERENCE}"
			(at -0.00001 -0.09602 360)
			(unlocked yes)
			(layer "B.Fab")
			(effects
				(font
					(face "Arial")
					(size 0.63 0.63)
					(thickness 0.1)
				)
				(justify left bottom mirror)
			)
		)
		(pad "1" smd rect
			(at -0.36554 0 180)
			(size 0.58106 0.51213)
			(layers "B.Cu" "B.Mask" "B.Paste")
			(net "+3.3V")
			(solder_mask_margin 0)
			(solder_paste_margin 0)
		)
		(pad "2" smd rect
			(at 0.36554 0 180)
			(size 0.58106 0.51213)
			(layers "B.Cu" "B.Mask" "B.Paste")
			(net "GND")
			(solder_mask_margin 0)
			(solder_paste_margin 0)
		)
	)
	(footprint "Vault:FP-0402-L_1_0_1-W_0_5_0_1-IPC_C"
		(layer "B.Cu")
		(at 158.3216 129.5162 180)
		(property "Reference" "C94"
			(at 0.2286 1.687989 0)
			(unlocked yes)
			(layer "B.SilkS")
			(effects
				(font
					(size 0.762 0.762)
					(thickness 0.2286)
				)
				(justify mirror)
			)
		)
		(property "Value" "0.1uF_25V_0402"
			(at -2.465551 -9.839215 90)
			(unlocked yes)
			(layer "B.SilkS")
			(hide yes)
			(effects
				(font
					(size 0.762 0.762)
					(thickness 0.2286)
				)
				(justify mirror)
			)
		)
		(sheetname "09-USBUart_PPSMUX_UARTMUX")
		(sheetfile "09-USBUart_PPSMUX_UARTMUX.kicad_sch")
		(duplicate_pad_numbers_are_jumpers no)
		(fp_line
			(start 0.65607 0.7)
			(end -0.65607 0.7)
			(stroke
				(width 0.2)
				(type solid)
			)
			(layer "B.SilkS")
		)
		(fp_line
			(start 0.65607 -0.7)
			(end -0.65607 -0.7)
			(stroke
				(width 0.2)
				(type solid)
			)
			(layer "B.SilkS")
		)
		(fp_line
			(start 0.75607 0.4)
			(end -0.75607 0.4)
			(stroke
				(width 0.2)
				(type solid)
			)
			(layer "B.CrtYd")
		)
		(fp_line
			(start 0.75607 -0.4)
			(end 0.75607 0.4)
			(stroke
				(width 0.2)
				(type solid)
			)
			(layer "B.CrtYd")
		)
		(fp_line
			(start 0.75607 -0.4)
			(end -0.75607 -0.4)
			(stroke
				(width 0.2)
				(type solid)
			)
			(layer "B.CrtYd")
		)
		(fp_line
			(start -0.75607 -0.4)
			(end -0.75607 0.4)
			(stroke
				(width 0.2)
				(type solid)
			)
			(layer "B.CrtYd")
		)
		(fp_line
			(start 0.75607 0.4)
			(end -0.75607 0.4)
			(stroke
				(width 0.2)
				(type solid)
			)
			(layer "B.Fab")
		)
		(fp_line
			(start 0.75607 -0.4)
			(end 0.75607 0.4)
			(stroke
				(width 0.2)
				(type solid)
			)
			(layer "B.Fab")
		)
		(fp_line
			(start 0.75607 -0.4)
			(end -0.75607 -0.4)
			(stroke
				(width 0.2)
				(type solid)
			)
			(layer "B.Fab")
		)
		(fp_line
			(start 0.5 0)
			(end -0.5 0)
			(stroke
				(width 0.1)
				(type solid)
			)
			(layer "B.Fab")
		)
		(fp_line
			(start 0 -0.5)
			(end 0 0.5)
			(stroke
				(width 0.1)
				(type solid)
			)
			(layer "B.Fab")
		)
		(fp_line
			(start -0.75607 -0.4)
			(end -0.75607 0.4)
			(stroke
				(width 0.2)
				(type solid)
			)
			(layer "B.Fab")
		)
		(fp_text user "${REFERENCE}"
			(at -0.00001 -0.09602 360)
			(unlocked yes)
			(layer "B.Fab")
			(effects
				(font
					(face "Arial")
					(size 0.63 0.63)
					(thickness 0.1)
				)
				(justify left bottom mirror)
			)
		)
		(pad "1" smd rect
			(at -0.36554 0 180)
			(size 0.58106 0.51213)
			(layers "B.Cu" "B.Mask" "B.Paste")
			(net "+3.3V")
			(solder_mask_margin 0)
			(solder_paste_margin 0)
		)
		(pad "2" smd rect
			(at 0.36554 0 180)
			(size 0.58106 0.51213)
			(layers "B.Cu" "B.Mask" "B.Paste")
			(net "GND")
			(solder_mask_margin 0)
			(solder_paste_margin 0)
		)
	)
	(footprint "Vault:RESC1005X40X25NL10T10"
		(layer "B.Cu")
		(at 76.7216 129.9162 90)
		(property "Reference" "R16"
			(at 2.0714 0.026931 90)
			(unlocked yes)
			(layer "B.SilkS")
			(effects
				(font
					(size 0.762 0.762)
					(thickness 0.2286)
				)
				(justify mirror)
			)
		)
		(property "Value" "4.7K_1%_0402"
			(at -0.558471 -4.825345 0)
			(unlocked yes)
			(layer "B.SilkS")
			(hide yes)
			(effects
				(font
					(size 0.762 0.762)
					(thickness 0.2286)
				)
				(justify mirror)
			)
		)
		(sheetname "01-USER_IO")
		(sheetfile "01-USER_IO.kicad_sch")
		(duplicate_pad_numbers_are_jumpers no)
		(pad "1" smd rect
			(at -0.425 0)
			(size 0.6 0.65)
			(layers "B.Cu" "B.Mask" "B.Paste")
			(net "+3.3V")
		)
		(pad "2" smd rect
			(at 0.425 0)
			(size 0.6 0.65)
			(layers "B.Cu" "B.Mask" "B.Paste")
			(net "ANT3_IO_IN")
		)
	)
	(footprint "Vault:RESC1005X40X25NL05T05"
		(layer "B.Cu")
		(at 220.6216 113.7162 -90)
		(property "Reference" "R122"
			(at -0.0968 1.273079 90)
			(unlocked yes)
			(layer "B.SilkS")
			(effects
				(font
					(size 0.762 0.762)
					(thickness 0.2032)
				)
				(justify mirror)
			)
		)
		(property "Value" "200_1%_0402"
			(at -2.732271 -8.112675 180)
			(unlocked yes)
			(layer "B.SilkS")
			(hide yes)
			(effects
				(font
					(size 0.762 0.762)
					(thickness 0.2032)
				)
				(justify mirror)
			)
		)
		(sheetname "08-DIPSwitches_I2C")
		(sheetfile "08-DIPSwitches_I2C.kicad_sch")
		(duplicate_pad_numbers_are_jumpers no)
		(pad "1" smd rect
			(at -0.45 0 180)
			(size 0.55 0.55)
			(layers "B.Cu" "B.Mask" "B.Paste")
			(net "NetD22_1")
		)
		(pad "2" smd rect
			(at 0.45 0 180)
			(size 0.55 0.55)
			(layers "B.Cu" "B.Mask" "B.Paste")
			(net "DIP_SW_PPS_SEL")
		)
	)
	(footprint "Vault:CAPC1608X87X45ML20T05"
		(layer "B.Cu")
		(at 180.30985 105.2162 -90)
		(property "Reference" "C25"
			(at -2.4338 0.023079 90)
			(unlocked yes)
			(layer "B.SilkS")
			(effects
				(font
					(size 0.762 0.762)
					(thickness 0.2286)
				)
				(justify mirror)
			)
		)
		(property "Value" "0.1uF"
			(at 2.069025 -2.630671 90)
			(unlocked yes)
			(layer "B.SilkS")
			(hide yes)
			(effects
				(font
					(size 0.762 0.762)
					(thickness 0.2286)
				)
				(justify mirror)
			)
		)
		(sheetname "05-GPS_IMU_SENSORS")
		(sheetfile "05-GPS_IMU_SENSORS.kicad_sch")
		(duplicate_pad_numbers_are_jumpers no)
		(pad "1" smd rect
			(at -0.7 0 180)
			(size 1.1 1.05)
			(layers "B.Cu" "B.Mask" "B.Paste")
			(net "GND")
		)
		(pad "2" smd rect
			(at 0.7 0 180)
			(size 1.1 1.05)
			(layers "B.Cu" "B.Mask" "B.Paste")
			(net "+3.3V")
		)
	)
	(footprint "Vault:RESC1005X40X25LL05T05"
		(layer "B.Cu")
		(at 112.58072 86.8662)
		(property "Reference" "R55"
			(at -0.23052 6.823069 180)
			(unlocked yes)
			(layer "B.SilkS")
			(effects
				(font
					(size 0.762 0.762)
					(thickness 0.2286)
				)
				(justify mirror)
			)
		)
		(property "Value" "4.7K_0402"
			(at -3.024391 -2.374045 270)
			(unlocked yes)
			(layer "B.SilkS")
			(hide yes)
			(effects
				(font
					(size 0.762 0.762)
					(thickness 0.2286)
				)
				(justify mirror)
			)
		)
		(sheetname "05-GPS_IMU_SENSORS")
		(sheetfile "05-GPS_IMU_SENSORS.kicad_sch")
		(duplicate_pad_numbers_are_jumpers no)
		(pad "1" smd rect
			(at -0.4 0 270)
			(size 0.45 0.45)
			(layers "B.Cu" "B.Mask" "B.Paste")
			(net "BNO_BLIND")
		)
		(pad "2" smd rect
			(at 0.40001 0 270)
			(size 0.45 0.45)
			(layers "B.Cu" "B.Mask" "B.Paste")
			(net "NetR55_2")
		)
	)
	(footprint "Vault:RESC1005X40X25NL10T10"
		(layer "B.Cu")
		(at 88.1716 56.5662)
		(property "Reference" "R9"
			(at 0.75 -0.456655 0)
			(unlocked yes)
			(layer "B.SilkS")
			(effects
				(font
					(size 0.762 0.762)
					(thickness 0.2286)
				)
				(justify left bottom mirror)
			)
		)
		(property "Value" "20K_1%_0402"
			(at -10.4651 10.660245 0)
			(unlocked yes)
			(layer "B.SilkS")
			(hide yes)
			(effects
				(font
					(size 0.762 0.762)
					(thickness 0.2286)
				)
				(justify left bottom mirror)
			)
		)
		(sheetname "03-POWER")
		(sheetfile "03-POWER.kicad_sch")
		(duplicate_pad_numbers_are_jumpers no)
		(pad "1" smd rect
			(at -0.425 0 270)
			(size 0.6 0.65)
			(layers "B.Cu" "B.Mask" "B.Paste")
			(net "+12V")
		)
		(pad "2" smd rect
			(at 0.425 0 270)
			(size 0.6 0.65)
			(layers "B.Cu" "B.Mask" "B.Paste")
			(net "NetR9_2")
		)
	)
	(footprint "Vault:CAPC1608X87X45ML20T05"
		(layer "B.Cu")
		(at 207.6216 131.5162 180)
		(property "Reference" "C36"
			(at 0.1286 1.373079 0)
			(unlocked yes)
			(layer "B.SilkS")
			(effects
				(font
					(size 0.762 0.762)
					(thickness 0.2286)
				)
				(justify mirror)
			)
		)
		(property "Value" "0.1uF"
			(at 2.069035 -2.630671 0)
			(unlocked yes)
			(layer "B.SilkS")
			(hide yes)
			(effects
				(font
					(size 0.762 0.762)
					(thickness 0.2286)
				)
				(justify mirror)
			)
		)
		(sheetname "05-GPS_IMU_SENSORS")
		(sheetfile "05-GPS_IMU_SENSORS.kicad_sch")
		(duplicate_pad_numbers_are_jumpers no)
		(pad "1" smd rect
			(at -0.7 0 90)
			(size 1.1 1.05)
			(layers "B.Cu" "B.Mask" "B.Paste")
			(net "GND")
		)
		(pad "2" smd rect
			(at 0.7 0 90)
			(size 1.1 1.05)
			(layers "B.Cu" "B.Mask" "B.Paste")
			(net "GNSS2_P3V3")
		)
	)
	(footprint "Vault:FP-0402-L_1_0_1-W_0_5_0_1-IPC_C"
		(layer "B.Cu")
		(at 126.5216 74.1162 -90)
		(property "Reference" "C100"
			(at 2.8887 -0.141431 90)
			(unlocked yes)
			(layer "B.SilkS")
			(effects
				(font
					(size 0.762 0.762)
					(thickness 0.2032)
				)
				(justify mirror)
			)
		)
		(property "Value" "0.1uF_25V_0402"
			(at -2.465551 -9.813805 180)
			(unlocked yes)
			(layer "B.SilkS")
			(hide yes)
			(effects
				(font
					(size 0.762 0.762)
					(thickness 0.2032)
				)
				(justify mirror)
			)
		)
		(sheetname "10-M2_GPS")
		(sheetfile "10-M2_GPS.kicad_sch")
		(duplicate_pad_numbers_are_jumpers no)
		(fp_line
			(start 0.65607 0.7)
			(end -0.65607 0.7)
			(stroke
				(width 0.2)
				(type solid)
			)
			(layer "B.SilkS")
		)
		(fp_line
			(start 0.65607 -0.7)
			(end -0.65607 -0.7)
			(stroke
				(width 0.2)
				(type solid)
			)
			(layer "B.SilkS")
		)
		(fp_line
			(start -0.75607 0.4)
			(end -0.75607 -0.4)
			(stroke
				(width 0.2)
				(type solid)
			)
			(layer "B.CrtYd")
		)
		(fp_line
			(start 0.75607 0.4)
			(end -0.75607 0.4)
			(stroke
				(width 0.2)
				(type solid)
			)
			(layer "B.CrtYd")
		)
		(fp_line
			(start 0.75607 0.4)
			(end 0.75607 -0.4)
			(stroke
				(width 0.2)
				(type solid)
			)
			(layer "B.CrtYd")
		)
		(fp_line
			(start 0.75607 -0.4)
			(end -0.75607 -0.4)
			(stroke
				(width 0.2)
				(type solid)
			)
			(layer "B.CrtYd")
		)
		(fp_line
			(start 0 0.5)
			(end 0 -0.5)
			(stroke
				(width 0.1)
				(type solid)
			)
			(layer "B.Fab")
		)
		(fp_line
			(start -0.75607 0.4)
			(end -0.75607 -0.4)
			(stroke
				(width 0.2)
				(type solid)
			)
			(layer "B.Fab")
		)
		(fp_line
			(start 0.75607 0.4)
			(end -0.75607 0.4)
			(stroke
				(width 0.2)
				(type solid)
			)
			(layer "B.Fab")
		)
		(fp_line
			(start 0.75607 0.4)
			(end 0.75607 -0.4)
			(stroke
				(width 0.2)
				(type solid)
			)
			(layer "B.Fab")
		)
		(fp_line
			(start 0.5 0)
			(end -0.5 0)
			(stroke
				(width 0.1)
				(type solid)
			)
			(layer "B.Fab")
		)
		(fp_line
			(start 0.75607 -0.4)
			(end -0.75607 -0.4)
			(stroke
				(width 0.2)
				(type solid)
			)
			(layer "B.Fab")
		)
		(fp_text user "${REFERENCE}"
			(at -0.00001 -0.09602 90)
			(unlocked yes)
			(layer "B.Fab")
			(effects
				(font
					(face "Arial")
					(size 0.63 0.63)
					(thickness 0.1)
				)
				(justify left bottom mirror)
			)
		)
		(pad "1" smd rect
			(at -0.36554 0 270)
			(size 0.58106 0.51213)
			(layers "B.Cu" "B.Mask" "B.Paste")
			(net "+3.3V")
			(solder_mask_margin 0)
			(solder_paste_margin 0)
		)
		(pad "2" smd rect
			(at 0.36554 0 270)
			(size 0.58106 0.51213)
			(layers "B.Cu" "B.Mask" "B.Paste")
			(net "GND")
			(solder_mask_margin 0)
			(solder_paste_margin 0)
		)
	)
	(footprint "Vault:FP-MK212BG-MFG"
		(layer "B.Cu")
		(at 207.5592 138.64087)
		(property "Reference" "C35"
			(at -0.28601 -1.566639 0)
			(unlocked yes)
			(layer "B.SilkS")
			(effects
				(font
					(size 0.762 0.762)
					(thickness 0.2286)
				)
				(justify mirror)
			)
		)
		(property "Value" "10uF"
			(at -3.240271 -2.22164 270)
			(unlocked yes)
			(layer "B.SilkS")
			(hide yes)
			(effects
				(font
					(size 0.762 0.762)
					(thickness 0.2286)
				)
				(justify mirror)
			)
		)
		(sheetname "05-GPS_IMU_SENSORS")
		(sheetfile "05-GPS_IMU_SENSORS.kicad_sch")
		(duplicate_pad_numbers_are_jumpers no)
		(fp_line
			(start -0.125 -0.725)
			(end 0.125 -0.725)
			(stroke
				(width 0.2)
				(type solid)
			)
			(layer "B.SilkS")
		)
		(fp_line
			(start -0.125 0.725)
			(end 0.125 0.725)
			(stroke
				(width 0.2)
				(type solid)
			)
			(layer "B.SilkS")
		)
		(fp_line
			(start -1.6 -0.825)
			(end 1.6 -0.825)
			(stroke
				(width 0.2)
				(type solid)
			)
			(layer "B.CrtYd")
		)
		(fp_line
			(start -1.6 0.825)
			(end -1.6 -0.825)
			(stroke
				(width 0.2)
				(type solid)
			)
			(layer "B.CrtYd")
		)
		(fp_line
			(start -1.6 0.825)
			(end 1.6 0.825)
			(stroke
				(width 0.2)
				(type solid)
			)
			(layer "B.CrtYd")
		)
		(fp_line
			(start 1.6 0.825)
			(end 1.6 -0.825)
			(stroke
				(width 0.2)
				(type solid)
			)
			(layer "B.CrtYd")
		)
		(fp_line
			(start -1.6 -0.825)
			(end 1.6 -0.825)
			(stroke
				(width 0.2)
				(type solid)
			)
			(layer "B.Fab")
		)
		(fp_line
			(start -1.6 0.825)
			(end -1.6 -0.825)
			(stroke
				(width 0.2)
				(type solid)
			)
			(layer "B.Fab")
		)
		(fp_line
			(start -1.6 0.825)
			(end 1.6 0.825)
			(stroke
				(width 0.2)
				(type solid)
			)
			(layer "B.Fab")
		)
		(fp_line
			(start -0.5 0)
			(end 0.5 0)
			(stroke
				(width 0.1)
				(type solid)
			)
			(layer "B.Fab")
		)
		(fp_line
			(start 0 0.5)
			(end 0 -0.5)
			(stroke
				(width 0.1)
				(type solid)
			)
			(layer "B.Fab")
		)
		(fp_line
			(start 1.6 0.825)
			(end 1.6 -0.825)
			(stroke
				(width 0.2)
				(type solid)
			)
			(layer "B.Fab")
		)
		(fp_text user "${REFERENCE}"
			(at -0.00001 -0.09601 180)
			(unlocked yes)
			(layer "B.Fab")
			(effects
				(font
					(face "Arial")
					(size 0.63 0.63)
					(thickness 0.1)
				)
				(justify left bottom mirror)
			)
		)
		(pad "1" smd rect
			(at -1 0)
			(size 1 1.25)
			(layers "B.Cu" "B.Mask" "B.Paste")
			(net "GNSS2_P5V0")
			(solder_mask_margin 0)
			(solder_paste_margin 0)
		)
		(pad "2" smd rect
			(at 1 0)
			(size 1 1.25)
			(layers "B.Cu" "B.Mask" "B.Paste")
			(net "GND")
			(solder_mask_margin 0)
			(solder_paste_margin 0)
		)
	)
	(footprint "Vault:RESC1005X40X25NL10T10"
		(layer "B.Cu")
		(at 74.3216 103.7162 90)
		(property "Reference" "R15"
			(at 2.7714 0.026931 90)
			(unlocked yes)
			(layer "B.SilkS")
			(effects
				(font
					(size 0.762 0.762)
					(thickness 0.2286)
				)
				(justify mirror)
			)
		)
		(property "Value" "4.7K_1%_0402"
			(at -3.433471 -5.789055 0)
			(unlocked yes)
			(layer "B.SilkS")
			(hide yes)
			(effects
				(font
					(size 0.762 0.762)
					(thickness 0.2286)
				)
				(justify mirror)
			)
		)
		(sheetname "01-USER_IO")
		(sheetfile "01-USER_IO.kicad_sch")
		(duplicate_pad_numbers_are_jumpers no)
		(pad "1" smd rect
			(at -0.425 0)
			(size 0.6 0.65)
			(layers "B.Cu" "B.Mask" "B.Paste")
			(net "+3.3V")
		)
		(pad "2" smd rect
			(at 0.425 0)
			(size 0.6 0.65)
			(layers "B.Cu" "B.Mask" "B.Paste")
			(net "ANT1_IO_IN")
		)
	)
	(footprint "Vault:FP-0402-L_1_0_1-W_0_5_0_1-IPC_C"
		(layer "B.Cu")
		(at 112.4216 80.51363 90)
		(property "Reference" "C33"
			(at 1.96883 -0.273079 90)
			(unlocked yes)
			(layer "B.SilkS")
			(effects
				(font
					(size 0.762 0.762)
					(thickness 0.2286)
				)
				(justify mirror)
			)
		)
		(property "Value" "0.1uF_25V_0402"
			(at 2.069035 -2.567191 270)
			(unlocked yes)
			(layer "B.SilkS")
			(hide yes)
			(effects
				(font
					(size 0.762 0.762)
					(thickness 0.2286)
				)
				(justify mirror)
			)
		)
		(sheetname "05-GPS_IMU_SENSORS")
		(sheetfile "05-GPS_IMU_SENSORS.kicad_sch")
		(duplicate_pad_numbers_are_jumpers no)
		(fp_line
			(start -0.65606 -0.7)
			(end 0.65607 -0.7)
			(stroke
				(width 0.2)
				(type solid)
			)
			(layer "B.SilkS")
		)
		(fp_line
			(start -0.65606 0.7)
			(end 0.65607 0.7)
			(stroke
				(width 0.2)
				(type solid)
			)
			(layer "B.SilkS")
		)
		(fp_line
			(start 0.75607 -0.4)
			(end 0.75607 0.4)
			(stroke
				(width 0.2)
				(type solid)
			)
			(layer "B.CrtYd")
		)
		(fp_line
			(start -0.75606 -0.4)
			(end 0.75607 -0.4)
			(stroke
				(width 0.2)
				(type solid)
			)
			(layer "B.CrtYd")
		)
		(fp_line
			(start -0.75606 -0.4)
			(end -0.75606 0.4)
			(stroke
				(width 0.2)
				(type solid)
			)
			(layer "B.CrtYd")
		)
		(fp_line
			(start -0.75606 0.4)
			(end 0.75607 0.4)
			(stroke
				(width 0.2)
				(type solid)
			)
			(layer "B.CrtYd")
		)
		(fp_line
			(start 0 -0.5)
			(end 0 0.5)
			(stroke
				(width 0.1)
				(type solid)
			)
			(layer "B.Fab")
		)
		(fp_line
			(start 0.75607 -0.4)
			(end 0.75607 0.4)
			(stroke
				(width 0.2)
				(type solid)
			)
			(layer "B.Fab")
		)
		(fp_line
			(start -0.75606 -0.4)
			(end 0.75607 -0.4)
			(stroke
				(width 0.2)
				(type solid)
			)
			(layer "B.Fab")
		)
		(fp_line
			(start -0.75606 -0.4)
			(end -0.75606 0.4)
			(stroke
				(width 0.2)
				(type solid)
			)
			(layer "B.Fab")
		)
		(fp_line
			(start -0.5 0)
			(end 0.5 0)
			(stroke
				(width 0.1)
				(type solid)
			)
			(layer "B.Fab")
		)
		(fp_line
			(start -0.75606 0.4)
			(end 0.75607 0.4)
			(stroke
				(width 0.2)
				(type solid)
			)
			(layer "B.Fab")
		)
		(fp_text user "${REFERENCE}"
			(at -0.00001 -0.09602 270)
			(unlocked yes)
			(layer "B.Fab")
			(effects
				(font
					(face "Arial")
					(size 0.63 0.63)
					(thickness 0.1)
				)
				(justify left bottom mirror)
			)
		)
		(pad "1" smd rect
			(at -0.36553 0 90)
			(size 0.58106 0.51213)
			(layers "B.Cu" "B.Mask" "B.Paste")
			(net "BNO_P3V3")
			(solder_mask_margin 0)
			(solder_paste_margin 0)
		)
		(pad "2" smd rect
			(at 0.36554 0 90)
			(size 0.58106 0.51213)
			(layers "B.Cu" "B.Mask" "B.Paste")
			(net "GND")
			(solder_mask_margin 0)
			(solder_paste_margin 0)
		)
	)
	(footprint "Vault:CAPC1005X55X25LL05T10"
		(layer "B.Cu")
		(at 225.2116 116.83603 180)
		(property "Reference" "C88"
			(at -0.1386 -1.253239 180)
			(unlocked yes)
			(layer "B.SilkS")
			(effects
				(font
					(size 0.762 0.762)
					(thickness 0.2286)
				)
				(justify mirror)
			)
		)
		(property "Value" "47pF_50V_0402"
			(at -2.656031 -9.61078 90)
			(unlocked yes)
			(layer "B.SilkS")
			(hide yes)
			(effects
				(font
					(size 0.762 0.762)
					(thickness 0.2286)
				)
				(justify mirror)
			)
		)
		(sheetname "09-USBUart_PPSMUX_UARTMUX")
		(sheetfile "09-USBUart_PPSMUX_UARTMUX.kicad_sch")
		(duplicate_pad_numbers_are_jumpers no)
		(pad "1" smd rect
			(at -0.39 0 90)
			(size 0.52 0.56)
			(layers "B.Cu" "B.Mask" "B.Paste")
			(net "GND")
		)
		(pad "2" smd rect
			(at 0.39 0 90)
			(size 0.52 0.56)
			(layers "B.Cu" "B.Mask" "B.Paste")
			(net "FTDI_USB_R_N")
		)
	)
	(footprint "Vault:RESC1608X55X25LL10T15"
		(layer "B.Cu")
		(at 129.4216 88.8162)
		(property "Reference" "R10"
			(at -0.2286 -1.273069 0)
			(unlocked yes)
			(layer "B.SilkS")
			(effects
				(font
					(size 0.762 0.762)
					(thickness 0.2286)
				)
				(justify mirror)
			)
		)
		(property "Value" "4.7K"
			(at -2.630671 -2.57724 270)
			(unlocked yes)
			(layer "B.SilkS")
			(hide yes)
			(effects
				(font
					(size 0.762 0.762)
					(thickness 0.2286)
				)
				(justify mirror)
			)
		)
		(sheetname "06-MAC")
		(sheetfile "06-MAC.kicad_sch")
		(duplicate_pad_numbers_are_jumpers no)
		(pad "1" smd rect
			(at -0.65 0 270)
			(size 0.8 0.6)
			(layers "B.Cu" "B.Mask" "B.Paste")
			(net "GND")
		)
		(pad "2" smd rect
			(at 0.65 0 270)
			(size 0.8 0.6)
			(layers "B.Cu" "B.Mask" "B.Paste")
			(net "FPGA_MAC_PPS_IN1-")
		)
	)
	(footprint "Vault:RESC1608X55X30LL15T20"
		(layer "B.Cu")
		(at 181.90985 106.4162 90)
		(property "Reference" "R37"
			(at 2.1714 0.164521 90)
			(unlocked yes)
			(layer "B.SilkS")
			(effects
				(font
					(size 0.762 0.762)
					(thickness 0.2286)
				)
				(justify mirror)
			)
		)
		(property "Value" "10K"
			(at -2.630671 -1.76469 0)
			(unlocked yes)
			(layer "B.SilkS")
			(hide yes)
			(effects
				(font
					(size 0.762 0.762)
					(thickness 0.2286)
				)
				(justify mirror)
			)
		)
		(sheetname "05-GPS_IMU_SENSORS")
		(sheetfile "05-GPS_IMU_SENSORS.kicad_sch")
		(duplicate_pad_numbers_are_jumpers no)
		(pad "1" smd rect
			(at -0.575 0)
			(size 0.85 0.75)
			(layers "B.Cu" "B.Mask" "B.Paste")
			(net "EXT_EEPROM_WP")
		)
		(pad "2" smd rect
			(at 0.575 0)
			(size 0.85 0.75)
			(layers "B.Cu" "B.Mask" "B.Paste")
			(net "+3.3V")
		)
	)
	(footprint "Vault:RESC1608X55X30NL15T15"
		(layer "B.Cu")
		(at 79.4216 52.7162 180)
		(property "Reference" "R36"
			(at -2.9714 -0.126921 0)
			(unlocked yes)
			(layer "B.SilkS")
			(effects
				(font
					(size 0.762 0.762)
					(thickness 0.2286)
				)
				(justify mirror)
			)
		)
		(property "Value" "200 OHM"
			(at -2.935471 -4.78626 90)
			(unlocked yes)
			(layer "B.SilkS")
			(hide yes)
			(effects
				(font
					(size 0.762 0.762)
					(thickness 0.2286)
				)
				(justify mirror)
			)
		)
		(sheetname "02-USER_IO_STATUS")
		(sheetfile "02-USER_IO_STATUS.kicad_sch")
		(duplicate_pad_numbers_are_jumpers no)
		(pad "1" smd rect
			(at -0.675 0 90)
			(size 0.95 0.8)
			(layers "B.Cu" "B.Mask" "B.Paste")
			(net "LED2")
		)
		(pad "2" smd rect
			(at 0.675 0 90)
			(size 0.95 0.8)
			(layers "B.Cu" "B.Mask" "B.Paste")
			(net "NetD9_1")
		)
	)
	(footprint "Vault:FP-RG1005-IPC_A"
		(layer "B.Cu")
		(at 181.3216 88.8162 180)
		(property "Reference" "R63"
			(at 0.2286 1.573079 0)
			(unlocked yes)
			(layer "B.SilkS")
			(effects
				(font
					(size 0.762 0.762)
					(thickness 0.2286)
				)
				(justify mirror)
			)
		)
		(property "Value" "22_0.5%_0402"
			(at -2.884671 -8.036475 90)
			(unlocked yes)
			(layer "B.SilkS")
			(hide yes)
			(effects
				(font
					(size 0.762 0.762)
					(thickness 0.2286)
				)
				(justify mirror)
			)
		)
		(sheetname "03-POWER")
		(sheetfile "03-POWER.kicad_sch")
		(duplicate_pad_numbers_are_jumpers no)
		(fp_line
			(start 0.85792 0.73624)
			(end -0.85791 0.73624)
			(stroke
				(width 0.2)
				(type solid)
			)
			(layer "B.SilkS")
		)
		(fp_line
			(start 0.85792 -0.73624)
			(end -0.85791 -0.73624)
			(stroke
				(width 0.2)
				(type solid)
			)
			(layer "B.SilkS")
		)
		(fp_line
			(start 1.05792 0.53624)
			(end -1.05791 0.53624)
			(stroke
				(width 0.2)
				(type solid)
			)
			(layer "B.CrtYd")
		)
		(fp_line
			(start 1.05792 -0.53624)
			(end 1.05792 0.53624)
			(stroke
				(width 0.2)
				(type solid)
			)
			(layer "B.CrtYd")
		)
		(fp_line
			(start 1.05792 -0.53624)
			(end -1.05791 -0.53624)
			(stroke
				(width 0.2)
				(type solid)
			)
			(layer "B.CrtYd")
		)
		(fp_line
			(start -1.05791 -0.53624)
			(end -1.05791 0.53624)
			(stroke
				(width 0.2)
				(type solid)
			)
			(layer "B.CrtYd")
		)
		(fp_line
			(start 1.05792 0.53624)
			(end -1.05791 0.53624)
			(stroke
				(width 0.2)
				(type solid)
			)
			(layer "B.Fab")
		)
		(fp_line
			(start 1.05792 -0.53624)
			(end 1.05792 0.53624)
			(stroke
				(width 0.2)
				(type solid)
			)
			(layer "B.Fab")
		)
		(fp_line
			(start 1.05792 -0.53624)
			(end -1.05791 -0.53624)
			(stroke
				(width 0.2)
				(type solid)
			)
			(layer "B.Fab")
		)
		(fp_line
			(start 0.5 0)
			(end -0.5 0)
			(stroke
				(width 0.1)
				(type solid)
			)
			(layer "B.Fab")
		)
		(fp_line
			(start 0 -0.5)
			(end 0 0.5)
			(stroke
				(width 0.1)
				(type solid)
			)
			(layer "B.Fab")
		)
		(fp_line
			(start -1.05791 -0.53624)
			(end -1.05791 0.53624)
			(stroke
				(width 0.2)
				(type solid)
			)
			(layer "B.Fab")
		)
		(fp_text user "${REFERENCE}"
			(at -0.00001 -0.09602 360)
			(unlocked yes)
			(layer "B.Fab")
			(effects
				(font
					(face "Arial")
					(size 0.63 0.63)
					(thickness 0.1)
				)
				(justify left bottom mirror)
			)
		)
		(pad "1" smd rect
			(at -0.51351 0 180)
			(size 0.68881 0.67248)
			(layers "B.Cu" "B.Mask" "B.Paste")
			(net "GND")
			(solder_mask_margin 0)
			(solder_paste_margin 0)
		)
		(pad "2" smd rect
			(at 0.51351 0 180)
			(size 0.68881 0.67248)
			(layers "B.Cu" "B.Mask" "B.Paste")
			(net "NetR61_1")
			(solder_mask_margin 0)
			(solder_paste_margin 0)
		)
	)
	(footprint "Vault:CAPC1005X56X25NL10T15"
		(layer "B.Cu")
		(at 87.1116 69.33347 -90)
		(property "Reference" "C21"
			(at 0.78661 1.556325 270)
			(unlocked yes)
			(layer "B.SilkS")
			(effects
				(font
					(size 0.762 0.762)
					(thickness 0.2286)
				)
				(justify left bottom mirror)
			)
		)
		(property "Value" "0.1uF_25V_0402"
			(at -9.460165 23.8395 0)
			(unlocked yes)
			(layer "B.SilkS")
			(hide yes)
			(effects
				(font
					(size 0.762 0.762)
					(thickness 0.2286)
				)
				(justify left bottom mirror)
			)
		)
		(sheetname "03-POWER")
		(sheetfile "03-POWER.kicad_sch")
		(duplicate_pad_numbers_are_jumpers no)
		(pad "1" smd rect
			(at -0.44 0 180)
			(size 0.64 0.68)
			(layers "B.Cu" "B.Mask" "B.Paste")
			(net "GND")
		)
		(pad "2" smd rect
			(at 0.44 0 180)
			(size 0.64 0.68)
			(layers "B.Cu" "B.Mask" "B.Paste")
			(net "+3.3V")
		)
	)
	(footprint "Vault:CAPC1608X87X45ML20T05"
		(layer "B.Cu")
		(at 102.7491 67.15612)
		(property "Reference" "C54"
			(at 0.2011 1.333159 180)
			(unlocked yes)
			(layer "B.SilkS")
			(effects
				(font
					(size 0.762 0.762)
					(thickness 0.2286)
				)
				(justify mirror)
			)
		)
		(property "Value" "0.1uF"
			(at 2.069035 -2.630671 180)
			(unlocked yes)
			(layer "B.SilkS")
			(hide yes)
			(effects
				(font
					(size 0.762 0.762)
					(thickness 0.2286)
				)
				(justify mirror)
			)
		)
		(sheetname "05-GPS_IMU_SENSORS")
		(sheetfile "05-GPS_IMU_SENSORS.kicad_sch")
		(duplicate_pad_numbers_are_jumpers no)
		(pad "1" smd rect
			(at -0.7 0 270)
			(size 1.1 1.05)
			(layers "B.Cu" "B.Mask" "B.Paste")
			(net "GND")
		)
		(pad "2" smd rect
			(at 0.7 0 270)
			(size 1.1 1.05)
			(layers "B.Cu" "B.Mask" "B.Paste")
			(net "+5.0V")
		)
	)
	(footprint "Vault:CAPC1608X87X45ML20T05"
		(layer "B.Cu")
		(at 113.5216 66.7162 90)
		(property "Reference" "C43"
			(at 0.2286 1.473069 270)
			(unlocked yes)
			(layer "B.SilkS")
			(effects
				(font
					(size 0.762 0.762)
					(thickness 0.2286)
				)
				(justify mirror)
			)
		)
		(property "Value" "0.1uF"
			(at 2.069035 -2.630671 270)
			(unlocked yes)
			(layer "B.SilkS")
			(hide yes)
			(effects
				(font
					(size 0.762 0.762)
					(thickness 0.2286)
				)
				(justify mirror)
			)
		)
		(sheetname "05-GPS_IMU_SENSORS")
		(sheetfile "05-GPS_IMU_SENSORS.kicad_sch")
		(duplicate_pad_numbers_are_jumpers no)
		(pad "1" smd rect
			(at -0.7 0)
			(size 1.1 1.05)
			(layers "B.Cu" "B.Mask" "B.Paste")
			(net "GND")
		)
		(pad "2" smd rect
			(at 0.7 0)
			(size 1.1 1.05)
			(layers "B.Cu" "B.Mask" "B.Paste")
			(net "+3.3V")
		)
	)
	(footprint "Vault:FP-0402-L_1_0_1-W_0_5_0_1-IPC_C"
		(layer "B.Cu")
		(at 124.07407 74.1662 -90)
		(property "Reference" "C99"
			(at 2.5532 0.325539 90)
			(unlocked yes)
			(layer "B.SilkS")
			(effects
				(font
					(size 0.762 0.762)
					(thickness 0.2032)
				)
				(justify mirror)
			)
		)
		(property "Value" "0.1uF_25V_0402"
			(at -2.465551 -9.813805 180)
			(unlocked yes)
			(layer "B.SilkS")
			(hide yes)
			(effects
				(font
					(size 0.762 0.762)
					(thickness 0.2032)
				)
				(justify mirror)
			)
		)
		(sheetname "10-M2_GPS")
		(sheetfile "10-M2_GPS.kicad_sch")
		(duplicate_pad_numbers_are_jumpers no)
		(fp_line
			(start 0.65607 0.70001)
			(end -0.65607 0.70001)
			(stroke
				(width 0.2)
				(type solid)
			)
			(layer "B.SilkS")
		)
		(fp_line
			(start 0.65607 -0.7)
			(end -0.65607 -0.7)
			(stroke
				(width 0.2)
				(type solid)
			)
			(layer "B.SilkS")
		)
		(fp_line
			(start -0.75607 0.4)
			(end -0.75607 -0.39999)
			(stroke
				(width 0.2)
				(type solid)
			)
			(layer "B.CrtYd")
		)
		(fp_line
			(start 0.75607 0.4)
			(end -0.75607 0.4)
			(stroke
				(width 0.2)
				(type solid)
			)
			(layer "B.CrtYd")
		)
		(fp_line
			(start 0.75607 0.4)
			(end 0.75607 -0.39999)
			(stroke
				(width 0.2)
				(type solid)
			)
			(layer "B.CrtYd")
		)
		(fp_line
			(start 0.75607 -0.39999)
			(end -0.75607 -0.39999)
			(stroke
				(width 0.2)
				(type solid)
			)
			(layer "B.CrtYd")
		)
		(fp_line
			(start 0 0.5)
			(end 0 -0.49999)
			(stroke
				(width 0.1)
				(type solid)
			)
			(layer "B.Fab")
		)
		(fp_line
			(start -0.75607 0.4)
			(end -0.75607 -0.39999)
			(stroke
				(width 0.2)
				(type solid)
			)
			(layer "B.Fab")
		)
		(fp_line
			(start 0.75607 0.4)
			(end -0.75607 0.4)
			(stroke
				(width 0.2)
				(type solid)
			)
			(layer "B.Fab")
		)
		(fp_line
			(start 0.75607 0.4)
			(end 0.75607 -0.39999)
			(stroke
				(width 0.2)
				(type solid)
			)
			(layer "B.Fab")
		)
		(fp_line
			(start 0.5 0)
			(end -0.5 0)
			(stroke
				(width 0.1)
				(type solid)
			)
			(layer "B.Fab")
		)
		(fp_line
			(start 0.75607 -0.39999)
			(end -0.75607 -0.39999)
			(stroke
				(width 0.2)
				(type solid)
			)
			(layer "B.Fab")
		)
		(fp_text user "${REFERENCE}"
			(at -0.00001 -0.09601 90)
			(unlocked yes)
			(layer "B.Fab")
			(effects
				(font
					(face "Arial")
					(size 0.63 0.63)
					(thickness 0.1)
				)
				(justify left bottom mirror)
			)
		)
		(pad "1" smd rect
			(at -0.36554 0 270)
			(size 0.58106 0.51213)
			(layers "B.Cu" "B.Mask" "B.Paste")
			(net "+3.3V")
			(solder_mask_margin 0)
			(solder_paste_margin 0)
		)
		(pad "2" smd rect
			(at 0.36554 0 270)
			(size 0.58106 0.51213)
			(layers "B.Cu" "B.Mask" "B.Paste")
			(net "GND")
			(solder_mask_margin 0)
			(solder_paste_margin 0)
		)
	)
	(footprint "Vault:RESC1609X50X30NL10T20"
		(layer "B.Cu")
		(at 123.3216 88.3162)
		(property "Reference" "R12"
			(at -0.2286 -1.273079 0)
			(unlocked yes)
			(layer "B.SilkS")
			(effects
				(font
					(size 0.762 0.762)
					(thickness 0.2286)
				)
				(justify mirror)
			)
		)
		(property "Value" "110R"
			(at -2.884681 -2.24708 270)
			(unlocked yes)
			(layer "B.SilkS")
			(hide yes)
			(effects
				(font
					(size 0.762 0.762)
					(thickness 0.2286)
				)
				(justify mirror)
			)
		)
		(sheetname "06-MAC")
		(sheetfile "06-MAC.kicad_sch")
		(duplicate_pad_numbers_are_jumpers no)
		(pad "1" smd rect
			(at -0.625 0 270)
			(size 0.95 0.8)
			(layers "B.Cu" "B.Mask" "B.Paste")
			(net "MAC_PPS_OUT-")
		)
		(pad "2" smd rect
			(at 0.625 0 270)
			(size 0.95 0.8)
			(layers "B.Cu" "B.Mask" "B.Paste")
			(net "MAC_PPS_OUT+")
		)
	)
	(footprint "Vault:RESC1005X40X25NL10T10"
		(layer "B.Cu")
		(at 184.8216 94.3162)
		(property "Reference" "R185"
			(at 2.396998 -2.70424 270)
			(unlocked yes)
			(layer "B.SilkS")
			(effects
				(font
					(size 1.524 1.524)
					(thickness 0.254)
				)
				(justify mirror)
			)
		)
		(property "Value" "10K_1%_0402"
			(at -2.759202 -8.036515 270)
			(unlocked yes)
			(layer "B.SilkS")
			(hide yes)
			(effects
				(font
					(size 1.524 1.524)
					(thickness 0.254)
				)
				(justify mirror)
			)
		)
		(sheetname "03-POWER")
		(sheetfile "03-POWER.kicad_sch")
		(duplicate_pad_numbers_are_jumpers no)
		(pad "1" smd rect
			(at -0.425 0 270)
			(size 0.6 0.65)
			(layers "B.Cu" "B.Mask" "B.Paste")
			(net "GND")
		)
		(pad "2" smd rect
			(at 0.425 0 270)
			(size 0.6 0.65)
			(layers "B.Cu" "B.Mask" "B.Paste")
			(net "NetR129_2")
		)
	)
	(footprint "Vault:FP-C1005-050-0_05-IPC_A"
		(layer "B.Cu")
		(at 177.7216 86.7162 180)
		(property "Reference" "C5"
			(at -0.5 1.006655 0)
			(unlocked yes)
			(layer "B.SilkS")
			(effects
				(font
					(size 0.762 0.762)
					(thickness 0.2286)
				)
				(justify left bottom mirror)
			)
		)
		(property "Value" "2.2uF_16V_0402"
			(at 29.5119 -16.624845 0)
			(unlocked yes)
			(layer "B.SilkS")
			(hide yes)
			(effects
				(font
					(size 0.762 0.762)
					(thickness 0.2286)
				)
				(justify left bottom mirror)
			)
		)
		(sheetname "03-POWER")
		(sheetfile "03-POWER.kicad_sch")
		(duplicate_pad_numbers_are_jumpers no)
		(fp_line
			(start 0.83624 0.73624)
			(end -0.83624 0.73624)
			(stroke
				(width 0.2)
				(type solid)
			)
			(layer "B.SilkS")
		)
		(fp_line
			(start 0.83624 -0.73624)
			(end -0.83624 -0.73624)
			(stroke
				(width 0.2)
				(type solid)
			)
			(layer "B.SilkS")
		)
		(fp_line
			(start 1.03624 0.53624)
			(end -1.03624 0.53624)
			(stroke
				(width 0.2)
				(type solid)
			)
			(layer "B.CrtYd")
		)
		(fp_line
			(start 1.03624 -0.53624)
			(end 1.03624 0.53624)
			(stroke
				(width 0.2)
				(type solid)
			)
			(layer "B.CrtYd")
		)
		(fp_line
			(start 1.03624 -0.53624)
			(end -1.03624 -0.53624)
			(stroke
				(width 0.2)
				(type solid)
			)
			(layer "B.CrtYd")
		)
		(fp_line
			(start -1.03624 -0.53624)
			(end -1.03624 0.53624)
			(stroke
				(width 0.2)
				(type solid)
			)
			(layer "B.CrtYd")
		)
		(fp_line
			(start 1.03624 0.53624)
			(end -1.03624 0.53624)
			(stroke
				(width 0.2)
				(type solid)
			)
			(layer "B.Fab")
		)
		(fp_line
			(start 1.03624 -0.53624)
			(end 1.03624 0.53624)
			(stroke
				(width 0.2)
				(type solid)
			)
			(layer "B.Fab")
		)
		(fp_line
			(start 1.03624 -0.53624)
			(end -1.03624 -0.53624)
			(stroke
				(width 0.2)
				(type solid)
			)
			(layer "B.Fab")
		)
		(fp_line
			(start 0.5 0)
			(end -0.5 0)
			(stroke
				(width 0.1)
				(type solid)
			)
			(layer "B.Fab")
		)
		(fp_line
			(start 0 -0.5)
			(end 0 0.5)
			(stroke
				(width 0.1)
				(type solid)
			)
			(layer "B.Fab")
		)
		(fp_line
			(start -1.03624 -0.53624)
			(end -1.03624 0.53624)
			(stroke
				(width 0.2)
				(type solid)
			)
			(layer "B.Fab")
		)
		(fp_text user "${REFERENCE}"
			(at -0.00001 -0.09602 360)
			(unlocked yes)
			(layer "B.Fab")
			(effects
				(font
					(face "Arial")
					(size 0.63 0.63)
					(thickness 0.1)
				)
				(justify left bottom mirror)
			)
		)
		(pad "1" smd rect
			(at -0.46657 0 180)
			(size 0.73933 0.67248)
			(layers "B.Cu" "B.Mask" "B.Paste")
			(net "P3V3_MUN_VCC")
			(solder_mask_margin 0)
			(solder_paste_margin 0)
		)
		(pad "2" smd rect
			(at 0.46658 0 180)
			(size 0.73933 0.67248)
			(layers "B.Cu" "B.Mask" "B.Paste")
			(net "GND")
			(solder_mask_margin 0)
			(solder_paste_margin 0)
		)
	)
	(footprint "Vault:CAPC1608X87X45ML20T05"
		(layer "B.Cu")
		(at 213.9216 141.5162)
		(property "Reference" "C64"
			(at 0.2286 1.273069 180)
			(unlocked yes)
			(layer "B.SilkS")
			(effects
				(font
					(size 0.762 0.762)
					(thickness 0.2286)
				)
				(justify mirror)
			)
		)
		(property "Value" "0.1uF"
			(at 2.069035 -2.630671 180)
			(unlocked yes)
			(layer "B.SilkS")
			(hide yes)
			(effects
				(font
					(size 0.762 0.762)
					(thickness 0.2286)
				)
				(justify mirror)
			)
		)
		(sheetname "05-GPS_IMU_SENSORS")
		(sheetfile "05-GPS_IMU_SENSORS.kicad_sch")
		(duplicate_pad_numbers_are_jumpers no)
		(pad "1" smd rect
			(at -0.7 0 270)
			(size 1.1 1.05)
			(layers "B.Cu" "B.Mask" "B.Paste")
			(net "GND")
		)
		(pad "2" smd rect
			(at 0.7 0 270)
			(size 1.1 1.05)
			(layers "B.Cu" "B.Mask" "B.Paste")
			(net "GNSS2_P5V0")
		)
	)
	(gr_poly
		(pts
			(xy 196.05995 55.79733) (xy 196.05995 55.80552) (xy 196.05995 55.81372) (xy 196.05995 55.82191) (xy 196.05995 55.83011)
			(xy 196.05995 55.8383) (xy 196.05995 55.84649) (xy 196.05995 55.85469) (xy 196.05995 55.86288) (xy 196.05995 55.87108)
			(xy 196.05995 55.87927) (xy 196.05995 55.88747) (xy 196.05995 55.89566) (xy 196.05995 55.90386) (xy 196.05995 55.91205)
			(xy 196.05995 55.92024) (xy 196.05995 55.92844) (xy 196.05995 55.93663) (xy 196.05995 55.94483) (xy 196.05995 55.95302)
			(xy 196.05995 55.96122) (xy 196.05995 55.96941) (xy 196.05995 55.97761) (xy 196.05995 55.9858) (xy 196.05995 55.994)
			(xy 196.05995 56.00219) (xy 196.05995 56.01039) (xy 196.05995 56.01858) (xy 196.05995 56.02677) (xy 196.05995 56.03497)
			(xy 196.05995 56.04316) (xy 196.05995 56.05136) (xy 196.05995 56.05955) (xy 196.05995 56.06775) (xy 196.05995 56.07594)
			(xy 196.05995 56.08413) (xy 196.05995 56.09233) (xy 196.05995 56.10053) (xy 196.05995 56.10872) (xy 196.05995 56.11691)
			(xy 196.05995 56.12511) (xy 196.05995 56.1333) (xy 196.05995 56.1415) (xy 196.05995 56.14969) (xy 196.05995 56.15788)
			(xy 196.05995 56.16608) (xy 196.05995 56.17427) (xy 196.05995 56.18247) (xy 196.05995 56.19066) (xy 196.05995 56.19886)
			(xy 196.05995 56.20705) (xy 196.05995 56.21524) (xy 196.05995 56.22344) (xy 195.44537 56.22344) (xy 195.44537 56.21524)
			(xy 195.44537 56.20705) (xy 195.44537 56.19886) (xy 195.44537 56.19066) (xy 195.44537 56.18247) (xy 195.44537 56.17427)
			(xy 195.44537 56.16608) (xy 195.44537 56.15788) (xy 195.44537 56.14969) (xy 195.44537 56.1415) (xy 195.44537 56.1333)
			(xy 195.44537 56.12511) (xy 195.44537 56.11691) (xy 195.44537 56.10872) (xy 195.44537 56.10053) (xy 195.44537 56.09233)
			(xy 195.44537 56.08413) (xy 195.44537 56.07594) (xy 195.44537 56.06775) (xy 195.44537 56.05955) (xy 195.44537 56.05136)
			(xy 195.44537 56.04316) (xy 195.44537 56.03497) (xy 195.44537 56.02677) (xy 195.44537 56.01858) (xy 195.44537 56.01039)
			(xy 195.44537 56.00219) (xy 195.44537 55.994) (xy 195.44537 55.9858) (xy 195.44537 55.97761) (xy 195.44537 55.96941)
			(xy 195.44537 55.96122) (xy 195.44537 55.95302) (xy 195.44537 55.94483) (xy 195.44537 55.93663) (xy 195.44537 55.92844)
			(xy 195.44537 55.92024) (xy 195.44537 55.91205) (xy 195.44537 55.90386) (xy 195.44537 55.89566) (xy 195.44537 55.88747)
			(xy 195.44537 55.87927) (xy 195.44537 55.87108) (xy 195.44537 55.86288) (xy 195.44537 55.85469) (xy 195.44537 55.84649)
			(xy 195.44537 55.8383) (xy 195.44537 55.83011) (xy 195.44537 55.82191) (xy 195.44537 55.81372) (xy 195.44537 55.80552)
			(xy 195.44537 55.79733) (xy 195.44537 55.78913) (xy 196.05995 55.78913)
		)
		(stroke
			(width 0)
			(type default)
		)
		(fill yes)
		(layer "F.Cu")
	)
	(gr_poly
		(pts
			(xy 189.4388 58.19831) (xy 189.47158 58.19831) (xy 189.47158 58.20651) (xy 189.48797 58.20651) (xy 189.48797 58.2147)
			(xy 189.50436 58.2147) (xy 189.50436 58.2229) (xy 189.52075 58.2229) (xy 189.52075 58.23109) (xy 189.53714 58.23109)
			(xy 189.53714 58.23929) (xy 189.54533 58.23929) (xy 189.54533 58.24748) (xy 189.56172 58.24748) (xy 189.56172 58.25568)
			(xy 189.56992 58.25568) (xy 189.56992 58.26387) (xy 189.57811 58.26387) (xy 189.57811 58.27207) (xy 189.5863 58.27207)
			(xy 189.5863 58.28026) (xy 189.5945 58.28026) (xy 189.5945 58.28845) (xy 189.6027 58.28845) (xy 189.6027 58.29665)
			(xy 189.61089 58.29665) (xy 189.61089 58.30484) (xy 189.61908 58.30484) (xy 189.61908 58.31304) (xy 189.61908 58.32123)
			(xy 189.62728 58.32123) (xy 189.62728 58.32942) (xy 189.63547 58.32942) (xy 189.63547 58.33762) (xy 189.63547 58.34582)
			(xy 189.64367 58.34582) (xy 189.64367 58.35401) (xy 189.64367 58.36221) (xy 189.65186 58.36221) (xy 189.65186 58.3704)
			(xy 189.65186 58.37859) (xy 189.66005 58.37859) (xy 189.66005 58.38679) (xy 189.66005 58.39498) (xy 189.66005 58.40318)
			(xy 189.66825 58.40318) (xy 189.66825 58.41137) (xy 189.66825 58.41957) (xy 189.66825 58.42776) (xy 189.66825 58.43595)
			(xy 189.66825 58.44415) (xy 189.67644 58.44415) (xy 189.67644 58.45234) (xy 189.67644 58.46054) (xy 189.67644 58.46874)
			(xy 189.67644 58.47693) (xy 189.67644 58.48512) (xy 189.67644 58.49332) (xy 189.67644 58.50151) (xy 189.67644 58.50971)
			(xy 189.67644 58.5179) (xy 189.67644 58.52609) (xy 189.67644 58.53429) (xy 189.67644 58.54248) (xy 189.66825 58.54248)
			(xy 189.66825 58.55068) (xy 189.66825 58.55887) (xy 189.66825 58.56707) (xy 189.66825 58.57526) (xy 189.66825 58.58345)
			(xy 189.66005 58.58345) (xy 189.66005 58.59165) (xy 189.66005 58.59985) (xy 189.66005 58.60804) (xy 189.65186 58.60804)
			(xy 189.65186 58.61623) (xy 189.65186 58.62443) (xy 189.64367 58.62443) (xy 189.64367 58.63262) (xy 189.64367 58.64082)
			(xy 189.63547 58.64082) (xy 189.63547 58.64901) (xy 189.63547 58.65721) (xy 189.62728 58.65721) (xy 189.62728 58.6654)
			(xy 189.61908 58.6654) (xy 189.61908 58.67359) (xy 189.61908 58.68179) (xy 189.61089 58.68179) (xy 189.61089 58.68998)
			(xy 189.6027 58.68998) (xy 189.6027 58.69818) (xy 189.5945 58.69818) (xy 189.5945 58.70637) (xy 189.5863 58.70637)
			(xy 189.5863 58.71457) (xy 189.57811 58.71457) (xy 189.57811 58.72276) (xy 189.56992 58.72276) (xy 189.56992 58.73096)
			(xy 189.56172 58.73096) (xy 189.56172 58.73915) (xy 189.54533 58.73915) (xy 189.54533 58.74735) (xy 189.53714 58.74735)
			(xy 189.53714 58.75554) (xy 189.52075 58.75554) (xy 189.52075 58.76374) (xy 189.50436 58.76374) (xy 189.50436 58.77193)
			(xy 189.48797 58.77193) (xy 189.48797 58.78012) (xy 189.46339 58.78012) (xy 189.46339 58.78832) (xy 189.4388 58.78832)
			(xy 189.4388 58.79651) (xy 189.2995 58.79651) (xy 189.2995 58.78832) (xy 189.27491 58.78832) (xy 189.27491 58.78012)
			(xy 189.25033 58.78012) (xy 189.25033 58.77193) (xy 189.23394 58.77193) (xy 189.23394 58.76374) (xy 189.21755 58.76374)
			(xy 189.21755 58.75554) (xy 189.20116 58.75554) (xy 189.20116 58.74735) (xy 189.19297 58.74735) (xy 189.19297 58.73915)
			(xy 189.18478 58.73915) (xy 189.18478 58.73096) (xy 189.16838 58.73096) (xy 189.16838 58.72276) (xy 189.16019 58.72276)
			(xy 189.16019 58.71457) (xy 189.152 58.71457) (xy 189.152 58.70637) (xy 189.1438 58.70637) (xy 189.1438 58.69818)
			(xy 189.13561 58.69818) (xy 189.13561 58.68998) (xy 189.12741 58.68998) (xy 189.12741 58.68179) (xy 189.12741 58.67359)
			(xy 189.11922 58.67359) (xy 189.11922 58.6654) (xy 189.11102 58.6654) (xy 189.11102 58.65721) (xy 189.11102 58.64901)
			(xy 189.10283 58.64901) (xy 189.10283 58.64082) (xy 189.10283 58.63262) (xy 189.09463 58.63262) (xy 189.09463 58.62443)
			(xy 189.09463 58.61623) (xy 189.08644 58.61623) (xy 189.08644 58.60804) (xy 189.08644 58.59985) (xy 189.07825 58.59985)
			(xy 189.07825 58.59165) (xy 189.07825 58.58345) (xy 189.07825 58.57526) (xy 189.07005 58.57526) (xy 189.07005 58.56707)
			(xy 189.07005 58.55887) (xy 189.07005 58.55068) (xy 189.07005 58.54248) (xy 189.07005 58.53429) (xy 189.06186 58.53429)
			(xy 189.06186 58.52609) (xy 189.06186 58.5179) (xy 189.06186 58.50971) (xy 189.06186 58.50151) (xy 189.06186 58.49332)
			(xy 189.06186 58.48512) (xy 189.06186 58.47693) (xy 189.06186 58.46874) (xy 189.06186 58.46054) (xy 189.06186 58.45234)
			(xy 189.07005 58.45234) (xy 189.07005 58.44415) (xy 189.07005 58.43595) (xy 189.07005 58.42776) (xy 189.07005 58.41957)
			(xy 189.07005 58.41137) (xy 189.07825 58.41137) (xy 189.07825 58.40318) (xy 189.07825 58.39498) (xy 189.07825 58.38679)
			(xy 189.08644 58.38679) (xy 189.08644 58.37859) (xy 189.08644 58.3704) (xy 189.09463 58.3704) (xy 189.09463 58.36221)
			(xy 189.09463 58.35401) (xy 189.10283 58.35401) (xy 189.10283 58.34582) (xy 189.10283 58.33762) (xy 189.11102 58.33762)
			(xy 189.11102 58.32942) (xy 189.11102 58.32123) (xy 189.11922 58.32123) (xy 189.11922 58.31304) (xy 189.12741 58.31304)
			(xy 189.12741 58.30484) (xy 189.12741 58.29665) (xy 189.13561 58.29665) (xy 189.13561 58.28845) (xy 189.1438 58.28845)
			(xy 189.1438 58.28026) (xy 189.152 58.28026) (xy 189.152 58.27207) (xy 189.16019 58.27207) (xy 189.16019 58.26387)
			(xy 189.16838 58.26387) (xy 189.16838 58.25568) (xy 189.17658 58.25568) (xy 189.17658 58.24748) (xy 189.19297 58.24748)
			(xy 189.19297 58.23929) (xy 189.20116 58.23929) (xy 189.20116 58.23109) (xy 189.21755 58.23109) (xy 189.21755 58.2229)
			(xy 189.23394 58.2229) (xy 189.23394 58.2147) (xy 189.25033 58.2147) (xy 189.25033 58.20651) (xy 189.27491 58.20651)
			(xy 189.27491 58.19831) (xy 189.2995 58.19831) (xy 189.2995 58.19012) (xy 189.4388 58.19012)
		)
		(stroke
			(width 0)
			(type default)
		)
		(fill yes)
		(layer "F.Cu")
	)
	(gr_poly
		(pts
			(xy 197.78899 55.81372) (xy 197.80538 55.81372) (xy 197.80538 55.82191) (xy 197.80538 55.83011) (xy 197.80538 55.8383)
			(xy 197.80538 55.84649) (xy 197.80538 55.85469) (xy 197.80538 55.86288) (xy 197.80538 55.87108) (xy 197.80538 55.87927)
			(xy 197.80538 55.88747) (xy 197.80538 55.89566) (xy 197.80538 55.90386) (xy 197.80538 55.91205) (xy 197.80538 55.92024)
			(xy 197.80538 55.92844) (xy 197.80538 55.93663) (xy 197.80538 55.94483) (xy 197.80538 55.95302) (xy 197.80538 55.96122)
			(xy 197.80538 55.96941) (xy 197.80538 55.97761) (xy 197.80538 55.9858) (xy 197.80538 55.994) (xy 197.80538 56.00219)
			(xy 197.80538 56.01039) (xy 197.80538 56.01858) (xy 197.80538 56.02677) (xy 197.80538 56.03497) (xy 197.80538 56.04316)
			(xy 197.80538 56.05136) (xy 197.80538 56.05955) (xy 197.80538 56.06775) (xy 197.80538 56.07594) (xy 197.80538 56.08413)
			(xy 197.80538 56.09233) (xy 197.80538 56.10053) (xy 197.80538 56.10872) (xy 197.80538 56.11691) (xy 197.80538 56.12511)
			(xy 197.80538 56.1333) (xy 197.80538 56.1415) (xy 197.80538 56.14969) (xy 197.80538 56.15788) (xy 197.80538 56.16608)
			(xy 197.80538 56.17427) (xy 197.80538 56.18247) (xy 197.80538 56.19066) (xy 197.80538 56.19886) (xy 197.80538 56.20705)
			(xy 197.80538 56.21524) (xy 197.80538 56.22344) (xy 197.80538 56.23164) (xy 197.80538 56.23983) (xy 197.80538 56.24803)
			(xy 197.80538 56.25622) (xy 197.80538 56.26441) (xy 197.80538 56.27261) (xy 197.80538 56.2808) (xy 197.80538 56.289)
			(xy 197.80538 56.29719) (xy 197.80538 56.30539) (xy 197.80538 56.31358) (xy 197.80538 56.32177) (xy 197.80538 56.32997)
			(xy 197.80538 56.33816) (xy 197.80538 56.34636) (xy 197.80538 56.35455) (xy 197.80538 56.36275) (xy 197.80538 56.37094)
			(xy 197.80538 56.37914) (xy 197.80538 56.38733) (xy 197.80538 56.39553) (xy 197.80538 56.40372) (xy 197.80538 56.41191)
			(xy 197.80538 56.42011) (xy 197.80538 56.42831) (xy 197.80538 56.4365) (xy 197.80538 56.44469) (xy 197.80538 56.45289)
			(xy 197.80538 56.46108) (xy 197.80538 56.46928) (xy 197.80538 56.47747) (xy 197.80538 56.48567) (xy 197.80538 56.49386)
			(xy 197.80538 56.50205) (xy 197.80538 56.51025) (xy 197.80538 56.51844) (xy 197.80538 56.52664) (xy 197.80538 56.53483)
			(xy 197.80538 56.54303) (xy 197.80538 56.55122) (xy 197.80538 56.55942) (xy 197.80538 56.56761) (xy 197.80538 56.5758)
			(xy 197.80538 56.584) (xy 197.80538 56.59219) (xy 197.80538 56.60039) (xy 197.80538 56.60858) (xy 197.80538 56.61678)
			(xy 197.80538 56.62497) (xy 197.80538 56.63317) (xy 197.80538 56.64136) (xy 197.80538 56.64955) (xy 197.80538 56.65775)
			(xy 197.80538 56.66594) (xy 197.80538 56.67414) (xy 197.80538 56.68233) (xy 197.80538 56.69053) (xy 197.80538 56.69872)
			(xy 197.80538 56.70692) (xy 197.80538 56.71511) (xy 197.80538 56.72331) (xy 197.20719 56.72331) (xy 197.20719 56.71511)
			(xy 197.20719 56.70692) (xy 197.20719 56.69872) (xy 197.20719 56.69053) (xy 197.20719 56.68233) (xy 197.20719 56.67414)
			(xy 197.20719 56.66594) (xy 197.20719 56.65775) (xy 197.20719 56.64955) (xy 197.20719 56.64136) (xy 197.20719 56.63317)
			(xy 197.20719 56.62497) (xy 197.20719 56.61678) (xy 197.20719 56.60858) (xy 197.20719 56.60039) (xy 197.20719 56.59219)
			(xy 197.20719 56.584) (xy 197.20719 56.5758) (xy 197.20719 56.56761) (xy 197.20719 56.55942) (xy 197.20719 56.55122)
			(xy 197.20719 56.54303) (xy 197.20719 56.53483) (xy 197.20719 56.52664) (xy 197.20719 56.51844) (xy 197.20719 56.51025)
			(xy 197.20719 56.50205) (xy 197.20719 56.49386) (xy 197.20719 56.48567) (xy 197.20719 56.47747) (xy 197.20719 56.46928)
			(xy 197.20719 56.46108) (xy 197.20719 56.45289) (xy 197.20719 56.44469) (xy 197.20719 56.4365) (xy 197.20719 56.42831)
			(xy 197.20719 56.42011) (xy 197.20719 56.41191) (xy 197.20719 56.40372) (xy 197.20719 56.39553) (xy 197.20719 56.38733)
			(xy 197.20719 56.37914) (xy 197.20719 56.37094) (xy 197.20719 56.36275) (xy 197.20719 56.35455) (xy 197.20719 56.34636)
			(xy 197.20719 56.33816) (xy 197.20719 56.32997) (xy 197.20719 56.32177) (xy 197.20719 56.31358) (xy 197.20719 56.30539)
			(xy 197.20719 56.29719) (xy 197.20719 56.289) (xy 197.20719 56.2808) (xy 197.20719 56.27261) (xy 197.20719 56.26441)
			(xy 197.20719 56.25622) (xy 197.20719 56.24803) (xy 197.20719 56.23983) (xy 197.20719 56.23164) (xy 197.20719 56.22344)
			(xy 197.20719 56.21524) (xy 197.20719 56.20705) (xy 197.20719 56.19886) (xy 197.20719 56.19066) (xy 197.20719 56.18247)
			(xy 197.20719 56.17427) (xy 197.20719 56.16608) (xy 197.20719 56.15788) (xy 197.20719 56.14969) (xy 197.20719 56.1415)
			(xy 197.20719 56.1333) (xy 197.20719 56.12511) (xy 197.20719 56.11691) (xy 197.20719 56.10872) (xy 197.20719 56.10053)
			(xy 197.20719 56.09233) (xy 197.20719 56.08413) (xy 197.20719 56.07594) (xy 197.20719 56.06775) (xy 197.20719 56.05955)
			(xy 197.20719 56.05136) (xy 197.20719 56.04316) (xy 197.20719 56.03497) (xy 197.20719 56.02677) (xy 197.20719 56.01858)
			(xy 197.20719 56.01039) (xy 197.20719 56.00219) (xy 197.20719 55.994) (xy 197.20719 55.9858) (xy 197.20719 55.97761)
			(xy 197.20719 55.96941) (xy 197.20719 55.96122) (xy 197.20719 55.95302) (xy 197.20719 55.94483) (xy 197.20719 55.93663)
			(xy 197.20719 55.92844) (xy 197.20719 55.92024) (xy 197.20719 55.91205) (xy 197.20719 55.90386) (xy 197.20719 55.89566)
			(xy 197.20719 55.88747) (xy 197.20719 55.87927) (xy 197.20719 55.87108) (xy 197.20719 55.86288) (xy 197.20719 55.85469)
			(xy 197.20719 55.84649) (xy 197.20719 55.8383) (xy 197.20719 55.83011) (xy 197.20719 55.82191) (xy 197.20719 55.81372)
			(xy 197.21538 55.81372) (xy 197.21538 55.80552) (xy 197.22357 55.80552) (xy 197.22357 55.81372) (xy 197.75621 55.81372)
			(xy 197.75621 55.80552) (xy 197.76441 55.80552) (xy 197.76441 55.81372) (xy 197.7808 55.81372) (xy 197.7808 55.80552)
			(xy 197.78899 55.80552)
		)
		(stroke
			(width 0)
			(type default)
		)
		(fill yes)
		(layer "F.Cu")
	)
	(gr_poly
		(pts
			(xy 189.40603 57.08386) (xy 189.447 57.08386) (xy 189.447 57.09206) (xy 189.47158 57.09206) (xy 189.47158 57.10025)
			(xy 189.49617 57.10025) (xy 189.49617 57.10845) (xy 189.51255 57.10845) (xy 189.51255 57.11664) (xy 189.52894 57.11664)
			(xy 189.52894 57.12484) (xy 189.53714 57.12484) (xy 189.53714 57.13303) (xy 189.55353 57.13303) (xy 189.55353 57.14122)
			(xy 189.56172 57.14122) (xy 189.56172 57.14942) (xy 189.56992 57.14942) (xy 189.56992 57.15761) (xy 189.57811 57.15761)
			(xy 189.57811 57.16581) (xy 189.5863 57.16581) (xy 189.5863 57.174) (xy 189.5945 57.174) (xy 189.5945 57.18219)
			(xy 189.6027 57.18219) (xy 189.6027 57.19039) (xy 189.61089 57.19039) (xy 189.61089 57.19859) (xy 189.61908 57.19859)
			(xy 189.61908 57.20678) (xy 189.61908 57.21498) (xy 189.62728 57.21498) (xy 189.62728 57.22317) (xy 189.63547 57.22317)
			(xy 189.63547 57.23136) (xy 189.63547 57.23956) (xy 189.64367 57.23956) (xy 189.64367 57.24775) (xy 189.64367 57.25595)
			(xy 189.65186 57.25595) (xy 189.65186 57.26414) (xy 189.65186 57.27234) (xy 189.66005 57.27234) (xy 189.66005 57.28053)
			(xy 189.66005 57.28872) (xy 189.66005 57.29692) (xy 189.66825 57.29692) (xy 189.66825 57.30511) (xy 189.66825 57.31331)
			(xy 189.66825 57.3215) (xy 189.66825 57.3297) (xy 189.67644 57.3297) (xy 189.67644 57.33789) (xy 189.67644 57.34609)
			(xy 189.67644 57.35428) (xy 189.67644 57.36248) (xy 189.67644 57.37067) (xy 189.67644 57.37886) (xy 189.67644 57.38706)
			(xy 189.67644 57.39526) (xy 189.67644 57.40345) (xy 189.67644 57.41164) (xy 189.67644 57.41984) (xy 189.67644 57.42803)
			(xy 189.67644 57.43623) (xy 189.66825 57.43623) (xy 189.66825 57.44442) (xy 189.66825 57.45262) (xy 189.66825 57.46081)
			(xy 189.66825 57.469) (xy 189.66005 57.469) (xy 189.66005 57.4772) (xy 189.66005 57.48539) (xy 189.66005 57.49359)
			(xy 189.65186 57.49359) (xy 189.65186 57.50178) (xy 189.65186 57.50998) (xy 189.65186 57.51817) (xy 189.64367 57.51817)
			(xy 189.64367 57.52637) (xy 189.64367 57.53456) (xy 189.63547 57.53456) (xy 189.63547 57.54276) (xy 189.62728 57.54276)
			(xy 189.62728 57.55095) (xy 189.62728 57.55914) (xy 189.61908 57.55914) (xy 189.61908 57.56734) (xy 189.61089 57.56734)
			(xy 189.61089 57.57553) (xy 189.61089 57.58373) (xy 189.6027 57.58373) (xy 189.6027 57.59192) (xy 189.5945 57.59192)
			(xy 189.5945 57.60011) (xy 189.5863 57.60011) (xy 189.5863 57.60831) (xy 189.57811 57.60831) (xy 189.57811 57.61651)
			(xy 189.56992 57.61651) (xy 189.56992 57.6247) (xy 189.55353 57.6247) (xy 189.55353 57.63289) (xy 189.54533 57.63289)
			(xy 189.54533 57.64109) (xy 189.52894 57.64109) (xy 189.52894 57.64928) (xy 189.52075 57.64928) (xy 189.52075 57.65748)
			(xy 189.50436 57.65748) (xy 189.50436 57.66567) (xy 189.47978 57.66567) (xy 189.47978 57.67387) (xy 189.46339 57.67387)
			(xy 189.46339 57.68206) (xy 189.43061 57.68206) (xy 189.43061 57.69026) (xy 189.30769 57.69026) (xy 189.30769 57.68206)
			(xy 189.28311 57.68206) (xy 189.28311 57.67387) (xy 189.25853 57.67387) (xy 189.25853 57.66567) (xy 189.23394 57.66567)
			(xy 189.23394 57.65748) (xy 189.22575 57.65748) (xy 189.22575 57.64928) (xy 189.20936 57.64928) (xy 189.20936 57.64109)
			(xy 189.19297 57.64109) (xy 189.19297 57.63289) (xy 189.18478 57.63289) (xy 189.18478 57.6247) (xy 189.17658 57.6247)
			(xy 189.17658 57.61651) (xy 189.16019 57.61651) (xy 189.16019 57.60831) (xy 189.152 57.60831) (xy 189.152 57.60011)
			(xy 189.1438 57.60011) (xy 189.1438 57.59192) (xy 189.13561 57.59192) (xy 189.13561 57.58373) (xy 189.13561 57.57553)
			(xy 189.12741 57.57553) (xy 189.12741 57.56734) (xy 189.11922 57.56734) (xy 189.11922 57.55914) (xy 189.11102 57.55914)
			(xy 189.11102 57.55095) (xy 189.11102 57.54276) (xy 189.10283 57.54276) (xy 189.10283 57.53456) (xy 189.10283 57.52637)
			(xy 189.09463 57.52637) (xy 189.09463 57.51817) (xy 189.09463 57.50998) (xy 189.08644 57.50998) (xy 189.08644 57.50178)
			(xy 189.08644 57.49359) (xy 189.07825 57.49359) (xy 189.07825 57.48539) (xy 189.07825 57.4772) (xy 189.07825 57.469)
			(xy 189.07005 57.469) (xy 189.07005 57.46081) (xy 189.07005 57.45262) (xy 189.07005 57.44442) (xy 189.07005 57.43623)
			(xy 189.07005 57.42803) (xy 189.06186 57.42803) (xy 189.06186 57.41984) (xy 189.06186 57.41164) (xy 189.06186 57.40345)
			(xy 189.06186 57.39526) (xy 189.06186 57.38706) (xy 189.06186 57.37886) (xy 189.06186 57.37067) (xy 189.06186 57.36248)
			(xy 189.06186 57.35428) (xy 189.06186 57.34609) (xy 189.07005 57.34609) (xy 189.07005 57.33789) (xy 189.07005 57.3297)
			(xy 189.07005 57.3215) (xy 189.07005 57.31331) (xy 189.07005 57.30511) (xy 189.07825 57.30511) (xy 189.07825 57.29692)
			(xy 189.07825 57.28872) (xy 189.07825 57.28053) (xy 189.08644 57.28053) (xy 189.08644 57.27234) (xy 189.08644 57.26414)
			(xy 189.08644 57.25595) (xy 189.09463 57.25595) (xy 189.09463 57.24775) (xy 189.09463 57.23956) (xy 189.10283 57.23956)
			(xy 189.10283 57.23136) (xy 189.10283 57.22317) (xy 189.11102 57.22317) (xy 189.11102 57.21498) (xy 189.11922 57.21498)
			(xy 189.11922 57.20678) (xy 189.11922 57.19859) (xy 189.12741 57.19859) (xy 189.12741 57.19039) (xy 189.13561 57.19039)
			(xy 189.13561 57.18219) (xy 189.1438 57.18219) (xy 189.1438 57.174) (xy 189.152 57.174) (xy 189.152 57.16581)
			(xy 189.16019 57.16581) (xy 189.16019 57.15761) (xy 189.16838 57.15761) (xy 189.16838 57.14942) (xy 189.17658 57.14942)
			(xy 189.17658 57.14122) (xy 189.18478 57.14122) (xy 189.18478 57.13303) (xy 189.20116 57.13303) (xy 189.20116 57.12484)
			(xy 189.21755 57.12484) (xy 189.21755 57.11664) (xy 189.22575 57.11664) (xy 189.22575 57.10845) (xy 189.24213 57.10845)
			(xy 189.24213 57.10025) (xy 189.26672 57.10025) (xy 189.26672 57.09206) (xy 189.2913 57.09206) (xy 189.2913 57.08386)
			(xy 189.33228 57.08386) (xy 189.33228 57.07567) (xy 189.40603 57.07567)
		)
		(stroke
			(width 0)
			(type default)
		)
		(fill yes)
		(layer "F.Cu")
	)
	(gr_poly
		(pts
			(xy 189.42242 55.97761) (xy 189.45519 55.97761) (xy 189.45519 55.9858) (xy 189.47978 55.9858) (xy 189.47978 55.994)
			(xy 189.49617 55.994) (xy 189.49617 56.00219) (xy 189.51255 56.00219) (xy 189.51255 56.01039) (xy 189.52894 56.01039)
			(xy 189.52894 56.01858) (xy 189.54533 56.01858) (xy 189.54533 56.02677) (xy 189.55353 56.02677) (xy 189.55353 56.03497)
			(xy 189.56172 56.03497) (xy 189.56172 56.04316) (xy 189.57811 56.04316) (xy 189.57811 56.05136) (xy 189.5863 56.05136)
			(xy 189.5863 56.05955) (xy 189.5945 56.05955) (xy 189.5945 56.06775) (xy 189.6027 56.06775) (xy 189.6027 56.07594)
			(xy 189.6027 56.08413) (xy 189.61089 56.08413) (xy 189.61089 56.09233) (xy 189.61908 56.09233) (xy 189.61908 56.10053)
			(xy 189.62728 56.10053) (xy 189.62728 56.10872) (xy 189.62728 56.11691) (xy 189.63547 56.11691) (xy 189.63547 56.12511)
			(xy 189.63547 56.1333) (xy 189.64367 56.1333) (xy 189.64367 56.1415) (xy 189.64367 56.14969) (xy 189.65186 56.14969)
			(xy 189.65186 56.15788) (xy 189.65186 56.16608) (xy 189.66005 56.16608) (xy 189.66005 56.17427) (xy 189.66005 56.18247)
			(xy 189.66005 56.19066) (xy 189.66825 56.19066) (xy 189.66825 56.19886) (xy 189.66825 56.20705) (xy 189.66825 56.21524)
			(xy 189.66825 56.22344) (xy 189.67644 56.22344) (xy 189.67644 56.23164) (xy 189.67644 56.23983) (xy 189.67644 56.24803)
			(xy 189.67644 56.25622) (xy 189.67644 56.26441) (xy 189.67644 56.27261) (xy 189.67644 56.2808) (xy 189.67644 56.289)
			(xy 189.67644 56.29719) (xy 189.67644 56.30539) (xy 189.67644 56.31358) (xy 189.67644 56.32177) (xy 189.67644 56.32997)
			(xy 189.66825 56.32997) (xy 189.66825 56.33816) (xy 189.66825 56.34636) (xy 189.66825 56.35455) (xy 189.66825 56.36275)
			(xy 189.66005 56.36275) (xy 189.66005 56.37094) (xy 189.66005 56.37914) (xy 189.66005 56.38733) (xy 189.65186 56.38733)
			(xy 189.65186 56.39553) (xy 189.65186 56.40372) (xy 189.64367 56.40372) (xy 189.64367 56.41191) (xy 189.64367 56.42011)
			(xy 189.63547 56.42011) (xy 189.63547 56.42831) (xy 189.63547 56.4365) (xy 189.62728 56.4365) (xy 189.62728 56.44469)
			(xy 189.62728 56.45289) (xy 189.61908 56.45289) (xy 189.61908 56.46108) (xy 189.61089 56.46108) (xy 189.61089 56.46928)
			(xy 189.6027 56.46928) (xy 189.6027 56.47747) (xy 189.6027 56.48567) (xy 189.5945 56.48567) (xy 189.5945 56.49386)
			(xy 189.5863 56.49386) (xy 189.5863 56.50205) (xy 189.56992 56.50205) (xy 189.56992 56.51025) (xy 189.56172 56.51025)
			(xy 189.56172 56.51844) (xy 189.55353 56.51844) (xy 189.55353 56.52664) (xy 189.54533 56.52664) (xy 189.54533 56.53483)
			(xy 189.52894 56.53483) (xy 189.52894 56.54303) (xy 189.51255 56.54303) (xy 189.51255 56.55122) (xy 189.49617 56.55122)
			(xy 189.49617 56.55942) (xy 189.47978 56.55942) (xy 189.47978 56.56761) (xy 189.45519 56.56761) (xy 189.45519 56.5758)
			(xy 189.41422 56.5758) (xy 189.41422 56.584) (xy 189.32408 56.584) (xy 189.32408 56.5758) (xy 189.28311 56.5758)
			(xy 189.28311 56.56761) (xy 189.25853 56.56761) (xy 189.25853 56.55942) (xy 189.24213 56.55942) (xy 189.24213 56.55122)
			(xy 189.22575 56.55122) (xy 189.22575 56.54303) (xy 189.20936 56.54303) (xy 189.20936 56.53483) (xy 189.20116 56.53483)
			(xy 189.20116 56.52664) (xy 189.18478 56.52664) (xy 189.18478 56.51844) (xy 189.17658 56.51844) (xy 189.17658 56.51025)
			(xy 189.16838 56.51025) (xy 189.16838 56.50205) (xy 189.16019 56.50205) (xy 189.16019 56.49386) (xy 189.152 56.49386)
			(xy 189.152 56.48567) (xy 189.1438 56.48567) (xy 189.1438 56.47747) (xy 189.13561 56.47747) (xy 189.13561 56.46928)
			(xy 189.12741 56.46928) (xy 189.12741 56.46108) (xy 189.11922 56.46108) (xy 189.11922 56.45289) (xy 189.11922 56.44469)
			(xy 189.11102 56.44469) (xy 189.11102 56.4365) (xy 189.10283 56.4365) (xy 189.10283 56.42831) (xy 189.10283 56.42011)
			(xy 189.09463 56.42011) (xy 189.09463 56.41191) (xy 189.09463 56.40372) (xy 189.08644 56.40372) (xy 189.08644 56.39553)
			(xy 189.08644 56.38733) (xy 189.08644 56.37914) (xy 189.07825 56.37914) (xy 189.07825 56.37094) (xy 189.07825 56.36275)
			(xy 189.07825 56.35455) (xy 189.07005 56.35455) (xy 189.07005 56.34636) (xy 189.07005 56.33816) (xy 189.07005 56.32997)
			(xy 189.07005 56.32177) (xy 189.06186 56.32177) (xy 189.06186 56.31358) (xy 189.06186 56.30539) (xy 189.06186 56.29719)
			(xy 189.06186 56.289) (xy 189.06186 56.2808) (xy 189.06186 56.27261) (xy 189.06186 56.26441) (xy 189.06186 56.25622)
			(xy 189.06186 56.24803) (xy 189.06186 56.23983) (xy 189.06186 56.23164) (xy 189.07005 56.23164) (xy 189.07005 56.22344)
			(xy 189.07005 56.21524) (xy 189.07005 56.20705) (xy 189.07005 56.19886) (xy 189.07825 56.19886) (xy 189.07825 56.19066)
			(xy 189.07825 56.18247) (xy 189.07825 56.17427) (xy 189.07825 56.16608) (xy 189.08644 56.16608) (xy 189.08644 56.15788)
			(xy 189.08644 56.14969) (xy 189.09463 56.14969) (xy 189.09463 56.1415) (xy 189.09463 56.1333) (xy 189.10283 56.1333)
			(xy 189.10283 56.12511) (xy 189.10283 56.11691) (xy 189.11102 56.11691) (xy 189.11102 56.10872) (xy 189.11922 56.10872)
			(xy 189.11922 56.10053) (xy 189.11922 56.09233) (xy 189.12741 56.09233) (xy 189.12741 56.08413) (xy 189.13561 56.08413)
			(xy 189.13561 56.07594) (xy 189.1438 56.07594) (xy 189.1438 56.06775) (xy 189.152 56.06775) (xy 189.152 56.05955)
			(xy 189.16019 56.05955) (xy 189.16019 56.05136) (xy 189.16838 56.05136) (xy 189.16838 56.04316) (xy 189.17658 56.04316)
			(xy 189.17658 56.03497) (xy 189.18478 56.03497) (xy 189.18478 56.02677) (xy 189.20116 56.02677) (xy 189.20116 56.01858)
			(xy 189.20936 56.01858) (xy 189.20936 56.01039) (xy 189.22575 56.01039) (xy 189.22575 56.00219) (xy 189.24213 56.00219)
			(xy 189.24213 55.994) (xy 189.25853 55.994) (xy 189.25853 55.9858) (xy 189.28311 55.9858) (xy 189.28311 55.97761)
			(xy 189.32408 55.97761) (xy 189.32408 55.96941) (xy 189.42242 55.96941)
		)
		(stroke
			(width 0)
			(type default)
		)
		(fill yes)
		(layer "F.Cu")
	)
	(gr_poly
		(pts
			(xy 189.43061 54.87135) (xy 189.46339 54.87135) (xy 189.46339 54.87955) (xy 189.48797 54.87955) (xy 189.48797 54.88774)
			(xy 189.50436 54.88774) (xy 189.50436 54.89593) (xy 189.52075 54.89593) (xy 189.52075 54.90413) (xy 189.52894 54.90413)
			(xy 189.52894 54.91232) (xy 189.54533 54.91232) (xy 189.54533 54.92052) (xy 189.55353 54.92052) (xy 189.55353 54.92871)
			(xy 189.56992 54.92871) (xy 189.56992 54.93691) (xy 189.57811 54.93691) (xy 189.57811 54.9451) (xy 189.5863 54.9451)
			(xy 189.5863 54.95329) (xy 189.5945 54.95329) (xy 189.5945 54.96149) (xy 189.6027 54.96149) (xy 189.6027 54.96968)
			(xy 189.61089 54.96968) (xy 189.61089 54.97788) (xy 189.61089 54.98607) (xy 189.61908 54.98607) (xy 189.61908 54.99427)
			(xy 189.62728 54.99427) (xy 189.62728 55.00246) (xy 189.62728 55.01065) (xy 189.63547 55.01065) (xy 189.63547 55.01885)
			(xy 189.64367 55.01885) (xy 189.64367 55.02705) (xy 189.64367 55.03524) (xy 189.65186 55.03524) (xy 189.65186 55.04344)
			(xy 189.65186 55.05163) (xy 189.65186 55.05982) (xy 189.66005 55.05982) (xy 189.66005 55.06802) (xy 189.66005 55.07621)
			(xy 189.66005 55.08441) (xy 189.66825 55.08441) (xy 189.66825 55.0926) (xy 189.66825 55.1008) (xy 189.66825 55.10899)
			(xy 189.66825 55.11718) (xy 189.67644 55.11718) (xy 189.67644 55.12538) (xy 189.67644 55.13357) (xy 189.67644 55.14177)
			(xy 189.67644 55.14996) (xy 189.67644 55.15816) (xy 189.67644 55.16635) (xy 189.67644 55.17455) (xy 189.67644 55.18274)
			(xy 189.67644 55.19093) (xy 189.67644 55.19913) (xy 189.67644 55.20732) (xy 189.67644 55.21552) (xy 189.67644 55.22371)
			(xy 189.66825 55.22371) (xy 189.66825 55.23191) (xy 189.66825 55.2401) (xy 189.66825 55.2483) (xy 189.66825 55.25649)
			(xy 189.66005 55.25649) (xy 189.66005 55.26469) (xy 189.66005 55.27288) (xy 189.66005 55.28108) (xy 189.65186 55.28108)
			(xy 189.65186 55.28927) (xy 189.65186 55.29746) (xy 189.64367 55.29746) (xy 189.64367 55.30566) (xy 189.64367 55.31385)
			(xy 189.63547 55.31385) (xy 189.63547 55.32205) (xy 189.63547 55.33024) (xy 189.62728 55.33024) (xy 189.62728 55.33844)
			(xy 189.61908 55.33844) (xy 189.61908 55.34663) (xy 189.61908 55.35482) (xy 189.61089 55.35482) (xy 189.61089 55.36302)
			(xy 189.6027 55.36302) (xy 189.6027 55.37122) (xy 189.5945 55.37122) (xy 189.5945 55.37941) (xy 189.5863 55.37941)
			(xy 189.5863 55.3876) (xy 189.57811 55.3876) (xy 189.57811 55.3958) (xy 189.56992 55.3958) (xy 189.56992 55.40399)
			(xy 189.56172 55.40399) (xy 189.56172 55.41219) (xy 189.55353 55.41219) (xy 189.55353 55.42038) (xy 189.53714 55.42038)
			(xy 189.53714 55.42857) (xy 189.52894 55.42857) (xy 189.52894 55.43677) (xy 189.51255 55.43677) (xy 189.51255 55.44496)
			(xy 189.49617 55.44496) (xy 189.49617 55.45316) (xy 189.47158 55.45316) (xy 189.47158 55.46136) (xy 189.447 55.46136)
			(xy 189.447 55.46955) (xy 189.39783 55.46955) (xy 189.39783 55.47774) (xy 189.34047 55.47774) (xy 189.34047 55.46955)
			(xy 189.2913 55.46955) (xy 189.2913 55.46136) (xy 189.26672 55.46136) (xy 189.26672 55.45316) (xy 189.25033 55.45316)
			(xy 189.25033 55.44496) (xy 189.22575 55.44496) (xy 189.22575 55.43677) (xy 189.21755 55.43677) (xy 189.21755 55.42857)
			(xy 189.20116 55.42857) (xy 189.20116 55.42038) (xy 189.19297 55.42038) (xy 189.19297 55.41219) (xy 189.17658 55.41219)
			(xy 189.17658 55.40399) (xy 189.16838 55.40399) (xy 189.16838 55.3958) (xy 189.16019 55.3958) (xy 189.16019 55.3876)
			(xy 189.152 55.3876) (xy 189.152 55.37941) (xy 189.1438 55.37941) (xy 189.1438 55.37122) (xy 189.13561 55.37122)
			(xy 189.13561 55.36302) (xy 189.12741 55.36302) (xy 189.12741 55.35482) (xy 189.11922 55.35482) (xy 189.11922 55.34663)
			(xy 189.11922 55.33844) (xy 189.11102 55.33844) (xy 189.11102 55.33024) (xy 189.11102 55.32205) (xy 189.10283 55.32205)
			(xy 189.10283 55.31385) (xy 189.09463 55.31385) (xy 189.09463 55.30566) (xy 189.09463 55.29746) (xy 189.08644 55.29746)
			(xy 189.08644 55.28927) (xy 189.08644 55.28108) (xy 189.08644 55.27288) (xy 189.07825 55.27288) (xy 189.07825 55.26469)
			(xy 189.07825 55.25649) (xy 189.07825 55.2483) (xy 189.07005 55.2483) (xy 189.07005 55.2401) (xy 189.07005 55.23191)
			(xy 189.07005 55.22371) (xy 189.07005 55.21552) (xy 189.07005 55.20732) (xy 189.06186 55.20732) (xy 189.06186 55.19913)
			(xy 189.06186 55.19093) (xy 189.06186 55.18274) (xy 189.06186 55.17455) (xy 189.06186 55.16635) (xy 189.06186 55.15816)
			(xy 189.06186 55.14996) (xy 189.06186 55.14177) (xy 189.06186 55.13357) (xy 189.06186 55.12538) (xy 189.07005 55.12538)
			(xy 189.07005 55.11718) (xy 189.07005 55.10899) (xy 189.07005 55.1008) (xy 189.07005 55.0926) (xy 189.07005 55.08441)
			(xy 189.07825 55.08441) (xy 189.07825 55.07621) (xy 189.07825 55.06802) (xy 189.07825 55.05982) (xy 189.08644 55.05982)
			(xy 189.08644 55.05163) (xy 189.08644 55.04344) (xy 189.09463 55.04344) (xy 189.09463 55.03524) (xy 189.09463 55.02705)
			(xy 189.10283 55.02705) (xy 189.10283 55.01885) (xy 189.10283 55.01065) (xy 189.11102 55.01065) (xy 189.11102 55.00246)
			(xy 189.11102 54.99427) (xy 189.11922 54.99427) (xy 189.11922 54.98607) (xy 189.12741 54.98607) (xy 189.12741 54.97788)
			(xy 189.13561 54.97788) (xy 189.13561 54.96968) (xy 189.13561 54.96149) (xy 189.1438 54.96149) (xy 189.1438 54.95329)
			(xy 189.152 54.95329) (xy 189.152 54.9451) (xy 189.16019 54.9451) (xy 189.16019 54.93691) (xy 189.17658 54.93691)
			(xy 189.17658 54.92871) (xy 189.18478 54.92871) (xy 189.18478 54.92052) (xy 189.19297 54.92052) (xy 189.19297 54.91232)
			(xy 189.20936 54.91232) (xy 189.20936 54.90413) (xy 189.21755 54.90413) (xy 189.21755 54.89593) (xy 189.23394 54.89593)
			(xy 189.23394 54.88774) (xy 189.25853 54.88774) (xy 189.25853 54.87955) (xy 189.27491 54.87955) (xy 189.27491 54.87135)
			(xy 189.30769 54.87135) (xy 189.30769 54.86316) (xy 189.43061 54.86316)
		)
		(stroke
			(width 0)
			(type default)
		)
		(fill yes)
		(layer "F.Cu")
	)
	(gr_poly
		(pts
			(xy 201.84527 51.44605) (xy 201.92721 51.44605) (xy 201.92721 51.45424) (xy 201.96818 51.45424) (xy 201.96818 51.46244)
			(xy 202.00096 51.46244) (xy 202.00096 51.47064) (xy 202.01735 51.47064) (xy 202.01735 51.47883) (xy 202.04194 51.47883)
			(xy 202.04194 51.48702) (xy 202.05832 51.48702) (xy 202.05832 51.49522) (xy 202.08291 51.49522) (xy 202.08291 51.50341)
			(xy 202.0911 51.50341) (xy 202.0911 51.51161) (xy 202.10749 51.51161) (xy 202.10749 51.5198) (xy 202.12388 51.5198)
			(xy 202.12388 51.52799) (xy 202.13208 51.52799) (xy 202.13208 51.53619) (xy 202.14846 51.53619) (xy 202.14846 51.54439)
			(xy 202.15666 51.54439) (xy 202.15666 51.55258) (xy 202.17305 51.55258) (xy 202.17305 51.56077) (xy 202.18124 51.56077)
			(xy 202.18124 51.56897) (xy 202.18944 51.56897) (xy 202.18944 51.57716) (xy 202.19763 51.57716) (xy 202.19763 51.58536)
			(xy 202.20582 51.58536) (xy 202.20582 51.59355) (xy 202.21402 51.59355) (xy 202.21402 51.60175) (xy 202.22222 51.60175)
			(xy 202.22222 51.60994) (xy 202.23041 51.60994) (xy 202.23041 51.61814) (xy 202.2386 51.61814) (xy 202.2386 51.62633)
			(xy 202.2468 51.62633) (xy 202.2468 51.63452) (xy 202.25499 51.63452) (xy 202.25499 51.64272) (xy 202.26319 51.64272)
			(xy 202.26319 51.65091) (xy 202.26319 51.65911) (xy 202.27138 51.65911) (xy 202.27138 51.6673) (xy 202.27958 51.6673)
			(xy 202.27958 51.6755) (xy 202.27958 51.68369) (xy 202.28777 51.68369) (xy 202.28777 51.69189) (xy 202.29597 51.69189)
			(xy 202.29597 51.70008) (xy 202.29597 51.70828) (xy 202.30416 51.70828) (xy 202.30416 51.71647) (xy 202.30416 51.72466)
			(xy 202.31235 51.72466) (xy 202.31235 51.73286) (xy 202.32055 51.73286) (xy 202.32055 51.74105) (xy 202.32055 51.74925)
			(xy 202.32874 51.74925) (xy 202.32874 51.75744) (xy 202.32874 51.76564) (xy 202.32874 51.77383) (xy 202.33694 51.77383)
			(xy 202.33694 51.78203) (xy 202.33694 51.79022) (xy 202.34513 51.79022) (xy 202.34513 51.79841) (xy 202.34513 51.80661)
			(xy 202.34513 51.8148) (xy 202.35333 51.8148) (xy 202.35333 51.823) (xy 202.35333 51.83119) (xy 202.35333 51.83939)
			(xy 202.35333 51.84758) (xy 202.36152 51.84758) (xy 202.36152 51.85578) (xy 202.36152 51.86397) (xy 202.36152 51.87216)
			(xy 202.36152 51.88036) (xy 202.36971 51.88036) (xy 202.36971 51.88856) (xy 202.36971 51.89675) (xy 202.36971 51.90494)
			(xy 202.36971 51.91314) (xy 202.36971 51.92133) (xy 202.36971 51.92953) (xy 202.36971 51.93772) (xy 202.36971 51.94592)
			(xy 202.36971 51.95411) (xy 202.36971 51.9623) (xy 202.37791 51.9623) (xy 202.37791 51.9705) (xy 202.37791 51.97869)
			(xy 202.37791 51.98689) (xy 202.37791 51.99508) (xy 202.36971 51.99508) (xy 202.36971 52.00328) (xy 202.36971 52.01147)
			(xy 202.36971 52.01967) (xy 202.36971 52.02786) (xy 202.36971 52.03606) (xy 202.36971 52.04425) (xy 202.36971 52.05244)
			(xy 202.36971 52.06064) (xy 202.36971 52.06883) (xy 202.36152 52.06883) (xy 202.36152 52.07703) (xy 202.36152 52.08522)
			(xy 202.36152 52.09342) (xy 202.36152 52.10161) (xy 202.36152 52.1098) (xy 202.35333 52.1098) (xy 202.35333 52.118)
			(xy 202.35333 52.1262) (xy 202.35333 52.13439) (xy 202.34513 52.13439) (xy 202.34513 52.14258) (xy 202.34513 52.15078)
			(xy 202.34513 52.15897) (xy 202.33694 52.15897) (xy 202.33694 52.16717) (xy 202.33694 52.17536) (xy 202.33694 52.18356)
			(xy 202.32874 52.18356) (xy 202.32874 52.19175) (xy 202.32874 52.19995) (xy 202.32055 52.19995) (xy 202.32055 52.20814)
			(xy 202.32055 52.21633) (xy 202.31235 52.21633) (xy 202.31235 52.22453) (xy 202.31235 52.23272) (xy 202.30416 52.23272)
			(xy 202.30416 52.24092) (xy 202.30416 52.24911) (xy 202.29597 52.24911) (xy 202.29597 52.25731) (xy 202.29597 52.2655)
			(xy 202.28777 52.2655) (xy 202.28777 52.2737) (xy 202.27958 52.2737) (xy 202.27958 52.28189) (xy 202.27958 52.29008)
			(xy 202.27138 52.29008) (xy 202.27138 52.29828) (xy 202.26319 52.29828) (xy 202.26319 52.30647) (xy 202.25499 52.30647)
			(xy 202.25499 52.31467) (xy 202.25499 52.32286) (xy 202.2468 52.32286) (xy 202.2468 52.33106) (xy 202.2386 52.33106)
			(xy 202.2386 52.33925) (xy 202.23041 52.33925) (xy 202.23041 52.34744) (xy 202.22222 52.34744) (xy 202.22222 52.35564)
			(xy 202.21402 52.35564) (xy 202.21402 52.36384) (xy 202.20582 52.36384) (xy 202.20582 52.37203) (xy 202.19763 52.37203)
			(xy 202.19763 52.38022) (xy 202.18944 52.38022) (xy 202.18944 52.38842) (xy 202.17305 52.38842) (xy 202.17305 52.39661)
			(xy 202.16485 52.39661) (xy 202.16485 52.40481) (xy 202.15666 52.40481) (xy 202.15666 52.413) (xy 202.14846 52.413)
			(xy 202.14846 52.4212) (xy 202.13208 52.4212) (xy 202.13208 52.42939) (xy 202.12388 52.42939) (xy 202.12388 52.43759)
			(xy 202.10749 52.43759) (xy 202.10749 52.44578) (xy 202.0911 52.44578) (xy 202.0911 52.45397) (xy 202.07471 52.45397)
			(xy 202.07471 52.46217) (xy 202.05832 52.46217) (xy 202.05832 52.47036) (xy 202.04194 52.47036) (xy 202.04194 52.47856)
			(xy 202.01735 52.47856) (xy 202.01735 52.48675) (xy 201.99277 52.48675) (xy 201.99277 52.49495) (xy 201.95999 52.49495)
			(xy 201.95999 52.50314) (xy 201.91902 52.50314) (xy 201.91902 52.51134) (xy 201.12415 52.51134) (xy 201.12415 52.50314)
			(xy 201.08318 52.50314) (xy 201.08318 52.49495) (xy 201.0586 52.49495) (xy 201.0586 52.48675) (xy 201.03401 52.48675)
			(xy 201.03401 52.47856) (xy 201.00943 52.47856) (xy 201.00943 52.47036) (xy 200.99304 52.47036) (xy 200.99304 52.46217)
			(xy 200.96846 52.46217) (xy 200.96846 52.45397) (xy 200.96026 52.45397) (xy 200.96026 52.44578) (xy 200.94387 52.44578)
			(xy 200.94387 52.43759) (xy 200.92748 52.43759) (xy 200.92748 52.42939) (xy 200.91929 52.42939) (xy 200.91929 52.4212)
			(xy 200.9029 52.4212) (xy 200.9029 52.413) (xy 200.89471 52.413) (xy 200.89471 52.40481) (xy 200.87832 52.40481)
			(xy 200.87832 52.39661) (xy 200.87012 52.39661) (xy 200.87012 52.38842) (xy 200.86193 52.38842) (xy 200.86193 52.38022)
			(xy 200.85373 52.38022) (xy 200.85373 52.37203) (xy 200.84554 52.37203) (xy 200.84554 52.36384) (xy 200.83735 52.36384)
			(xy 200.83735 52.35564) (xy 200.82915 52.35564) (xy 200.82915 52.34744) (xy 200.82096 52.34744) (xy 200.82096 52.33925)
			(xy 200.81276 52.33925) (xy 200.81276 52.33106) (xy 200.80457 52.33106) (xy 200.80457 52.32286) (xy 200.79637 52.32286)
			(xy 200.79637 52.31467) (xy 200.78818 52.31467) (xy 200.78818 52.30647) (xy 200.78818 52.29828) (xy 200.77998 52.29828)
			(xy 200.77998 52.29008) (xy 200.77179 52.29008) (xy 200.77179 52.28189) (xy 200.76359 52.28189) (xy 200.76359 52.2737)
			(xy 200.76359 52.2655) (xy 200.7554 52.2655) (xy 200.7554 52.25731) (xy 200.7554 52.24911) (xy 200.7472 52.24911)
			(xy 200.7472 52.24092) (xy 200.73901 52.24092) (xy 200.73901 52.23272) (xy 200.73901 52.22453) (xy 200.73082 52.22453)
			(xy 200.73082 52.21633) (xy 200.73082 52.20814) (xy 200.72262 52.20814) (xy 200.72262 52.19995) (xy 200.72262 52.19175)
			(xy 200.71443 52.19175) (xy 200.71443 52.18356) (xy 200.71443 52.17536) (xy 200.71443 52.16717) (xy 200.70623 52.16717)
			(xy 200.70623 52.15897) (xy 200.70623 52.15078) (xy 200.70623 52.14258) (xy 200.69804 52.14258) (xy 200.69804 52.13439)
			(xy 200.69804 52.1262) (xy 200.69804 52.118) (xy 200.68984 52.118) (xy 200.68984 52.1098) (xy 200.68984 52.10161)
			(xy 200.68984 52.09342) (xy 200.68984 52.08522) (xy 200.68984 52.07703) (xy 200.68165 52.07703) (xy 200.68165 52.06883)
			(xy 200.68165 52.06064) (xy 200.68165 52.05244) (xy 200.68165 52.04425) (xy 200.68165 52.03606) (xy 200.67345 52.03606)
			(xy 200.67345 52.02786) (xy 200.67345 52.01967) (xy 200.67345 52.01147) (xy 200.67345 52.00328) (xy 200.67345 51.99508)
			(xy 200.67345 51.98689) (xy 200.67345 51.97869) (xy 200.67345 51.9705) (xy 200.67345 51.9623) (xy 200.67345 51.95411)
			(xy 200.67345 51.94592) (xy 200.67345 51.93772) (xy 200.67345 51.92953) (xy 200.68165 51.92953) (xy 200.68165 51.92133)
			(xy 200.68165 51.91314) (xy 200.68165 51.90494) (xy 200.68165 51.89675) (xy 200.68165 51.88856) (xy 200.68165 51.88036)
			(xy 200.68165 51.87216) (xy 200.68984 51.87216) (xy 200.68984 51.86397) (xy 200.68984 51.85578) (xy 200.68984 51.84758)
			(xy 200.68984 51.83939) (xy 200.69804 51.83939) (xy 200.69804 51.83119) (xy 200.69804 51.823) (xy 200.69804 51.8148)
			(xy 200.69804 51.80661) (xy 200.70623 51.80661) (xy 200.70623 51.79841) (xy 200.70623 51.79022) (xy 200.71443 51.79022)
			(xy 200.71443 51.78203) (xy 200.71443 51.77383) (xy 200.71443 51.76564) (xy 200.72262 51.76564) (xy 200.72262 51.75744)
			(xy 200.72262 51.74925) (xy 200.73082 51.74925) (xy 200.73082 51.74105) (xy 200.73082 51.73286) (xy 200.73901 51.73286)
			(xy 200.73901 51.72466) (xy 200.73901 51.71647) (xy 200.7472 51.71647) (xy 200.7472 51.70828) (xy 200.7472 51.70008)
			(xy 200.7554 51.70008) (xy 200.7554 51.69189) (xy 200.76359 51.69189) (xy 200.76359 51.68369) (xy 200.76359 51.6755)
			(xy 200.77179 51.6755) (xy 200.77179 51.6673) (xy 200.77998 51.6673) (xy 200.77998 51.65911) (xy 200.77998 51.65091)
			(xy 200.78818 51.65091) (xy 200.78818 51.64272) (xy 200.79637 51.64272) (xy 200.79637 51.63452) (xy 200.80457 51.63452)
			(xy 200.80457 51.62633) (xy 200.81276 51.62633) (xy 200.81276 51.61814) (xy 200.82096 51.61814) (xy 200.82096 51.60994)
			(xy 200.82915 51.60994) (xy 200.82915 51.60175) (xy 200.83735 51.60175) (xy 200.83735 51.59355) (xy 200.84554 51.59355)
			(xy 200.84554 51.58536) (xy 200.85373 51.58536) (xy 200.85373 51.57716) (xy 200.86193 51.57716) (xy 200.86193 51.56897)
			(xy 200.87012 51.56897) (xy 200.87012 51.56077) (xy 200.87832 51.56077) (xy 200.87832 51.55258) (xy 200.88651 51.55258)
			(xy 200.88651 51.54439) (xy 200.9029 51.54439) (xy 200.9029 51.53619) (xy 200.9111 51.53619) (xy 200.9111 51.52799)
			(xy 200.92748 51.52799) (xy 200.92748 51.5198) (xy 200.93568 51.5198) (xy 200.93568 51.51161) (xy 200.95207 51.51161)
			(xy 200.95207 51.50341) (xy 200.96846 51.50341) (xy 200.96846 51.49522) (xy 200.98484 51.49522) (xy 200.98484 51.48702)
			(xy 201.00943 51.48702) (xy 201.00943 51.47883) (xy 201.02582 51.47883) (xy 201.02582 51.47064) (xy 201.0504 51.47064)
			(xy 201.0504 51.46244) (xy 201.08318 51.46244) (xy 201.08318 51.45424) (xy 201.11596 51.45424) (xy 201.11596 51.44605)
			(xy 201.2061 51.44605) (xy 201.2061 51.43786) (xy 201.82888 51.43786) (xy 201.82888 51.44605) (xy 201.83707 51.44605)
			(xy 201.83707 51.43786) (xy 201.84527 51.43786)
		)
		(stroke
			(width 0)
			(type default)
		)
		(fill yes)
		(layer "F.Cu")
	)
	(gr_poly
		(pts
			(xy 203.73 55.72358) (xy 203.77917 55.72358) (xy 203.77917 55.73177) (xy 203.81195 55.73177) (xy 203.81195 55.73997)
			(xy 203.83653 55.73997) (xy 203.83653 55.74816) (xy 203.86111 55.74816) (xy 203.86111 55.75636) (xy 203.8775 55.75636)
			(xy 203.8775 55.76455) (xy 203.90208 55.76455) (xy 203.90208 55.77274) (xy 203.91848 55.77274) (xy 203.91848 55.78094)
			(xy 203.92667 55.78094) (xy 203.92667 55.78913) (xy 203.94306 55.78913) (xy 203.94306 55.79733) (xy 203.95945 55.79733)
			(xy 203.95945 55.80552) (xy 203.96764 55.80552) (xy 203.96764 55.81372) (xy 203.98403 55.81372) (xy 203.98403 55.82191)
			(xy 203.99222 55.82191) (xy 203.99222 55.83011) (xy 204.00042 55.83011) (xy 204.00042 55.8383) (xy 204.00862 55.8383)
			(xy 204.00862 55.84649) (xy 204.025 55.84649) (xy 204.025 55.85469) (xy 204.0332 55.85469) (xy 204.0332 55.86288)
			(xy 204.04139 55.86288) (xy 204.04139 55.87108) (xy 204.04959 55.87108) (xy 204.04959 55.87927) (xy 204.05778 55.87927)
			(xy 204.05778 55.88747) (xy 204.06597 55.88747) (xy 204.06597 55.89566) (xy 204.07417 55.89566) (xy 204.07417 55.90386)
			(xy 204.08236 55.90386) (xy 204.08236 55.91205) (xy 204.08236 55.92024) (xy 204.09056 55.92024) (xy 204.09056 55.92844)
			(xy 204.09875 55.92844) (xy 204.09875 55.93663) (xy 204.10695 55.93663) (xy 204.10695 55.94483) (xy 204.10695 55.95302)
			(xy 204.11514 55.95302) (xy 204.11514 55.96122) (xy 204.12334 55.96122) (xy 204.12334 55.96941) (xy 204.12334 55.97761)
			(xy 204.13153 55.97761) (xy 204.13153 55.9858) (xy 204.13153 55.994) (xy 204.13972 55.994) (xy 204.13972 56.00219)
			(xy 204.14792 56.00219) (xy 204.14792 56.01039) (xy 204.14792 56.01858) (xy 204.15612 56.01858) (xy 204.15612 56.02677)
			(xy 204.15612 56.03497) (xy 204.15612 56.04316) (xy 204.16431 56.04316) (xy 204.16431 56.05136) (xy 204.16431 56.05955)
			(xy 204.1725 56.05955) (xy 204.1725 56.06775) (xy 204.1725 56.07594) (xy 204.1725 56.08413) (xy 204.1807 56.08413)
			(xy 204.1807 56.09233) (xy 204.1807 56.10053) (xy 204.1807 56.10872) (xy 204.18889 56.10872) (xy 204.18889 56.11691)
			(xy 204.18889 56.12511) (xy 204.18889 56.1333) (xy 204.18889 56.1415) (xy 204.19709 56.1415) (xy 204.19709 56.14969)
			(xy 204.19709 56.15788) (xy 204.19709 56.16608) (xy 204.19709 56.17427) (xy 204.19709 56.18247) (xy 204.19709 56.19066)
			(xy 204.20528 56.19066) (xy 204.20528 56.19886) (xy 204.20528 56.20705) (xy 204.20528 56.21524) (xy 204.20528 56.22344)
			(xy 204.20528 56.23164) (xy 204.20528 56.23983) (xy 204.20528 56.24803) (xy 204.20528 56.25622) (xy 204.20528 56.26441)
			(xy 204.20528 56.27261) (xy 204.20528 56.2808) (xy 204.20528 56.289) (xy 204.20528 56.29719) (xy 204.20528 56.30539)
			(xy 204.20528 56.31358) (xy 204.19709 56.31358) (xy 204.19709 56.32177) (xy 204.19709 56.32997) (xy 204.19709 56.33816)
			(xy 204.19709 56.34636) (xy 204.19709 56.35455) (xy 204.19709 56.36275) (xy 204.18889 56.36275) (xy 204.18889 56.37094)
			(xy 204.18889 56.37914) (xy 204.18889 56.38733) (xy 204.18889 56.39553) (xy 204.1807 56.39553) (xy 204.1807 56.40372)
			(xy 204.1807 56.41191) (xy 204.1807 56.42011) (xy 204.1725 56.42011) (xy 204.1725 56.42831) (xy 204.1725 56.4365)
			(xy 204.1725 56.44469) (xy 204.16431 56.44469) (xy 204.16431 56.45289) (xy 204.16431 56.46108) (xy 204.15612 56.46108)
			(xy 204.15612 56.46928) (xy 204.15612 56.47747) (xy 204.14792 56.47747) (xy 204.14792 56.48567) (xy 204.14792 56.49386)
			(xy 204.13972 56.49386) (xy 204.13972 56.50205) (xy 204.13972 56.51025) (xy 204.13153 56.51025) (xy 204.13153 56.51844)
			(xy 204.13153 56.52664) (xy 204.12334 56.52664) (xy 204.12334 56.53483) (xy 204.11514 56.53483) (xy 204.11514 56.54303)
			(xy 204.11514 56.55122) (xy 204.10695 56.55122) (xy 204.10695 56.55942) (xy 204.09875 56.55942) (xy 204.09875 56.56761)
			(xy 204.09875 56.5758) (xy 204.09056 56.5758) (xy 204.09056 56.584) (xy 204.08236 56.584) (xy 204.08236 56.59219)
			(xy 204.07417 56.59219) (xy 204.07417 56.60039) (xy 204.06597 56.60039) (xy 204.06597 56.60858) (xy 204.05778 56.60858)
			(xy 204.05778 56.61678) (xy 204.04959 56.61678) (xy 204.04959 56.62497) (xy 204.04139 56.62497) (xy 204.04139 56.63317)
			(xy 204.0332 56.63317) (xy 204.0332 56.64136) (xy 204.025 56.64136) (xy 204.025 56.64955) (xy 204.01681 56.64955)
			(xy 204.01681 56.65775) (xy 204.00862 56.65775) (xy 204.00862 56.66594) (xy 204.00042 56.66594) (xy 204.00042 56.67414)
			(xy 203.98403 56.67414) (xy 203.98403 56.68233) (xy 203.97584 56.68233) (xy 203.97584 56.69053) (xy 203.96764 56.69053)
			(xy 203.96764 56.69872) (xy 203.95125 56.69872) (xy 203.95125 56.70692) (xy 203.93486 56.70692) (xy 203.93486 56.71511)
			(xy 203.92667 56.71511) (xy 203.92667 56.72331) (xy 203.91028 56.72331) (xy 203.91028 56.7315) (xy 203.89389 56.7315)
			(xy 203.89389 56.73969) (xy 203.86931 56.73969) (xy 203.86931 56.74789) (xy 203.85292 56.74789) (xy 203.85292 56.75608)
			(xy 203.82833 56.75608) (xy 203.82833 56.76428) (xy 203.79556 56.76428) (xy 203.79556 56.77247) (xy 203.75458 56.77247)
			(xy 203.75458 56.78067) (xy 203.70542 56.78067) (xy 203.70542 56.78886) (xy 203.69722 56.78886) (xy 203.69722 56.78067)
			(xy 203.68903 56.78067) (xy 203.68903 56.78886) (xy 203.68084 56.78886) (xy 203.68084 56.78067) (xy 203.67264 56.78067)
			(xy 203.67264 56.78886) (xy 203.61528 56.78886) (xy 203.61528 56.78067) (xy 203.55792 56.78067) (xy 203.55792 56.77247)
			(xy 203.51694 56.77247) (xy 203.51694 56.76428) (xy 203.49236 56.76428) (xy 203.49236 56.75608) (xy 203.46778 56.75608)
			(xy 203.46778 56.74789) (xy 203.44319 56.74789) (xy 203.44319 56.73969) (xy 203.42681 56.73969) (xy 203.42681 56.7315)
			(xy 203.41041 56.7315) (xy 203.41041 56.72331) (xy 203.39403 56.72331) (xy 203.39403 56.71511) (xy 203.37764 56.71511)
			(xy 203.37764 56.70692) (xy 203.36944 56.70692) (xy 203.36944 56.69872) (xy 203.35305 56.69872) (xy 203.35305 56.69053)
			(xy 203.34486 56.69053) (xy 203.34486 56.68233) (xy 203.32847 56.68233) (xy 203.32847 56.67414) (xy 203.32028 56.67414)
			(xy 203.32028 56.66594) (xy 203.31208 56.66594) (xy 203.31208 56.65775) (xy 203.30389 56.65775) (xy 203.30389 56.64955)
			(xy 203.2875 56.64955) (xy 203.2875 56.64136) (xy 203.2793 56.64136) (xy 203.2793 56.63317) (xy 203.27111 56.63317)
			(xy 203.27111 56.62497) (xy 203.26291 56.62497) (xy 203.26291 56.61678) (xy 203.25472 56.61678) (xy 203.25472 56.60858)
			(xy 203.24653 56.60858) (xy 203.24653 56.60039) (xy 203.24653 56.59219) (xy 203.23833 56.59219) (xy 203.23833 56.584)
			(xy 203.23014 56.584) (xy 203.23014 56.5758) (xy 203.22194 56.5758) (xy 203.22194 56.56761) (xy 203.21375 56.56761)
			(xy 203.21375 56.55942) (xy 203.21375 56.55122) (xy 203.20555 56.55122) (xy 203.20555 56.54303) (xy 203.19736 56.54303)
			(xy 203.19736 56.53483) (xy 203.19736 56.52664) (xy 203.18917 56.52664) (xy 203.18917 56.51844) (xy 203.18917 56.51025)
			(xy 203.18097 56.51025) (xy 203.18097 56.50205) (xy 203.17277 56.50205) (xy 203.17277 56.49386) (xy 203.17277 56.48567)
			(xy 203.16458 56.48567) (xy 203.16458 56.47747) (xy 203.16458 56.46928) (xy 203.15639 56.46928) (xy 203.15639 56.46108)
			(xy 203.15639 56.45289) (xy 203.15639 56.44469) (xy 203.14819 56.44469) (xy 203.14819 56.4365) (xy 203.14819 56.42831)
			(xy 203.14 56.42831) (xy 203.14 56.42011) (xy 203.14 56.41191) (xy 203.14 56.40372) (xy 203.1318 56.40372)
			(xy 203.1318 56.39553) (xy 203.1318 56.38733) (xy 203.1318 56.37914) (xy 203.1318 56.37094) (xy 203.12361 56.37094)
			(xy 203.12361 56.36275) (xy 203.12361 56.35455) (xy 203.12361 56.34636) (xy 203.12361 56.33816) (xy 203.12361 56.32997)
			(xy 203.11541 56.32997) (xy 203.11541 56.32177) (xy 203.11541 56.31358) (xy 203.11541 56.30539) (xy 203.11541 56.29719)
			(xy 203.11541 56.289) (xy 203.11541 56.2808) (xy 203.11541 56.27261) (xy 203.11541 56.26441) (xy 203.11541 56.25622)
			(xy 203.11541 56.24803) (xy 203.11541 56.23983) (xy 203.11541 56.23164) (xy 203.11541 56.22344) (xy 203.11541 56.21524)
			(xy 203.11541 56.20705) (xy 203.11541 56.19886) (xy 203.11541 56.19066) (xy 203.11541 56.18247) (xy 203.11541 56.17427)
			(xy 203.12361 56.17427) (xy 203.12361 56.16608) (xy 203.12361 56.15788) (xy 203.12361 56.14969) (xy 203.12361 56.1415)
			(xy 203.12361 56.1333) (xy 203.1318 56.1333) (xy 203.1318 56.12511) (xy 203.1318 56.11691) (xy 203.1318 56.10872)
			(xy 203.1318 56.10053) (xy 203.14 56.10053) (xy 203.14 56.09233) (xy 203.14 56.08413) (xy 203.14 56.07594)
			(xy 203.14819 56.07594) (xy 203.14819 56.06775) (xy 203.14819 56.05955) (xy 203.14819 56.05136) (xy 203.15639 56.05136)
			(xy 203.15639 56.04316) (xy 203.15639 56.03497) (xy 203.16458 56.03497) (xy 203.16458 56.02677) (xy 203.16458 56.01858)
			(xy 203.17277 56.01858) (xy 203.17277 56.01039) (xy 203.17277 56.00219) (xy 203.18097 56.00219) (xy 203.18097 55.994)
			(xy 203.18097 55.9858) (xy 203.18917 55.9858) (xy 203.18917 55.97761) (xy 203.18917 55.96941) (xy 203.19736 55.96941)
			(xy 203.19736 55.96122) (xy 203.20555 55.96122) (xy 203.20555 55.95302) (xy 203.20555 55.94483) (xy 203.21375 55.94483)
			(xy 203.21375 55.93663) (xy 203.22194 55.93663) (xy 203.22194 55.92844) (xy 203.23014 55.92844) (xy 203.23014 55.92024)
			(xy 203.23014 55.91205) (xy 203.23833 55.91205) (xy 203.23833 55.90386) (xy 203.24653 55.90386) (xy 203.24653 55.89566)
			(xy 203.25472 55.89566) (xy 203.25472 55.88747) (xy 203.26291 55.88747) (xy 203.26291 55.87927) (xy 203.27111 55.87927)
			(xy 203.27111 55.87108) (xy 203.2793 55.87108) (xy 203.2793 55.86288) (xy 203.2875 55.86288) (xy 203.2875 55.85469)
			(xy 203.29569 55.85469) (xy 203.29569 55.84649) (xy 203.30389 55.84649) (xy 203.30389 55.8383) (xy 203.31208 55.8383)
			(xy 203.31208 55.83011) (xy 203.32847 55.83011) (xy 203.32847 55.82191) (xy 203.33666 55.82191) (xy 203.33666 55.81372)
			(xy 203.35305 55.81372) (xy 203.35305 55.80552) (xy 203.36125 55.80552) (xy 203.36125 55.79733) (xy 203.37764 55.79733)
			(xy 203.37764 55.78913) (xy 203.38583 55.78913) (xy 203.38583 55.78094) (xy 203.40222 55.78094) (xy 203.40222 55.77274)
			(xy 203.41861 55.77274) (xy 203.41861 55.76455) (xy 203.435 55.76455) (xy 203.435 55.75636) (xy 203.45958 55.75636)
			(xy 203.45958 55.74816) (xy 203.48417 55.74816) (xy 203.48417 55.73997) (xy 203.50875 55.73997) (xy 203.50875 55.73177)
			(xy 203.54153 55.73177) (xy 203.54153 55.72358) (xy 203.5825 55.72358) (xy 203.5825 55.71538) (xy 203.73 55.71538)
		)
		(stroke
			(width 0)
			(type default)
		)
		(fill yes)
		(layer "F.Cu")
	)
	(gr_poly
		(pts
			(xy 188.24241 51.44605) (xy 188.32435 51.44605) (xy 188.32435 51.45424) (xy 188.35713 51.45424) (xy 188.35713 51.46244)
			(xy 188.38991 51.46244) (xy 188.38991 51.47064) (xy 188.4063 51.47064) (xy 188.4063 51.47883) (xy 188.43088 51.47883)
			(xy 188.43088 51.48702) (xy 188.44727 51.48702) (xy 188.44727 51.49522) (xy 188.46366 51.49522) (xy 188.46366 51.50341)
			(xy 188.48005 51.50341) (xy 188.48005 51.51161) (xy 188.49644 51.51161) (xy 188.49644 51.5198) (xy 188.50463 51.5198)
			(xy 188.50463 51.52799) (xy 188.52102 51.52799) (xy 188.52102 51.53619) (xy 188.52922 51.53619) (xy 188.52922 51.54439)
			(xy 188.53741 51.54439) (xy 188.53741 51.55258) (xy 188.5538 51.55258) (xy 188.5538 51.56077) (xy 188.56199 51.56077)
			(xy 188.56199 51.56897) (xy 188.57019 51.56897) (xy 188.57019 51.57716) (xy 188.57838 51.57716) (xy 188.57838 51.58536)
			(xy 188.58658 51.58536) (xy 188.58658 51.59355) (xy 188.59477 51.59355) (xy 188.59477 51.60175) (xy 188.60297 51.60175)
			(xy 188.60297 51.60994) (xy 188.61116 51.60994) (xy 188.61116 51.61814) (xy 188.61935 51.61814) (xy 188.61935 51.62633)
			(xy 188.61935 51.63452) (xy 188.62755 51.63452) (xy 188.62755 51.64272) (xy 188.63574 51.64272) (xy 188.63574 51.65091)
			(xy 188.64394 51.65091) (xy 188.64394 51.65911) (xy 188.64394 51.6673) (xy 188.65213 51.6673) (xy 188.65213 51.6755)
			(xy 188.66033 51.6755) (xy 188.66033 51.68369) (xy 188.66033 51.69189) (xy 188.66852 51.69189) (xy 188.66852 51.70008)
			(xy 188.66852 51.70828) (xy 188.67672 51.70828) (xy 188.67672 51.71647) (xy 188.67672 51.72466) (xy 188.68491 51.72466)
			(xy 188.68491 51.73286) (xy 188.68491 51.74105) (xy 188.69311 51.74105) (xy 188.69311 51.74925) (xy 188.69311 51.75744)
			(xy 188.69311 51.76564) (xy 188.7013 51.76564) (xy 188.7013 51.77383) (xy 188.7013 51.78203) (xy 188.70949 51.78203)
			(xy 188.70949 51.79022) (xy 188.70949 51.79841) (xy 188.70949 51.80661) (xy 188.70949 51.8148) (xy 188.71769 51.8148)
			(xy 188.71769 51.823) (xy 188.71769 51.83119) (xy 188.71769 51.83939) (xy 188.71769 51.84758) (xy 188.71769 51.85578)
			(xy 188.72588 51.85578) (xy 188.72588 51.86397) (xy 188.72588 51.87216) (xy 188.72588 51.88036) (xy 188.72588 51.88856)
			(xy 188.72588 51.89675) (xy 188.72588 51.90494) (xy 188.72588 51.91314) (xy 188.72588 51.92133) (xy 188.72588 51.92953)
			(xy 188.72588 51.93772) (xy 188.72588 51.94592) (xy 188.72588 51.95411) (xy 188.72588 51.9623) (xy 188.72588 51.9705)
			(xy 188.72588 51.97869) (xy 188.72588 51.98689) (xy 188.72588 51.99508) (xy 188.72588 52.00328) (xy 188.72588 52.01147)
			(xy 188.72588 52.01967) (xy 188.72588 52.02786) (xy 188.72588 52.03606) (xy 188.72588 52.04425) (xy 188.72588 52.05244)
			(xy 188.72588 52.06064) (xy 188.72588 52.06883) (xy 188.72588 52.07703) (xy 188.72588 52.08522) (xy 188.72588 52.09342)
			(xy 188.72588 52.10161) (xy 188.72588 52.1098) (xy 188.72588 52.118) (xy 188.72588 52.1262) (xy 188.72588 52.13439)
			(xy 188.72588 52.14258) (xy 188.72588 52.15078) (xy 188.72588 52.15897) (xy 188.72588 52.16717) (xy 188.72588 52.17536)
			(xy 188.72588 52.18356) (xy 188.72588 52.19175) (xy 188.72588 52.19995) (xy 188.72588 52.20814) (xy 188.72588 52.21633)
			(xy 188.72588 52.22453) (xy 188.72588 52.23272) (xy 188.72588 52.24092) (xy 188.72588 52.24911) (xy 188.72588 52.25731)
			(xy 188.72588 52.2655) (xy 188.72588 52.2737) (xy 188.72588 52.28189) (xy 188.72588 52.29008) (xy 188.72588 52.29828)
			(xy 188.72588 52.30647) (xy 188.72588 52.31467) (xy 188.72588 52.32286) (xy 188.72588 52.33106) (xy 188.72588 52.33925)
			(xy 188.72588 52.34744) (xy 188.72588 52.35564) (xy 188.72588 52.36384) (xy 188.72588 52.37203) (xy 188.72588 52.38022)
			(xy 188.72588 52.38842) (xy 188.72588 52.39661) (xy 188.72588 52.40481) (xy 188.72588 52.413) (xy 188.72588 52.4212)
			(xy 188.72588 52.42939) (xy 188.72588 52.43759) (xy 188.72588 52.44578) (xy 188.72588 52.45397) (xy 188.72588 52.46217)
			(xy 188.72588 52.47036) (xy 188.72588 52.47856) (xy 188.72588 52.48675) (xy 188.72588 52.49495) (xy 188.72588 52.50314)
			(xy 188.72588 52.51134) (xy 188.72588 52.51953) (xy 188.72588 52.52772) (xy 188.72588 52.53592) (xy 188.72588 52.54411)
			(xy 188.72588 52.55231) (xy 188.72588 52.5605) (xy 188.72588 52.5687) (xy 188.72588 52.57689) (xy 188.72588 52.58509)
			(xy 188.72588 52.59328) (xy 188.72588 52.60148) (xy 188.72588 52.60967) (xy 188.72588 52.61787) (xy 188.72588 52.62606)
			(xy 188.72588 52.63425) (xy 188.72588 52.64245) (xy 188.72588 52.65064) (xy 188.72588 52.65884) (xy 188.72588 52.66703)
			(xy 188.72588 52.67522) (xy 188.72588 52.68342) (xy 188.72588 52.69162) (xy 188.72588 52.69981) (xy 188.72588 52.708)
			(xy 188.72588 52.7162) (xy 188.72588 52.72439) (xy 188.72588 52.73259) (xy 188.72588 52.74078) (xy 188.72588 52.74898)
			(xy 188.72588 52.75717) (xy 188.72588 52.76536) (xy 188.72588 52.77356) (xy 188.72588 52.78175) (xy 188.72588 52.78995)
			(xy 188.72588 52.79814) (xy 188.72588 52.80634) (xy 188.72588 52.81453) (xy 188.72588 52.82273) (xy 188.72588 52.83092)
			(xy 188.72588 52.83911) (xy 188.72588 52.84731) (xy 188.72588 52.85551) (xy 188.72588 52.8637) (xy 188.72588 52.87189)
			(xy 188.72588 52.88009) (xy 188.72588 52.88828) (xy 188.72588 52.89648) (xy 188.72588 52.90467) (xy 188.72588 52.91287)
			(xy 188.72588 52.92106) (xy 188.72588 52.92926) (xy 188.72588 52.93745) (xy 188.72588 52.94564) (xy 188.72588 52.95384)
			(xy 188.72588 52.96203) (xy 188.72588 52.97023) (xy 188.72588 52.97842) (xy 188.72588 52.98662) (xy 188.72588 52.99481)
			(xy 188.72588 53.00301) (xy 188.72588 53.0112) (xy 188.72588 53.01939) (xy 188.72588 53.02759) (xy 188.72588 53.03578)
			(xy 188.72588 53.04398) (xy 188.72588 53.05217) (xy 188.72588 53.06037) (xy 188.72588 53.06856) (xy 188.72588 53.07675)
			(xy 188.72588 53.08495) (xy 188.72588 53.09315) (xy 188.72588 53.10134) (xy 188.72588 53.10953) (xy 188.72588 53.11773)
			(xy 188.72588 53.12592) (xy 188.72588 53.13412) (xy 188.72588 53.14231) (xy 188.72588 53.15051) (xy 188.72588 53.1587)
			(xy 188.72588 53.16689) (xy 188.72588 53.17509) (xy 188.72588 53.18328) (xy 188.72588 53.19148) (xy 188.72588 53.19967)
			(xy 188.72588 53.20787) (xy 188.72588 53.21606) (xy 188.72588 53.22426) (xy 188.72588 53.23245) (xy 188.72588 53.24065)
			(xy 188.72588 53.24884) (xy 188.72588 53.25703) (xy 188.72588 53.26523) (xy 188.72588 53.27342) (xy 188.72588 53.28162)
			(xy 188.72588 53.28981) (xy 188.72588 53.29801) (xy 188.72588 53.3062) (xy 188.72588 53.31439) (xy 188.72588 53.32259)
			(xy 188.72588 53.33079) (xy 188.72588 53.33898) (xy 188.72588 53.34718) (xy 188.72588 53.35537) (xy 188.72588 53.36356)
			(xy 188.72588 53.37176) (xy 188.72588 53.37995) (xy 188.72588 53.38815) (xy 188.72588 53.39634) (xy 188.72588 53.40453)
			(xy 188.72588 53.41273) (xy 188.72588 53.42092) (xy 188.72588 53.42912) (xy 188.72588 53.43731) (xy 188.72588 53.44551)
			(xy 188.72588 53.4537) (xy 188.72588 53.4619) (xy 188.72588 53.47009) (xy 188.72588 53.47829) (xy 188.72588 53.48648)
			(xy 188.72588 53.49467) (xy 188.72588 53.50287) (xy 188.72588 53.51106) (xy 188.72588 53.51926) (xy 188.72588 53.52745)
			(xy 188.72588 53.53565) (xy 188.72588 53.54384) (xy 188.72588 53.55204) (xy 188.72588 53.56023) (xy 188.72588 53.56843)
			(xy 188.72588 53.57662) (xy 188.72588 53.58482) (xy 188.72588 53.59301) (xy 188.72588 53.6012) (xy 188.72588 53.6094)
			(xy 188.72588 53.61759) (xy 188.72588 53.62579) (xy 188.72588 53.63398) (xy 188.72588 53.64218) (xy 188.72588 53.65037)
			(xy 188.72588 53.65857) (xy 188.72588 53.66676) (xy 188.72588 53.67495) (xy 188.72588 53.68315) (xy 188.72588 53.69134)
			(xy 188.72588 53.69954) (xy 188.72588 53.70773) (xy 188.72588 53.71593) (xy 188.72588 53.72412) (xy 188.72588 53.73231)
			(xy 188.72588 53.74051) (xy 188.72588 53.7487) (xy 188.72588 53.7569) (xy 188.72588 53.76509) (xy 188.72588 53.77329)
			(xy 188.72588 53.78148) (xy 188.72588 53.78968) (xy 188.72588 53.79787) (xy 188.72588 53.80606) (xy 188.72588 53.81426)
			(xy 188.72588 53.82246) (xy 188.72588 53.83065) (xy 188.72588 53.83884) (xy 188.72588 53.84704) (xy 188.72588 53.85523)
			(xy 188.72588 53.86343) (xy 188.72588 53.87162) (xy 188.72588 53.87982) (xy 188.72588 53.88801) (xy 188.72588 53.8962)
			(xy 188.72588 53.9044) (xy 188.72588 53.91259) (xy 188.72588 53.92079) (xy 188.72588 53.92898) (xy 188.72588 53.93718)
			(xy 188.72588 53.94537) (xy 188.72588 53.95357) (xy 188.72588 53.96176) (xy 188.72588 53.96996) (xy 188.72588 53.97815)
			(xy 188.72588 53.98634) (xy 188.72588 53.99454) (xy 188.72588 54.00273) (xy 188.72588 54.01093) (xy 188.72588 54.01912)
			(xy 188.72588 54.02732) (xy 188.72588 54.03551) (xy 188.72588 54.0437) (xy 188.72588 54.0519) (xy 188.72588 54.0601)
			(xy 188.72588 54.06829) (xy 188.72588 54.07649) (xy 188.72588 54.08468) (xy 188.72588 54.09287) (xy 188.72588 54.10107)
			(xy 188.72588 54.10926) (xy 188.72588 54.11746) (xy 188.72588 54.12565) (xy 188.72588 54.13385) (xy 188.72588 54.14204)
			(xy 188.72588 54.15023) (xy 188.72588 54.15843) (xy 188.72588 54.16662) (xy 188.72588 54.17482) (xy 188.72588 54.18301)
			(xy 188.72588 54.19121) (xy 188.72588 54.1994) (xy 188.72588 54.2076) (xy 188.72588 54.21579) (xy 188.72588 54.22398)
			(xy 188.72588 54.23218) (xy 188.72588 54.24037) (xy 188.72588 54.24857) (xy 188.72588 54.25676) (xy 188.72588 54.26496)
			(xy 188.72588 54.27315) (xy 188.72588 54.28134) (xy 188.72588 54.28954) (xy 188.72588 54.29774) (xy 188.72588 54.30593)
			(xy 188.72588 54.31413) (xy 188.72588 54.32232) (xy 188.72588 54.33051) (xy 188.72588 54.33871) (xy 188.72588 54.3469)
			(xy 188.72588 54.3551) (xy 188.72588 54.36329) (xy 188.72588 54.37149) (xy 188.72588 54.37968) (xy 188.72588 54.38787)
			(xy 188.72588 54.39607) (xy 188.72588 54.40426) (xy 188.72588 54.41246) (xy 188.72588 54.42065) (xy 188.72588 54.42885)
			(xy 188.72588 54.43704) (xy 188.72588 54.44524) (xy 188.72588 54.45343) (xy 188.72588 54.46162) (xy 188.72588 54.46982)
			(xy 188.72588 54.47801) (xy 188.72588 54.48621) (xy 188.72588 54.4944) (xy 188.72588 54.5026) (xy 188.72588 54.51079)
			(xy 188.72588 54.51899) (xy 188.72588 54.52718) (xy 188.72588 54.53538) (xy 188.72588 54.54357) (xy 188.72588 54.55176)
			(xy 188.72588 54.55996) (xy 188.72588 54.56815) (xy 188.72588 54.57635) (xy 188.72588 54.58454) (xy 188.72588 54.59274)
			(xy 188.72588 54.60093) (xy 188.72588 54.60913) (xy 188.72588 54.61732) (xy 188.72588 54.62551) (xy 188.72588 54.63371)
			(xy 188.72588 54.6419) (xy 188.72588 54.6501) (xy 188.72588 54.65829) (xy 188.72588 54.66649) (xy 188.72588 54.67468)
			(xy 188.72588 54.68288) (xy 188.72588 54.69107) (xy 188.72588 54.69926) (xy 188.72588 54.70746) (xy 188.72588 54.71565)
			(xy 188.72588 54.72385) (xy 188.72588 54.73204) (xy 188.72588 54.74024) (xy 188.72588 54.74843) (xy 188.72588 54.75663)
			(xy 188.72588 54.76482) (xy 188.72588 54.77302) (xy 188.72588 54.78121) (xy 188.72588 54.78941) (xy 188.72588 54.7976)
			(xy 188.72588 54.80579) (xy 188.72588 54.81399) (xy 188.72588 54.82218) (xy 188.72588 54.83038) (xy 188.72588 54.83857)
			(xy 188.72588 54.84677) (xy 188.72588 54.85496) (xy 188.72588 54.86316) (xy 188.72588 54.87135) (xy 188.72588 54.87955)
			(xy 188.72588 54.88774) (xy 188.72588 54.89593) (xy 188.72588 54.90413) (xy 188.72588 54.91232) (xy 188.72588 54.92052)
			(xy 188.72588 54.92871) (xy 188.72588 54.93691) (xy 188.72588 54.9451) (xy 188.72588 54.95329) (xy 188.72588 54.96149)
			(xy 188.72588 54.96968) (xy 188.72588 54.97788) (xy 188.72588 54.98607) (xy 188.72588 54.99427) (xy 188.72588 55.00246)
			(xy 188.72588 55.01065) (xy 188.72588 55.01885) (xy 188.72588 55.02705) (xy 188.72588 55.03524) (xy 188.72588 55.04344)
			(xy 188.72588 55.05163) (xy 188.72588 55.05982) (xy 188.72588 55.06802) (xy 188.72588 55.07621) (xy 188.72588 55.08441)
			(xy 188.72588 55.0926) (xy 188.72588 55.1008) (xy 188.72588 55.10899) (xy 188.72588 55.11718) (xy 188.72588 55.12538)
			(xy 188.72588 55.13357) (xy 188.72588 55.14177) (xy 188.72588 55.14996) (xy 188.72588 55.15816) (xy 188.72588 55.16635)
			(xy 188.72588 55.17455) (xy 188.72588 55.18274) (xy 188.72588 55.19093) (xy 188.72588 55.19913) (xy 188.72588 55.20732)
			(xy 188.72588 55.21552) (xy 188.72588 55.22371) (xy 188.72588 55.23191) (xy 188.72588 55.2401) (xy 188.72588 55.2483)
			(xy 188.72588 55.25649) (xy 188.72588 55.26469) (xy 188.72588 55.27288) (xy 188.72588 55.28108) (xy 188.72588 55.28927)
			(xy 188.72588 55.29746) (xy 188.72588 55.30566) (xy 188.72588 55.31385) (xy 188.72588 55.32205) (xy 188.72588 55.33024)
			(xy 188.72588 55.33844) (xy 188.72588 55.34663) (xy 188.72588 55.35482) (xy 188.72588 55.36302) (xy 188.72588 55.37122)
			(xy 188.72588 55.37941) (xy 188.72588 55.3876) (xy 188.72588 55.3958) (xy 188.72588 55.40399) (xy 188.72588 55.41219)
			(xy 188.72588 55.42038) (xy 188.72588 55.42857) (xy 188.72588 55.43677) (xy 188.72588 55.44496) (xy 188.72588 55.45316)
			(xy 188.72588 55.46136) (xy 188.72588 55.46955) (xy 188.72588 55.47774) (xy 188.72588 55.48594) (xy 188.72588 55.49413)
			(xy 188.72588 55.50233) (xy 188.72588 55.51052) (xy 188.72588 55.51872) (xy 188.72588 55.52691) (xy 188.72588 55.5351)
			(xy 188.72588 55.5433) (xy 188.72588 55.55149) (xy 188.72588 55.55969) (xy 188.72588 55.56788) (xy 188.72588 55.57608)
			(xy 188.72588 55.58427) (xy 188.72588 55.59247) (xy 188.72588 55.60066) (xy 188.72588 55.60885) (xy 188.72588 55.61705)
			(xy 188.72588 55.62524) (xy 188.72588 55.63344) (xy 188.72588 55.64163) (xy 188.72588 55.64983) (xy 188.72588 55.65802)
			(xy 188.72588 55.66622) (xy 188.72588 55.67441) (xy 188.72588 55.6826) (xy 188.72588 55.6908) (xy 188.72588 55.69899)
			(xy 188.72588 55.70719) (xy 188.72588 55.71538) (xy 188.72588 55.72358) (xy 188.72588 55.73177) (xy 188.72588 55.73997)
			(xy 188.72588 55.74816) (xy 188.72588 55.75636) (xy 188.72588 55.76455) (xy 188.72588 55.77274) (xy 188.72588 55.78094)
			(xy 188.72588 55.78913) (xy 188.72588 55.79733) (xy 188.72588 55.80552) (xy 188.72588 55.81372) (xy 188.72588 55.82191)
			(xy 188.72588 55.83011) (xy 188.72588 55.8383) (xy 188.72588 55.84649) (xy 188.72588 55.85469) (xy 188.72588 55.86288)
			(xy 188.72588 55.87108) (xy 188.72588 55.87927) (xy 188.72588 55.88747) (xy 188.72588 55.89566) (xy 188.72588 55.90386)
			(xy 188.72588 55.91205) (xy 188.72588 55.92024) (xy 188.72588 55.92844) (xy 188.72588 55.93663) (xy 188.72588 55.94483)
			(xy 188.72588 55.95302) (xy 188.72588 55.96122) (xy 188.72588 55.96941) (xy 188.72588 55.97761) (xy 188.72588 55.9858)
			(xy 188.72588 55.994) (xy 188.72588 56.00219) (xy 188.72588 56.01039) (xy 188.72588 56.01858) (xy 188.72588 56.02677)
			(xy 188.72588 56.03497) (xy 188.72588 56.04316) (xy 188.72588 56.05136) (xy 188.72588 56.05955) (xy 188.72588 56.06775)
			(xy 188.72588 56.07594) (xy 188.72588 56.08413) (xy 188.72588 56.09233) (xy 188.72588 56.10053) (xy 188.72588 56.10872)
			(xy 188.72588 56.11691) (xy 188.72588 56.12511) (xy 188.72588 56.1333) (xy 188.72588 56.1415) (xy 188.72588 56.14969)
			(xy 188.72588 56.15788) (xy 188.72588 56.16608) (xy 188.72588 56.17427) (xy 188.72588 56.18247) (xy 188.72588 56.19066)
			(xy 188.72588 56.19886) (xy 188.72588 56.20705) (xy 188.72588 56.21524) (xy 188.72588 56.22344) (xy 188.72588 56.23164)
			(xy 188.72588 56.23983) (xy 188.72588 56.24803) (xy 188.72588 56.25622) (xy 188.72588 56.26441) (xy 188.72588 56.27261)
			(xy 188.72588 56.2808) (xy 188.72588 56.289) (xy 188.72588 56.29719) (xy 188.72588 56.30539) (xy 188.72588 56.31358)
			(xy 188.72588 56.32177) (xy 188.72588 56.32997) (xy 188.72588 56.33816) (xy 188.72588 56.34636) (xy 188.72588 56.35455)
			(xy 188.72588 56.36275) (xy 188.72588 56.37094) (xy 188.72588 56.37914) (xy 188.72588 56.38733) (xy 188.72588 56.39553)
			(xy 188.72588 56.40372) (xy 188.72588 56.41191) (xy 188.72588 56.42011) (xy 188.72588 56.42831) (xy 188.72588 56.4365)
			(xy 188.72588 56.44469) (xy 188.72588 56.45289) (xy 188.72588 56.46108) (xy 188.72588 56.46928) (xy 188.72588 56.47747)
			(xy 188.72588 56.48567) (xy 188.72588 56.49386) (xy 188.72588 56.50205) (xy 188.72588 56.51025) (xy 188.72588 56.51844)
			(xy 188.72588 56.52664) (xy 188.72588 56.53483) (xy 188.72588 56.54303) (xy 188.72588 56.55122) (xy 188.72588 56.55942)
			(xy 188.72588 56.56761) (xy 188.72588 56.5758) (xy 188.72588 56.584) (xy 188.72588 56.59219) (xy 188.72588 56.60039)
			(xy 188.72588 56.60858) (xy 188.72588 56.61678) (xy 188.72588 56.62497) (xy 188.72588 56.63317) (xy 188.72588 56.64136)
			(xy 188.72588 56.64955) (xy 188.72588 56.65775) (xy 188.72588 56.66594) (xy 188.72588 56.67414) (xy 188.72588 56.68233)
			(xy 188.72588 56.69053) (xy 188.72588 56.69872) (xy 188.72588 56.70692) (xy 188.72588 56.71511) (xy 188.72588 56.72331)
			(xy 188.72588 56.7315) (xy 188.72588 56.73969) (xy 188.72588 56.74789) (xy 188.72588 56.75608) (xy 188.72588 56.76428)
			(xy 188.72588 56.77247) (xy 188.72588 56.78067) (xy 188.72588 56.78886) (xy 188.72588 56.79706) (xy 188.72588 56.80525)
			(xy 188.72588 56.81345) (xy 188.72588 56.82164) (xy 188.72588 56.82983) (xy 188.72588 56.83803) (xy 188.72588 56.84622)
			(xy 188.72588 56.85442) (xy 188.72588 56.86261) (xy 188.72588 56.87081) (xy 188.72588 56.879) (xy 188.72588 56.88719)
			(xy 188.72588 56.89539) (xy 188.72588 56.90358) (xy 188.72588 56.91178) (xy 188.72588 56.91997) (xy 188.72588 56.92817)
			(xy 188.72588 56.93636) (xy 188.72588 56.94455) (xy 188.72588 56.95275) (xy 188.72588 56.96095) (xy 188.72588 56.96914)
			(xy 188.72588 56.97734) (xy 188.72588 56.98553) (xy 188.72588 56.99372) (xy 188.72588 57.00192) (xy 188.72588 57.01011)
			(xy 188.72588 57.01831) (xy 188.72588 57.0265) (xy 188.72588 57.0347) (xy 188.72588 57.04289) (xy 188.72588 57.05109)
			(xy 188.72588 57.05928) (xy 188.72588 57.06747) (xy 188.72588 57.07567) (xy 188.72588 57.08386) (xy 188.72588 57.09206)
			(xy 188.72588 57.10025) (xy 188.72588 57.10845) (xy 188.72588 57.11664) (xy 188.72588 57.12484) (xy 188.72588 57.13303)
			(xy 188.72588 57.14122) (xy 188.72588 57.14942) (xy 188.72588 57.15761) (xy 188.72588 57.16581) (xy 188.72588 57.174)
			(xy 188.72588 57.18219) (xy 188.72588 57.19039) (xy 188.72588 57.19859) (xy 188.72588 57.20678) (xy 188.72588 57.21498)
			(xy 188.72588 57.22317) (xy 188.72588 57.23136) (xy 188.72588 57.23956) (xy 188.72588 57.24775) (xy 188.72588 57.25595)
			(xy 188.72588 57.26414) (xy 188.72588 57.27234) (xy 188.72588 57.28053) (xy 188.72588 57.28872) (xy 188.72588 57.29692)
			(xy 188.72588 57.30511) (xy 188.72588 57.31331) (xy 188.72588 57.3215) (xy 188.72588 57.3297) (xy 188.72588 57.33789)
			(xy 188.72588 57.34609) (xy 188.72588 57.35428) (xy 188.72588 57.36248) (xy 188.72588 57.37067) (xy 188.72588 57.37886)
			(xy 188.72588 57.38706) (xy 188.72588 57.39526) (xy 188.72588 57.40345) (xy 188.72588 57.41164) (xy 188.72588 57.41984)
			(xy 188.72588 57.42803) (xy 188.72588 57.43623) (xy 188.72588 57.44442) (xy 188.72588 57.45262) (xy 188.72588 57.46081)
			(xy 188.72588 57.469) (xy 188.72588 57.4772) (xy 188.72588 57.48539) (xy 188.72588 57.49359) (xy 188.72588 57.50178)
			(xy 188.72588 57.50998) (xy 188.72588 57.51817) (xy 188.72588 57.52637) (xy 188.72588 57.53456) (xy 188.72588 57.54276)
			(xy 188.72588 57.55095) (xy 188.72588 57.55914) (xy 188.72588 57.56734) (xy 188.72588 57.57553) (xy 188.72588 57.58373)
			(xy 188.72588 57.59192) (xy 188.72588 57.60011) (xy 188.72588 57.60831) (xy 188.72588 57.61651) (xy 188.72588 57.6247)
			(xy 188.72588 57.63289) (xy 188.72588 57.64109) (xy 188.72588 57.64928) (xy 188.72588 57.65748) (xy 188.72588 57.66567)
			(xy 188.72588 57.67387) (xy 188.72588 57.68206) (xy 188.72588 57.69026) (xy 188.72588 57.69845) (xy 188.72588 57.70664)
			(xy 188.72588 57.71484) (xy 188.72588 57.72303) (xy 188.72588 57.73123) (xy 188.72588 57.73942) (xy 188.72588 57.74762)
			(xy 188.72588 57.75581) (xy 188.72588 57.76401) (xy 188.72588 57.7722) (xy 188.72588 57.7804) (xy 188.72588 57.78859)
			(xy 188.72588 57.79678) (xy 188.72588 57.80498) (xy 188.72588 57.81317) (xy 188.72588 57.82137) (xy 188.72588 57.82956)
			(xy 188.72588 57.83776) (xy 188.72588 57.84595) (xy 188.72588 57.85415) (xy 188.72588 57.86234) (xy 188.72588 57.87053)
			(xy 188.72588 57.87873) (xy 188.72588 57.88692) (xy 188.72588 57.89512) (xy 188.72588 57.90331) (xy 188.72588 57.91151)
			(xy 188.72588 57.9197) (xy 188.72588 57.9279) (xy 188.72588 57.93609) (xy 188.72588 57.94429) (xy 188.72588 57.95248)
			(xy 188.72588 57.96067) (xy 188.72588 57.96887) (xy 188.72588 57.97706) (xy 188.72588 57.98526) (xy 188.72588 57.99345)
			(xy 188.72588 58.00165) (xy 188.72588 58.00984) (xy 188.72588 58.01804) (xy 188.72588 58.02623) (xy 188.72588 58.03442)
			(xy 188.72588 58.04262) (xy 188.72588 58.05081) (xy 188.72588 58.05901) (xy 188.72588 58.0672) (xy 188.72588 58.0754)
			(xy 188.72588 58.08359) (xy 188.72588 58.09178) (xy 188.72588 58.09998) (xy 188.72588 58.10817) (xy 188.72588 58.11637)
			(xy 188.72588 58.12456) (xy 188.72588 58.13276) (xy 188.72588 58.14095) (xy 188.72588 58.14915) (xy 188.72588 58.15734)
			(xy 188.72588 58.16554) (xy 188.72588 58.17373) (xy 188.72588 58.18193) (xy 188.72588 58.19012) (xy 188.72588 58.19831)
			(xy 188.72588 58.20651) (xy 188.72588 58.2147) (xy 188.72588 58.2229) (xy 188.72588 58.23109) (xy 188.72588 58.23929)
			(xy 188.72588 58.24748) (xy 188.72588 58.25568) (xy 188.72588 58.26387) (xy 188.72588 58.27207) (xy 188.72588 58.28026)
			(xy 188.72588 58.28845) (xy 188.72588 58.29665) (xy 188.72588 58.30484) (xy 188.72588 58.31304) (xy 188.72588 58.32123)
			(xy 188.72588 58.32942) (xy 188.72588 58.33762) (xy 188.72588 58.34582) (xy 188.72588 58.35401) (xy 188.72588 58.36221)
			(xy 188.72588 58.3704) (xy 188.72588 58.37859) (xy 188.72588 58.38679) (xy 188.72588 58.39498) (xy 188.72588 58.40318)
			(xy 188.72588 58.41137) (xy 188.72588 58.41957) (xy 188.72588 58.42776) (xy 188.72588 58.43595) (xy 188.72588 58.44415)
			(xy 188.72588 58.45234) (xy 188.72588 58.46054) (xy 188.72588 58.46874) (xy 188.72588 58.47693) (xy 188.72588 58.48512)
			(xy 188.72588 58.49332) (xy 188.72588 58.50151) (xy 188.72588 58.50971) (xy 188.72588 58.5179) (xy 188.72588 58.52609)
			(xy 188.72588 58.53429) (xy 188.72588 58.54248) (xy 188.72588 58.55068) (xy 188.72588 58.55887) (xy 188.72588 58.56707)
			(xy 188.72588 58.57526) (xy 188.72588 58.58345) (xy 188.72588 58.59165) (xy 188.72588 58.59985) (xy 188.72588 58.60804)
			(xy 188.72588 58.61623) (xy 188.72588 58.62443) (xy 188.72588 58.63262) (xy 188.72588 58.64082) (xy 188.72588 58.64901)
			(xy 188.72588 58.65721) (xy 188.72588 58.6654) (xy 188.72588 58.67359) (xy 188.72588 58.68179) (xy 188.72588 58.68998)
			(xy 188.72588 58.69818) (xy 188.72588 58.70637) (xy 188.72588 58.71457) (xy 188.72588 58.72276) (xy 188.72588 58.73096)
			(xy 188.72588 58.73915) (xy 188.72588 58.74735) (xy 188.72588 58.75554) (xy 188.72588 58.76374) (xy 188.72588 58.77193)
			(xy 188.72588 58.78012) (xy 188.72588 58.78832) (xy 188.72588 58.79651) (xy 188.72588 58.80471) (xy 188.72588 58.8129)
			(xy 188.72588 58.82109) (xy 188.72588 58.82929) (xy 188.72588 58.83748) (xy 188.72588 58.84568) (xy 188.72588 58.85387)
			(xy 188.72588 58.86207) (xy 188.72588 58.87026) (xy 188.72588 58.87846) (xy 188.72588 58.88665) (xy 188.72588 58.89485)
			(xy 188.72588 58.90304) (xy 188.72588 58.91124) (xy 188.72588 58.91943) (xy 188.72588 58.92762) (xy 188.72588 58.93582)
			(xy 188.72588 58.94401) (xy 188.72588 58.95221) (xy 188.72588 58.9604) (xy 188.72588 58.9686) (xy 188.72588 58.97679)
			(xy 188.72588 58.98499) (xy 188.72588 58.99318) (xy 188.72588 59.00138) (xy 188.72588 59.00957) (xy 188.72588 59.01776)
			(xy 188.72588 59.02596) (xy 188.72588 59.03415) (xy 188.72588 59.04235) (xy 188.72588 59.05054) (xy 188.72588 59.05874)
			(xy 188.72588 59.06693) (xy 188.72588 59.07513) (xy 188.72588 59.08332) (xy 188.72588 59.09151) (xy 188.72588 59.09971)
			(xy 188.72588 59.1079) (xy 188.72588 59.1161) (xy 188.72588 59.12429) (xy 188.72588 59.13249) (xy 188.72588 59.14068)
			(xy 188.72588 59.14888) (xy 188.72588 59.15707) (xy 188.72588 59.16526) (xy 188.72588 59.17346) (xy 188.72588 59.18165)
			(xy 188.72588 59.18985) (xy 188.72588 59.19805) (xy 188.72588 59.20624) (xy 188.72588 59.21443) (xy 188.72588 59.22263)
			(xy 188.72588 59.23082) (xy 188.72588 59.23902) (xy 188.72588 59.24721) (xy 188.72588 59.2554) (xy 188.72588 59.2636)
			(xy 188.72588 59.27179) (xy 188.72588 59.27999) (xy 188.72588 59.28818) (xy 188.72588 59.29638) (xy 188.72588 59.30457)
			(xy 188.72588 59.31276) (xy 188.72588 59.32096) (xy 188.72588 59.32916) (xy 188.72588 59.33735) (xy 188.72588 59.34554)
			(xy 188.72588 59.35374) (xy 188.72588 59.36193) (xy 188.72588 59.37013) (xy 188.72588 59.37832) (xy 188.72588 59.38652)
			(xy 188.72588 59.39471) (xy 188.72588 59.4029) (xy 188.72588 59.4111) (xy 188.72588 59.41929) (xy 188.72588 59.42749)
			(xy 188.72588 59.43568) (xy 188.72588 59.44388) (xy 188.72588 59.45207) (xy 188.72588 59.46027) (xy 188.72588 59.46846)
			(xy 188.72588 59.47665) (xy 188.72588 59.48485) (xy 188.72588 59.49305) (xy 188.72588 59.50124) (xy 188.72588 59.50943)
			(xy 188.72588 59.51763) (xy 188.72588 59.52582) (xy 188.72588 59.53402) (xy 188.72588 59.54221) (xy 188.72588 59.5504)
			(xy 188.72588 59.5586) (xy 188.72588 59.5668) (xy 188.72588 59.57499) (xy 188.72588 59.58318) (xy 188.72588 59.59138)
			(xy 188.72588 59.59957) (xy 188.72588 59.60777) (xy 188.72588 59.61596) (xy 188.72588 59.62416) (xy 188.72588 59.63235)
			(xy 188.72588 59.64054) (xy 188.72588 59.64874) (xy 188.72588 59.65693) (xy 188.72588 59.66513) (xy 188.72588 59.67332)
			(xy 188.72588 59.68152) (xy 188.72588 59.68971) (xy 188.72588 59.69791) (xy 188.72588 59.7061) (xy 188.72588 59.7143)
			(xy 188.72588 59.72249) (xy 188.72588 59.73069) (xy 188.72588 59.73888) (xy 188.72588 59.74707) (xy 188.72588 59.75527)
			(xy 188.72588 59.76346) (xy 188.72588 59.77166) (xy 188.72588 59.77985) (xy 188.72588 59.78805) (xy 188.72588 59.79624)
			(xy 188.72588 59.80443) (xy 188.72588 59.81263) (xy 188.72588 59.82082) (xy 188.72588 59.82902) (xy 188.72588 59.83721)
			(xy 188.72588 59.84541) (xy 188.72588 59.8536) (xy 188.72588 59.8618) (xy 188.72588 59.86999) (xy 188.72588 59.87819)
			(xy 188.72588 59.88638) (xy 188.72588 59.89457) (xy 188.72588 59.90277) (xy 188.72588 59.91097) (xy 188.72588 59.91916)
			(xy 188.72588 59.92735) (xy 188.72588 59.93555) (xy 188.72588 59.94374) (xy 188.72588 59.95194) (xy 188.72588 59.96013)
			(xy 188.72588 59.96832) (xy 188.72588 59.97652) (xy 188.72588 59.98471) (xy 188.72588 59.99291) (xy 188.72588 60.0011)
			(xy 188.72588 60.0093) (xy 188.72588 60.01749) (xy 188.72588 60.02569) (xy 188.72588 60.03388) (xy 188.72588 60.04207)
			(xy 188.72588 60.05027) (xy 188.72588 60.05846) (xy 188.72588 60.06666) (xy 188.72588 60.07485) (xy 188.72588 60.08305)
			(xy 188.72588 60.09124) (xy 188.72588 60.09944) (xy 188.72588 60.10763) (xy 188.72588 60.11583) (xy 188.72588 60.12402)
			(xy 188.72588 60.13221) (xy 188.72588 60.14041) (xy 188.72588 60.1486) (xy 188.72588 60.1568) (xy 188.72588 60.16499)
			(xy 188.72588 60.17319) (xy 188.72588 60.18138) (xy 188.72588 60.18958) (xy 188.72588 60.19777) (xy 188.72588 60.20597)
			(xy 188.72588 60.21416) (xy 188.72588 60.22236) (xy 188.72588 60.23055) (xy 188.72588 60.23874) (xy 188.72588 60.24694)
			(xy 188.72588 60.25513) (xy 188.72588 60.26333) (xy 188.72588 60.27152) (xy 188.72588 60.27971) (xy 188.72588 60.28791)
			(xy 188.72588 60.29611) (xy 188.72588 60.3043) (xy 188.72588 60.31249) (xy 188.72588 60.32069) (xy 188.72588 60.32888)
			(xy 188.72588 60.33708) (xy 188.72588 60.34527) (xy 188.72588 60.35347) (xy 188.72588 60.36166) (xy 188.72588 60.36985)
			(xy 188.72588 60.37805) (xy 188.72588 60.38624) (xy 188.72588 60.39444) (xy 188.72588 60.40263) (xy 188.72588 60.41083)
			(xy 188.72588 60.41902) (xy 188.72588 60.42722) (xy 188.72588 60.43541) (xy 188.72588 60.44361) (xy 188.72588 60.4518)
			(xy 188.72588 60.46) (xy 188.72588 60.46819) (xy 188.72588 60.47638) (xy 188.72588 60.48458) (xy 188.72588 60.49277)
			(xy 188.72588 60.50097) (xy 188.72588 60.50916) (xy 188.72588 60.51736) (xy 188.72588 60.52555) (xy 188.72588 60.53375)
			(xy 188.72588 60.54194) (xy 188.72588 60.55013) (xy 188.72588 60.55833) (xy 188.72588 60.56652) (xy 188.72588 60.57472)
			(xy 188.72588 60.58291) (xy 188.72588 60.59111) (xy 188.72588 60.5993) (xy 188.72588 60.60749) (xy 188.72588 60.61569)
			(xy 188.72588 60.62388) (xy 188.72588 60.63208) (xy 188.72588 60.64028) (xy 188.72588 60.64847) (xy 188.72588 60.65666)
			(xy 188.72588 60.66486) (xy 188.72588 60.67305) (xy 188.72588 60.68125) (xy 188.72588 60.68944) (xy 188.72588 60.69763)
			(xy 188.72588 60.70583) (xy 188.72588 60.71402) (xy 188.72588 60.72222) (xy 188.72588 60.73041) (xy 188.72588 60.73861)
			(xy 188.72588 60.7468) (xy 188.72588 60.755) (xy 188.72588 60.76319) (xy 188.72588 60.77139) (xy 188.72588 60.77958)
			(xy 188.72588 60.78777) (xy 188.72588 60.79597) (xy 188.72588 60.80416) (xy 188.42269 60.80416) (xy 188.42269 60.79597)
			(xy 188.42269 60.78777) (xy 188.42269 60.77958) (xy 188.42269 60.77139) (xy 188.42269 60.76319) (xy 188.42269 60.755)
			(xy 188.42269 60.7468) (xy 188.42269 60.73861) (xy 188.42269 60.73041) (xy 188.42269 60.72222) (xy 188.42269 60.71402)
			(xy 188.42269 60.70583) (xy 188.42269 60.69763) (xy 188.42269 60.68944) (xy 188.42269 60.68125) (xy 188.42269 60.67305)
			(xy 188.42269 60.66486) (xy 188.42269 60.65666) (xy 188.42269 60.64847) (xy 188.42269 60.64028) (xy 188.42269 60.63208)
			(xy 188.42269 60.62388) (xy 188.42269 60.61569) (xy 188.42269 60.60749) (xy 188.42269 60.5993) (xy 188.42269 60.59111)
			(xy 188.42269 60.58291) (xy 188.42269 60.57472) (xy 188.42269 60.56652) (xy 188.42269 60.55833) (xy 188.42269 60.55013)
			(xy 188.42269 60.54194) (xy 188.42269 60.53375) (xy 188.42269 60.52555) (xy 188.42269 60.51736) (xy 188.42269 60.50916)
			(xy 188.42269 60.50097) (xy 188.42269 60.49277) (xy 188.42269 60.48458) (xy 188.42269 60.47638) (xy 188.42269 60.46819)
			(xy 188.42269 60.46) (xy 188.42269 60.4518) (xy 188.42269 60.44361) (xy 188.42269 60.43541) (xy 188.42269 60.42722)
			(xy 188.42269 60.41902) (xy 188.42269 60.41083) (xy 188.42269 60.40263) (xy 188.42269 60.39444) (xy 188.42269 60.38624)
			(xy 188.42269 60.37805) (xy 188.42269 60.36985) (xy 188.42269 60.36166) (xy 188.42269 60.35347) (xy 188.42269 60.34527)
			(xy 188.42269 60.33708) (xy 188.42269 60.32888) (xy 188.42269 60.32069) (xy 188.42269 60.31249) (xy 188.42269 60.3043)
			(xy 188.42269 60.29611) (xy 188.42269 60.28791) (xy 188.42269 60.27971) (xy 188.42269 60.27152) (xy 188.42269 60.26333)
			(xy 188.42269 60.25513) (xy 188.42269 60.24694) (xy 188.42269 60.23874) (xy 188.42269 60.23055) (xy 188.42269 60.22236)
			(xy 188.42269 60.21416) (xy 188.42269 60.20597) (xy 188.42269 60.19777) (xy 188.42269 60.18958) (xy 188.42269 60.18138)
			(xy 188.42269 60.17319) (xy 188.42269 60.16499) (xy 188.42269 60.1568) (xy 188.42269 60.1486) (xy 188.42269 60.14041)
			(xy 188.42269 60.13221) (xy 188.42269 60.12402) (xy 188.42269 60.11583) (xy 188.42269 60.10763) (xy 188.42269 60.09944)
			(xy 188.42269 60.09124) (xy 188.42269 60.08305) (xy 188.42269 60.07485) (xy 188.42269 60.06666) (xy 188.42269 60.05846)
			(xy 188.42269 60.05027) (xy 188.42269 60.04207) (xy 188.42269 60.03388) (xy 188.42269 60.02569) (xy 188.42269 60.01749)
			(xy 188.42269 60.0093) (xy 188.42269 60.0011) (xy 188.42269 59.99291) (xy 188.42269 59.98471) (xy 188.42269 59.97652)
			(xy 188.42269 59.96832) (xy 188.42269 59.96013) (xy 188.42269 59.95194) (xy 188.42269 59.94374) (xy 188.42269 59.93555)
			(xy 188.42269 59.92735) (xy 188.42269 59.91916) (xy 188.42269 59.91097) (xy 188.42269 59.90277) (xy 188.42269 59.89457)
			(xy 188.42269 59.88638) (xy 188.42269 59.87819) (xy 188.42269 59.86999) (xy 188.42269 59.8618) (xy 188.42269 59.8536)
			(xy 188.42269 59.84541) (xy 188.42269 59.83721) (xy 188.42269 59.82902) (xy 188.42269 59.82082) (xy 188.42269 59.81263)
			(xy 188.42269 59.80443) (xy 188.42269 59.79624) (xy 188.42269 59.78805) (xy 188.42269 59.77985) (xy 188.42269 59.77166)
			(xy 188.42269 59.76346) (xy 188.42269 59.75527) (xy 188.42269 59.74707) (xy 188.42269 59.73888) (xy 188.42269 59.73069)
			(xy 188.42269 59.72249) (xy 188.42269 59.7143) (xy 188.42269 59.7061) (xy 188.42269 59.69791) (xy 188.42269 59.68971)
			(xy 188.42269 59.68152) (xy 188.42269 59.67332) (xy 188.42269 59.66513) (xy 188.42269 59.65693) (xy 188.42269 59.64874)
			(xy 188.42269 59.64054) (xy 188.42269 59.63235) (xy 188.42269 59.62416) (xy 188.42269 59.61596) (xy 188.42269 59.60777)
			(xy 188.42269 59.59957) (xy 188.42269 59.59138) (xy 188.42269 59.58318) (xy 188.42269 59.57499) (xy 188.42269 59.5668)
			(xy 188.42269 59.5586) (xy 188.42269 59.5504) (xy 188.42269 59.54221) (xy 188.42269 59.53402) (xy 188.42269 59.52582)
			(xy 188.42269 59.51763) (xy 188.42269 59.50943) (xy 188.42269 59.50124) (xy 188.42269 59.49305) (xy 188.42269 59.48485)
			(xy 188.42269 59.47665) (xy 188.42269 59.46846) (xy 188.42269 59.46027) (xy 188.42269 59.45207) (xy 188.42269 59.44388)
			(xy 188.42269 59.43568) (xy 188.42269 59.42749) (xy 188.42269 59.41929) (xy 188.42269 59.4111) (xy 188.42269 59.4029)
			(xy 188.42269 59.39471) (xy 188.42269 59.38652) (xy 188.42269 59.37832) (xy 188.42269 59.37013) (xy 188.42269 59.36193)
			(xy 188.42269 59.35374) (xy 188.42269 59.34554) (xy 188.42269 59.33735) (xy 188.42269 59.32916) (xy 188.42269 59.32096)
			(xy 188.42269 59.31276) (xy 188.42269 59.30457) (xy 188.42269 59.29638) (xy 188.42269 59.28818) (xy 188.42269 59.27999)
			(xy 188.42269 59.27179) (xy 188.42269 59.2636) (xy 188.42269 59.2554) (xy 188.42269 59.24721) (xy 188.42269 59.23902)
			(xy 188.42269 59.23082) (xy 188.42269 59.22263) (xy 188.42269 59.21443) (xy 188.42269 59.20624) (xy 188.42269 59.19805)
			(xy 188.42269 59.18985) (xy 188.42269 59.18165) (xy 188.42269 59.17346) (xy 188.42269 59.16526) (xy 188.42269 59.15707)
			(xy 188.42269 59.14888) (xy 188.42269 59.14068) (xy 188.42269 59.13249) (xy 188.42269 59.12429) (xy 188.42269 59.1161)
			(xy 188.42269 59.1079) (xy 188.42269 59.09971) (xy 188.42269 59.09151) (xy 188.42269 59.08332) (xy 188.42269 59.07513)
			(xy 188.42269 59.06693) (xy 188.42269 59.05874) (xy 188.42269 59.05054) (xy 188.42269 59.04235) (xy 188.42269 59.03415)
			(xy 188.42269 59.02596) (xy 188.42269 59.01776) (xy 188.42269 59.00957) (xy 188.42269 59.00138) (xy 188.42269 58.99318)
			(xy 188.42269 58.98499) (xy 188.42269 58.97679) (xy 188.42269 58.9686) (xy 188.42269 58.9604) (xy 188.42269 58.95221)
			(xy 188.42269 58.94401) (xy 188.42269 58.93582) (xy 188.42269 58.92762) (xy 188.42269 58.91943) (xy 188.42269 58.91124)
			(xy 188.42269 58.90304) (xy 188.42269 58.89485) (xy 188.42269 58.88665) (xy 188.42269 58.87846) (xy 188.42269 58.87026)
			(xy 188.42269 58.86207) (xy 188.42269 58.85387) (xy 188.42269 58.84568) (xy 188.42269 58.83748) (xy 188.42269 58.82929)
			(xy 188.42269 58.82109) (xy 188.42269 58.8129) (xy 188.42269 58.80471) (xy 188.42269 58.79651) (xy 188.42269 58.78832)
			(xy 188.42269 58.78012) (xy 188.42269 58.77193) (xy 188.42269 58.76374) (xy 188.42269 58.75554) (xy 188.42269 58.74735)
			(xy 188.42269 58.73915) (xy 188.42269 58.73096) (xy 188.42269 58.72276) (xy 188.42269 58.71457) (xy 188.42269 58.70637)
			(xy 188.42269 58.69818) (xy 188.42269 58.68998) (xy 188.42269 58.68179) (xy 188.42269 58.67359) (xy 188.42269 58.6654)
			(xy 188.42269 58.65721) (xy 188.42269 58.64901) (xy 188.42269 58.64082) (xy 188.42269 58.63262) (xy 188.42269 58.62443)
			(xy 188.42269 58.61623) (xy 188.42269 58.60804) (xy 188.42269 58.59985) (xy 188.42269 58.59165) (xy 188.42269 58.58345)
			(xy 188.42269 58.57526) (xy 188.42269 58.56707) (xy 188.42269 58.55887) (xy 188.42269 58.55068) (xy 188.42269 58.54248)
			(xy 188.42269 58.53429) (xy 188.42269 58.52609) (xy 188.42269 58.5179) (xy 188.42269 58.50971) (xy 188.42269 58.50151)
			(xy 188.42269 58.49332) (xy 188.42269 58.48512) (xy 188.42269 58.47693) (xy 188.42269 58.46874) (xy 188.42269 58.46054)
			(xy 188.42269 58.45234) (xy 188.42269 58.44415) (xy 188.42269 58.43595) (xy 188.42269 58.42776) (xy 188.42269 58.41957)
			(xy 188.42269 58.41137) (xy 188.42269 58.40318) (xy 188.42269 58.39498) (xy 188.42269 58.38679) (xy 188.42269 58.37859)
			(xy 188.42269 58.3704) (xy 188.42269 58.36221) (xy 188.42269 58.35401) (xy 188.42269 58.34582) (xy 188.42269 58.33762)
			(xy 188.42269 58.32942) (xy 188.42269 58.32123) (xy 188.42269 58.31304) (xy 188.42269 58.30484) (xy 188.42269 58.29665)
			(xy 188.42269 58.28845) (xy 188.42269 58.28026) (xy 188.42269 58.27207) (xy 188.42269 58.26387) (xy 188.42269 58.25568)
			(xy 188.42269 58.24748) (xy 188.42269 58.23929) (xy 188.42269 58.23109) (xy 188.42269 58.2229) (xy 188.42269 58.2147)
			(xy 188.42269 58.20651) (xy 188.42269 58.19831) (xy 188.42269 58.19012) (xy 188.42269 58.18193) (xy 188.42269 58.17373)
			(xy 188.42269 58.16554) (xy 188.42269 58.15734) (xy 188.42269 58.14915) (xy 188.42269 58.14095) (xy 188.42269 58.13276)
			(xy 188.42269 58.12456) (xy 188.42269 58.11637) (xy 188.42269 58.10817) (xy 188.42269 58.09998) (xy 188.42269 58.09178)
			(xy 188.42269 58.08359) (xy 188.42269 58.0754) (xy 188.42269 58.0672) (xy 188.42269 58.05901) (xy 188.42269 58.05081)
			(xy 188.42269 58.04262) (xy 188.42269 58.03442) (xy 188.42269 58.02623) (xy 188.42269 58.01804) (xy 188.42269 58.00984)
			(xy 188.42269 58.00165) (xy 188.42269 57.99345) (xy 188.42269 57.98526) (xy 188.42269 57.97706) (xy 188.42269 57.96887)
			(xy 188.42269 57.96067) (xy 188.42269 57.95248) (xy 188.42269 57.94429) (xy 188.42269 57.93609) (xy 188.42269 57.9279)
			(xy 188.42269 57.9197) (xy 188.42269 57.91151) (xy 188.42269 57.90331) (xy 188.42269 57.89512) (xy 188.42269 57.88692)
			(xy 188.42269 57.87873) (xy 188.42269 57.87053) (xy 188.42269 57.86234) (xy 188.42269 57.85415) (xy 188.42269 57.84595)
			(xy 188.42269 57.83776) (xy 188.42269 57.82956) (xy 188.42269 57.82137) (xy 188.42269 57.81317) (xy 188.42269 57.80498)
			(xy 188.42269 57.79678) (xy 188.42269 57.78859) (xy 188.42269 57.7804) (xy 188.42269 57.7722) (xy 188.42269 57.76401)
			(xy 188.42269 57.75581) (xy 188.42269 57.74762) (xy 188.42269 57.73942) (xy 188.42269 57.73123) (xy 188.42269 57.72303)
			(xy 188.42269 57.71484) (xy 188.42269 57.70664) (xy 188.42269 57.69845) (xy 188.42269 57.69026) (xy 188.42269 57.68206)
			(xy 188.42269 57.67387) (xy 188.42269 57.66567) (xy 188.42269 57.65748) (xy 188.42269 57.64928) (xy 188.42269 57.64109)
			(xy 188.42269 57.63289) (xy 188.42269 57.6247) (xy 188.42269 57.61651) (xy 188.42269 57.60831) (xy 188.42269 57.60011)
			(xy 188.42269 57.59192) (xy 188.42269 57.58373) (xy 188.42269 57.57553) (xy 188.42269 57.56734) (xy 188.42269 57.55914)
			(xy 188.42269 57.55095) (xy 188.42269 57.54276) (xy 188.42269 57.53456) (xy 188.42269 57.52637) (xy 188.42269 57.51817)
			(xy 188.42269 57.50998) (xy 188.42269 57.50178) (xy 188.42269 57.49359) (xy 188.42269 57.48539) (xy 188.42269 57.4772)
			(xy 188.42269 57.469) (xy 188.42269 57.46081) (xy 188.42269 57.45262) (xy 188.42269 57.44442) (xy 188.42269 57.43623)
			(xy 188.42269 57.42803) (xy 188.42269 57.41984) (xy 188.42269 57.41164) (xy 188.42269 57.40345) (xy 188.42269 57.39526)
			(xy 188.42269 57.38706) (xy 188.42269 57.37886) (xy 188.42269 57.37067) (xy 188.42269 57.36248) (xy 188.42269 57.35428)
			(xy 188.42269 57.34609) (xy 188.42269 57.33789) (xy 188.42269 57.3297) (xy 188.42269 57.3215) (xy 188.42269 57.31331)
			(xy 188.42269 57.30511) (xy 188.42269 57.29692) (xy 188.42269 57.28872) (xy 188.42269 57.28053) (xy 188.42269 57.27234)
			(xy 188.42269 57.26414) (xy 188.42269 57.25595) (xy 188.42269 57.24775) (xy 188.42269 57.23956) (xy 188.42269 57.23136)
			(xy 188.42269 57.22317) (xy 188.42269 57.21498) (xy 188.42269 57.20678) (xy 188.42269 57.19859) (xy 188.42269 57.19039)
			(xy 188.42269 57.18219) (xy 188.42269 57.174) (xy 188.42269 57.16581) (xy 188.42269 57.15761) (xy 188.42269 57.14942)
			(xy 188.42269 57.14122) (xy 188.42269 57.13303) (xy 188.42269 57.12484) (xy 188.42269 57.11664) (xy 188.42269 57.10845)
			(xy 188.42269 57.10025) (xy 188.42269 57.09206) (xy 188.42269 57.08386) (xy 188.42269 57.07567) (xy 188.42269 57.06747)
			(xy 188.42269 57.05928) (xy 188.42269 57.05109) (xy 188.42269 57.04289) (xy 188.42269 57.0347) (xy 188.42269 57.0265)
			(xy 188.42269 57.01831) (xy 188.42269 57.01011) (xy 188.42269 57.00192) (xy 188.42269 56.99372) (xy 188.42269 56.98553)
			(xy 188.42269 56.97734) (xy 188.42269 56.96914) (xy 188.42269 56.96095) (xy 188.42269 56.95275) (xy 188.42269 56.94455)
			(xy 188.42269 56.93636) (xy 188.42269 56.92817) (xy 188.42269 56.91997) (xy 188.42269 56.91178) (xy 188.42269 56.90358)
			(xy 188.42269 56.89539) (xy 188.42269 56.88719) (xy 188.42269 56.879) (xy 188.42269 56.87081) (xy 188.42269 56.86261)
			(xy 188.42269 56.85442) (xy 188.42269 56.84622) (xy 188.42269 56.83803) (xy 188.42269 56.82983) (xy 188.42269 56.82164)
			(xy 188.42269 56.81345) (xy 188.42269 56.80525) (xy 188.42269 56.79706) (xy 188.42269 56.78886) (xy 188.42269 56.78067)
			(xy 188.42269 56.77247) (xy 188.42269 56.76428) (xy 188.42269 56.75608) (xy 188.42269 56.74789) (xy 188.42269 56.73969)
			(xy 188.42269 56.7315) (xy 188.42269 56.72331) (xy 188.42269 56.71511) (xy 188.42269 56.70692) (xy 188.42269 56.69872)
			(xy 188.42269 56.69053) (xy 188.42269 56.68233) (xy 188.42269 56.67414) (xy 188.42269 56.66594) (xy 188.42269 56.65775)
			(xy 188.42269 56.64955) (xy 188.42269 56.64136) (xy 188.42269 56.63317) (xy 188.42269 56.62497) (xy 188.42269 56.61678)
			(xy 188.42269 56.60858) (xy 188.42269 56.60039) (xy 188.42269 56.59219) (xy 188.42269 56.584) (xy 188.42269 56.5758)
			(xy 188.42269 56.56761) (xy 188.42269 56.55942) (xy 188.42269 56.55122) (xy 188.42269 56.54303) (xy 188.42269 56.53483)
			(xy 188.42269 56.52664) (xy 188.42269 56.51844) (xy 188.42269 56.51025) (xy 188.42269 56.50205) (xy 188.42269 56.49386)
			(xy 188.42269 56.48567) (xy 188.42269 56.47747) (xy 188.42269 56.46928) (xy 188.42269 56.46108) (xy 188.42269 56.45289)
			(xy 188.42269 56.44469) (xy 188.42269 56.4365) (xy 188.42269 56.42831) (xy 188.42269 56.42011) (xy 188.42269 56.41191)
			(xy 188.42269 56.40372) (xy 188.42269 56.39553) (xy 188.42269 56.38733) (xy 188.42269 56.37914) (xy 188.42269 56.37094)
			(xy 188.42269 56.36275) (xy 188.42269 56.35455) (xy 188.42269 56.34636) (xy 188.42269 56.33816) (xy 188.42269 56.32997)
			(xy 188.42269 56.32177) (xy 188.42269 56.31358) (xy 188.42269 56.30539) (xy 188.42269 56.29719) (xy 188.42269 56.289)
			(xy 188.42269 56.2808) (xy 188.42269 56.27261) (xy 188.42269 56.26441) (xy 188.42269 56.25622) (xy 188.42269 56.24803)
			(xy 188.42269 56.23983) (xy 188.42269 56.23164) (xy 188.42269 56.22344) (xy 188.42269 56.21524) (xy 188.42269 56.20705)
			(xy 188.42269 56.19886) (xy 188.42269 56.19066) (xy 188.42269 56.18247) (xy 188.42269 56.17427) (xy 188.42269 56.16608)
			(xy 188.42269 56.15788) (xy 188.42269 56.14969) (xy 188.42269 56.1415) (xy 188.42269 56.1333) (xy 188.42269 56.12511)
			(xy 188.42269 56.11691) (xy 188.42269 56.10872) (xy 188.42269 56.10053) (xy 188.42269 56.09233) (xy 188.42269 56.08413)
			(xy 188.42269 56.07594) (xy 188.42269 56.06775) (xy 188.42269 56.05955) (xy 188.42269 56.05136) (xy 188.42269 56.04316)
			(xy 188.42269 56.03497) (xy 188.42269 56.02677) (xy 188.42269 56.01858) (xy 188.42269 56.01039) (xy 188.42269 56.00219)
			(xy 188.42269 55.994) (xy 188.42269 55.9858) (xy 188.42269 55.97761) (xy 188.42269 55.96941) (xy 188.42269 55.96122)
			(xy 188.42269 55.95302) (xy 188.42269 55.94483) (xy 188.42269 55.93663) (xy 188.42269 55.92844) (xy 188.42269 55.92024)
			(xy 188.42269 55.91205) (xy 188.42269 55.90386) (xy 188.42269 55.89566) (xy 188.42269 55.88747) (xy 188.42269 55.87927)
			(xy 188.42269 55.87108) (xy 188.42269 55.86288) (xy 188.42269 55.85469) (xy 188.42269 55.84649) (xy 188.42269 55.8383)
			(xy 188.42269 55.83011) (xy 188.42269 55.82191) (xy 188.42269 55.81372) (xy 188.42269 55.80552) (xy 188.42269 55.79733)
			(xy 188.42269 55.78913) (xy 188.42269 55.78094) (xy 188.42269 55.77274) (xy 188.42269 55.76455) (xy 188.42269 55.75636)
			(xy 188.42269 55.74816) (xy 188.42269 55.73997) (xy 188.42269 55.73177) (xy 188.42269 55.72358) (xy 188.42269 55.71538)
			(xy 188.42269 55.70719) (xy 188.42269 55.69899) (xy 188.42269 55.6908) (xy 188.42269 55.6826) (xy 188.42269 55.67441)
			(xy 188.42269 55.66622) (xy 188.42269 55.65802) (xy 188.42269 55.64983) (xy 188.42269 55.64163) (xy 188.42269 55.63344)
			(xy 188.42269 55.62524) (xy 188.42269 55.61705) (xy 188.42269 55.60885) (xy 188.42269 55.60066) (xy 188.42269 55.59247)
			(xy 188.42269 55.58427) (xy 188.42269 55.57608) (xy 188.42269 55.56788) (xy 188.42269 55.55969) (xy 188.42269 55.55149)
			(xy 188.42269 55.5433) (xy 188.42269 55.5351) (xy 188.42269 55.52691) (xy 188.42269 55.51872) (xy 188.42269 55.51052)
			(xy 188.42269 55.50233) (xy 188.42269 55.49413) (xy 188.42269 55.48594) (xy 188.42269 55.47774) (xy 188.42269 55.46955)
			(xy 188.42269 55.46136) (xy 188.42269 55.45316) (xy 188.42269 55.44496) (xy 188.42269 55.43677) (xy 188.42269 55.42857)
			(xy 188.42269 55.42038) (xy 188.42269 55.41219) (xy 188.42269 55.40399) (xy 188.42269 55.3958) (xy 188.42269 55.3876)
			(xy 188.42269 55.37941) (xy 188.42269 55.37122) (xy 188.42269 55.36302) (xy 188.42269 55.35482) (xy 188.42269 55.34663)
			(xy 188.42269 55.33844) (xy 188.42269 55.33024) (xy 188.42269 55.32205) (xy 188.42269 55.31385) (xy 188.42269 55.30566)
			(xy 188.42269 55.29746) (xy 188.42269 55.28927) (xy 188.42269 55.28108) (xy 188.42269 55.27288) (xy 188.42269 55.26469)
			(xy 188.42269 55.25649) (xy 188.42269 55.2483) (xy 188.42269 55.2401) (xy 188.42269 55.23191) (xy 188.42269 55.22371)
			(xy 188.42269 55.21552) (xy 188.42269 55.20732) (xy 188.42269 55.19913) (xy 188.42269 55.19093) (xy 188.42269 55.18274)
			(xy 188.42269 55.17455) (xy 188.42269 55.16635) (xy 188.42269 55.15816) (xy 188.42269 55.14996) (xy 188.42269 55.14177)
			(xy 188.42269 55.13357) (xy 188.42269 55.12538) (xy 188.42269 55.11718) (xy 188.42269 55.10899) (xy 188.42269 55.1008)
			(xy 188.42269 55.0926) (xy 188.42269 55.08441) (xy 188.42269 55.07621) (xy 188.42269 55.06802) (xy 188.42269 55.05982)
			(xy 188.42269 55.05163) (xy 188.42269 55.04344) (xy 188.42269 55.03524) (xy 188.42269 55.02705) (xy 188.42269 55.01885)
			(xy 188.42269 55.01065) (xy 188.42269 55.00246) (xy 188.42269 54.99427) (xy 188.42269 54.98607) (xy 188.42269 54.97788)
			(xy 188.42269 54.96968) (xy 188.42269 54.96149) (xy 188.42269 54.95329) (xy 188.42269 54.9451) (xy 188.42269 54.93691)
			(xy 188.42269 54.92871) (xy 188.42269 54.92052) (xy 188.42269 54.91232) (xy 188.42269 54.90413) (xy 188.42269 54.89593)
			(xy 188.42269 54.88774) (xy 188.42269 54.87955) (xy 188.42269 54.87135) (xy 188.42269 54.86316) (xy 188.42269 54.85496)
			(xy 188.42269 54.84677) (xy 188.42269 54.83857) (xy 188.42269 54.83038) (xy 188.42269 54.82218) (xy 188.42269 54.81399)
			(xy 188.42269 54.80579) (xy 188.42269 54.7976) (xy 188.42269 54.78941) (xy 188.42269 54.78121) (xy 188.42269 54.77302)
			(xy 188.42269 54.76482) (xy 188.42269 54.75663) (xy 188.42269 54.74843) (xy 188.42269 54.74024) (xy 188.42269 54.73204)
			(xy 188.42269 54.72385) (xy 188.42269 54.71565) (xy 188.42269 54.70746) (xy 188.42269 54.69926) (xy 188.42269 54.69107)
			(xy 188.42269 54.68288) (xy 188.42269 54.67468) (xy 188.42269 54.66649) (xy 188.42269 54.65829) (xy 188.42269 54.6501)
			(xy 188.42269 54.6419) (xy 188.42269 54.63371) (xy 188.42269 54.62551) (xy 188.42269 54.61732) (xy 188.42269 54.60913)
			(xy 188.42269 54.60093) (xy 188.42269 54.59274) (xy 188.42269 54.58454) (xy 188.42269 54.57635) (xy 188.42269 54.56815)
			(xy 188.42269 54.55996) (xy 188.42269 54.55176) (xy 188.42269 54.54357) (xy 188.42269 54.53538) (xy 188.42269 54.52718)
			(xy 188.42269 54.51899) (xy 188.42269 54.51079) (xy 188.42269 54.5026) (xy 188.42269 54.4944) (xy 188.42269 54.48621)
			(xy 188.42269 54.47801) (xy 188.42269 54.46982) (xy 188.42269 54.46162) (xy 188.42269 54.45343) (xy 188.42269 54.44524)
			(xy 188.42269 54.43704) (xy 188.42269 54.42885) (xy 188.42269 54.42065) (xy 188.42269 54.41246) (xy 188.42269 54.40426)
			(xy 188.42269 54.39607) (xy 188.42269 54.38787) (xy 188.42269 54.37968) (xy 188.42269 54.37149) (xy 188.42269 54.36329)
			(xy 188.42269 54.3551) (xy 188.42269 54.3469) (xy 188.42269 54.33871) (xy 188.42269 54.33051) (xy 188.42269 54.32232)
			(xy 188.42269 54.31413) (xy 188.42269 54.30593) (xy 188.42269 54.29774) (xy 188.42269 54.28954) (xy 188.42269 54.28134)
			(xy 188.42269 54.27315) (xy 188.42269 54.26496) (xy 188.42269 54.25676) (xy 188.42269 54.24857) (xy 188.42269 54.24037)
			(xy 188.42269 54.23218) (xy 188.42269 54.22398) (xy 188.42269 54.21579) (xy 188.42269 54.2076) (xy 188.42269 54.1994)
			(xy 188.42269 54.19121) (xy 188.42269 54.18301) (xy 188.42269 54.17482) (xy 188.42269 54.16662) (xy 188.42269 54.15843)
			(xy 188.42269 54.15023) (xy 188.42269 54.14204) (xy 188.42269 54.13385) (xy 188.42269 54.12565) (xy 188.42269 54.11746)
			(xy 188.42269 54.10926) (xy 188.42269 54.10107) (xy 188.42269 54.09287) (xy 188.42269 54.08468) (xy 188.42269 54.07649)
			(xy 188.42269 54.06829) (xy 188.42269 54.0601) (xy 188.42269 54.0519) (xy 188.42269 54.0437) (xy 188.42269 54.03551)
			(xy 188.42269 54.02732) (xy 188.42269 54.01912) (xy 188.42269 54.01093) (xy 188.42269 54.00273) (xy 188.42269 53.99454)
			(xy 188.42269 53.98634) (xy 188.42269 53.97815) (xy 188.42269 53.96996) (xy 188.42269 53.96176) (xy 188.42269 53.95357)
			(xy 188.42269 53.94537) (xy 188.42269 53.93718) (xy 188.42269 53.92898) (xy 188.42269 53.92079) (xy 188.42269 53.91259)
			(xy 188.42269 53.9044) (xy 188.42269 53.8962) (xy 188.42269 53.88801) (xy 188.42269 53.87982) (xy 188.42269 53.87162)
			(xy 188.42269 53.86343) (xy 188.42269 53.85523) (xy 188.42269 53.84704) (xy 188.42269 53.83884) (xy 188.42269 53.83065)
			(xy 188.42269 53.82246) (xy 188.42269 53.81426) (xy 188.42269 53.80606) (xy 188.42269 53.79787) (xy 188.42269 53.78968)
			(xy 188.42269 53.78148) (xy 188.42269 53.77329) (xy 188.42269 53.76509) (xy 188.42269 53.7569) (xy 188.42269 53.7487)
			(xy 188.42269 53.74051) (xy 188.42269 53.73231) (xy 188.42269 53.72412) (xy 188.42269 53.71593) (xy 188.42269 53.70773)
			(xy 188.42269 53.69954) (xy 188.42269 53.69134) (xy 188.42269 53.68315) (xy 188.42269 53.67495) (xy 188.42269 53.66676)
			(xy 188.42269 53.65857) (xy 188.42269 53.65037) (xy 188.42269 53.64218) (xy 188.42269 53.63398) (xy 188.42269 53.62579)
			(xy 188.42269 53.61759) (xy 188.42269 53.6094) (xy 188.42269 53.6012) (xy 188.42269 53.59301) (xy 188.42269 53.58482)
			(xy 188.42269 53.57662) (xy 188.42269 53.56843) (xy 188.42269 53.56023) (xy 188.42269 53.55204) (xy 188.42269 53.54384)
			(xy 188.42269 53.53565) (xy 188.42269 53.52745) (xy 188.42269 53.51926) (xy 188.42269 53.51106) (xy 188.42269 53.50287)
			(xy 188.42269 53.49467) (xy 188.42269 53.48648) (xy 188.42269 53.47829) (xy 188.42269 53.47009) (xy 188.42269 53.4619)
			(xy 188.42269 53.4537) (xy 188.42269 53.44551) (xy 188.42269 53.43731) (xy 188.42269 53.42912) (xy 188.42269 53.42092)
			(xy 188.42269 53.41273) (xy 188.42269 53.40453) (xy 188.42269 53.39634) (xy 188.42269 53.38815) (xy 188.42269 53.37995)
			(xy 188.42269 53.37176) (xy 188.42269 53.36356) (xy 188.42269 53.35537) (xy 188.42269 53.34718) (xy 188.42269 53.33898)
			(xy 188.42269 53.33079) (xy 188.42269 53.32259) (xy 188.42269 53.31439) (xy 188.42269 53.3062) (xy 188.42269 53.29801)
			(xy 188.42269 53.28981) (xy 188.42269 53.28162) (xy 188.42269 53.27342) (xy 188.42269 53.26523) (xy 188.42269 53.25703)
			(xy 188.42269 53.24884) (xy 188.42269 53.24065) (xy 188.42269 53.23245) (xy 188.42269 53.22426) (xy 188.42269 53.21606)
			(xy 188.42269 53.20787) (xy 188.42269 53.19967) (xy 188.42269 53.19148) (xy 188.42269 53.18328) (xy 188.42269 53.17509)
			(xy 188.42269 53.16689) (xy 188.42269 53.1587) (xy 188.42269 53.15051) (xy 188.42269 53.14231) (xy 188.42269 53.13412)
			(xy 188.42269 53.12592) (xy 188.42269 53.11773) (xy 188.42269 53.10953) (xy 188.42269 53.10134) (xy 188.42269 53.09315)
			(xy 188.42269 53.08495) (xy 188.42269 53.07675) (xy 188.42269 53.06856) (xy 188.42269 53.06037) (xy 188.42269 53.05217)
			(xy 188.42269 53.04398) (xy 188.42269 53.03578) (xy 188.42269 53.02759) (xy 188.42269 53.01939) (xy 188.42269 53.0112)
			(xy 188.42269 53.00301) (xy 188.42269 52.99481) (xy 188.42269 52.98662) (xy 188.42269 52.97842) (xy 188.42269 52.97023)
			(xy 188.42269 52.96203) (xy 188.42269 52.95384) (xy 188.42269 52.94564) (xy 188.42269 52.93745) (xy 188.42269 52.92926)
			(xy 188.42269 52.92106) (xy 188.42269 52.91287) (xy 188.42269 52.90467) (xy 188.42269 52.89648) (xy 188.42269 52.88828)
			(xy 188.42269 52.88009) (xy 188.42269 52.87189) (xy 188.42269 52.8637) (xy 188.42269 52.85551) (xy 188.42269 52.84731)
			(xy 188.42269 52.83911) (xy 188.42269 52.83092) (xy 188.42269 52.82273) (xy 188.42269 52.81453) (xy 188.42269 52.80634)
			(xy 188.42269 52.79814) (xy 188.42269 52.78995) (xy 188.42269 52.78175) (xy 188.42269 52.77356) (xy 188.42269 52.76536)
			(xy 188.42269 52.75717) (xy 188.42269 52.74898) (xy 188.42269 52.74078) (xy 188.42269 52.73259) (xy 188.42269 52.72439)
			(xy 188.42269 52.7162) (xy 188.42269 52.708) (xy 188.42269 52.69981) (xy 188.42269 52.69162) (xy 188.42269 52.68342)
			(xy 188.42269 52.67522) (xy 188.42269 52.66703) (xy 188.42269 52.65884) (xy 188.42269 52.65064) (xy 188.42269 52.64245)
			(xy 188.42269 52.63425) (xy 188.42269 52.62606) (xy 188.42269 52.61787) (xy 188.42269 52.60967) (xy 188.42269 52.60148)
			(xy 188.42269 52.59328) (xy 188.42269 52.58509) (xy 188.42269 52.57689) (xy 188.42269 52.5687) (xy 188.42269 52.5605)
			(xy 188.42269 52.55231) (xy 188.42269 52.54411) (xy 188.42269 52.53592) (xy 188.42269 52.52772) (xy 188.42269 52.51953)
			(xy 188.42269 52.51134) (xy 188.42269 52.50314) (xy 188.42269 52.49495) (xy 188.42269 52.48675) (xy 188.42269 52.47856)
			(xy 188.42269 52.47036) (xy 188.42269 52.46217) (xy 188.42269 52.45397) (xy 188.42269 52.44578) (xy 188.42269 52.43759)
			(xy 188.42269 52.42939) (xy 188.42269 52.4212) (xy 188.42269 52.413) (xy 188.42269 52.40481) (xy 188.42269 52.39661)
			(xy 188.42269 52.38842) (xy 188.42269 52.38022) (xy 188.42269 52.37203) (xy 188.42269 52.36384) (xy 188.42269 52.35564)
			(xy 188.42269 52.34744) (xy 188.42269 52.33925) (xy 188.42269 52.33106) (xy 188.42269 52.32286) (xy 188.42269 52.31467)
			(xy 188.42269 52.30647) (xy 188.42269 52.29828) (xy 188.42269 52.29008) (xy 188.42269 52.28189) (xy 188.42269 52.2737)
			(xy 188.42269 52.2655) (xy 188.42269 52.25731) (xy 188.42269 52.24911) (xy 188.42269 52.24092) (xy 188.42269 52.23272)
			(xy 188.42269 52.22453) (xy 188.42269 52.21633) (xy 188.42269 52.20814) (xy 188.42269 52.19995) (xy 188.42269 52.19175)
			(xy 188.42269 52.18356) (xy 188.42269 52.17536) (xy 188.42269 52.16717) (xy 188.42269 52.15897) (xy 188.42269 52.15078)
			(xy 188.42269 52.14258) (xy 188.42269 52.13439) (xy 188.42269 52.1262) (xy 188.42269 52.118) (xy 188.42269 52.1098)
			(xy 188.42269 52.10161) (xy 188.42269 52.09342) (xy 188.42269 52.08522) (xy 188.42269 52.07703) (xy 188.42269 52.06883)
			(xy 188.42269 52.06064) (xy 188.42269 52.05244) (xy 188.42269 52.04425) (xy 188.42269 52.03606) (xy 188.42269 52.02786)
			(xy 188.42269 52.01967) (xy 188.42269 52.01147) (xy 188.42269 52.00328) (xy 188.42269 51.99508) (xy 188.42269 51.98689)
			(xy 188.42269 51.97869) (xy 188.42269 51.9705) (xy 188.42269 51.9623) (xy 188.42269 51.95411) (xy 188.42269 51.94592)
			(xy 188.42269 51.93772) (xy 188.41449 51.93772) (xy 188.41449 51.92953) (xy 188.41449 51.92133) (xy 188.41449 51.91314)
			(xy 188.41449 51.90494) (xy 188.41449 51.89675) (xy 188.4063 51.89675) (xy 188.4063 51.88856) (xy 188.4063 51.88036)
			(xy 188.3981 51.88036) (xy 188.3981 51.87216) (xy 188.3981 51.86397) (xy 188.38991 51.86397) (xy 188.38991 51.85578)
			(xy 188.38991 51.84758) (xy 188.38171 51.84758) (xy 188.38171 51.83939) (xy 188.37352 51.83939) (xy 188.37352 51.83119)
			(xy 188.37352 51.823) (xy 188.36533 51.823) (xy 188.36533 51.8148) (xy 188.35713 51.8148) (xy 188.35713 51.80661)
			(xy 188.34894 51.80661) (xy 188.34894 51.79841) (xy 188.33255 51.79841) (xy 188.33255 51.79022) (xy 188.32435 51.79022)
			(xy 188.32435 51.78203) (xy 188.30796 51.78203) (xy 188.30796 51.77383) (xy 188.29158 51.77383) (xy 188.29158 51.76564)
			(xy 188.27518 51.76564) (xy 188.27518 51.75744) (xy 188.24241 51.75744) (xy 188.24241 51.74925) (xy 187.20171 51.74925)
			(xy 187.20171 51.74105) (xy 187.20171 51.73286) (xy 187.20171 51.72466) (xy 187.20171 51.71647) (xy 187.20171 51.70828)
			(xy 187.20171 51.70008) (xy 187.20171 51.69189) (xy 187.20171 51.68369) (xy 187.20171 51.6755) (xy 187.20171 51.6673)
			(xy 187.20171 51.65911) (xy 187.20171 51.65091) (xy 187.20171 51.64272) (xy 187.20171 51.63452) (xy 187.20171 51.62633)
			(xy 187.20171 51.61814) (xy 187.20171 51.60994) (xy 187.20171 51.60175) (xy 187.20171 51.59355) (xy 187.20171 51.58536)
			(xy 187.20171 51.57716) (xy 187.20171 51.56897) (xy 187.20171 51.56077) (xy 187.20171 51.55258) (xy 187.20171 51.54439)
			(xy 187.20171 51.53619) (xy 187.20171 51.52799) (xy 187.20171 51.5198) (xy 187.20171 51.51161) (xy 187.20171 51.50341)
			(xy 187.20171 51.49522) (xy 187.20171 51.48702) (xy 187.20171 51.47883) (xy 187.20171 51.47064) (xy 187.20171 51.46244)
			(xy 187.20171 51.45424) (xy 187.20171 51.44605) (xy 187.20171 51.43786) (xy 188.24241 51.43786)
		)
		(stroke
			(width 0)
			(type default)
		)
		(fill yes)
		(layer "F.Cu")
	)
	(gr_poly
		(pts
			(xy 199.37873 51.44605) (xy 199.46886 51.44605) (xy 199.46886 51.45424) (xy 199.50164 51.45424) (xy 199.50164 51.46244)
			(xy 199.53442 51.46244) (xy 199.53442 51.47064) (xy 199.559 51.47064) (xy 199.559 51.47883) (xy 199.58359 51.47883)
			(xy 199.58359 51.48702) (xy 199.59998 51.48702) (xy 199.59998 51.49522) (xy 199.61637 51.49522) (xy 199.61637 51.50341)
			(xy 199.63275 51.50341) (xy 199.63275 51.51161) (xy 199.64914 51.51161) (xy 199.64914 51.5198) (xy 199.66553 51.5198)
			(xy 199.66553 51.52799) (xy 199.67373 51.52799) (xy 199.67373 51.53619) (xy 199.69012 51.53619) (xy 199.69012 51.54439)
			(xy 199.69831 51.54439) (xy 199.69831 51.55258) (xy 199.7065 51.55258) (xy 199.7065 51.56077) (xy 199.72289 51.56077)
			(xy 199.72289 51.56897) (xy 199.73109 51.56897) (xy 199.73109 51.57716) (xy 199.73928 51.57716) (xy 199.73928 51.58536)
			(xy 199.74748 51.58536) (xy 199.74748 51.59355) (xy 199.75567 51.59355) (xy 199.75567 51.60175) (xy 199.76387 51.60175)
			(xy 199.76387 51.60994) (xy 199.77206 51.60994) (xy 199.77206 51.61814) (xy 199.78025 51.61814) (xy 199.78025 51.62633)
			(xy 199.78845 51.62633) (xy 199.78845 51.63452) (xy 199.79664 51.63452) (xy 199.79664 51.64272) (xy 199.80484 51.64272)
			(xy 199.80484 51.65091) (xy 199.80484 51.65911) (xy 199.81304 51.65911) (xy 199.81304 51.6673) (xy 199.82123 51.6673)
			(xy 199.82123 51.6755) (xy 199.82942 51.6755) (xy 199.82942 51.68369) (xy 199.82942 51.69189) (xy 199.83762 51.69189)
			(xy 199.83762 51.70008) (xy 199.83762 51.70828) (xy 199.84581 51.70828) (xy 199.84581 51.71647) (xy 199.85401 51.71647)
			(xy 199.85401 51.72466) (xy 199.85401 51.73286) (xy 199.8622 51.73286) (xy 199.8622 51.74105) (xy 199.8622 51.74925)
			(xy 199.87039 51.74925) (xy 199.87039 51.75744) (xy 199.87039 51.76564) (xy 199.87859 51.76564) (xy 199.87859 51.77383)
			(xy 199.87859 51.78203) (xy 199.87859 51.79022) (xy 199.88678 51.79022) (xy 199.88678 51.79841) (xy 199.88678 51.80661)
			(xy 199.88678 51.8148) (xy 199.89498 51.8148) (xy 199.89498 51.823) (xy 199.89498 51.83119) (xy 199.89498 51.83939)
			(xy 199.90317 51.83939) (xy 199.90317 51.84758) (xy 199.90317 51.85578) (xy 199.90317 51.86397) (xy 199.90317 51.87216)
			(xy 199.91137 51.87216) (xy 199.91137 51.88036) (xy 199.91137 51.88856) (xy 199.91137 51.89675) (xy 199.91137 51.90494)
			(xy 199.91137 51.91314) (xy 199.91137 51.92133) (xy 199.91956 51.92133) (xy 199.91956 51.92953) (xy 199.91956 51.93772)
			(xy 199.91956 51.94592) (xy 199.91956 51.95411) (xy 199.91956 51.9623) (xy 199.91956 51.9705) (xy 199.91956 51.97869)
			(xy 199.91956 51.98689) (xy 199.91956 51.99508) (xy 199.91956 52.00328) (xy 199.91956 52.01147) (xy 199.91137 52.01147)
			(xy 199.91137 52.01967) (xy 199.91956 52.01967) (xy 199.91956 52.02786) (xy 199.91137 52.02786) (xy 199.91137 52.03606)
			(xy 199.91137 52.04425) (xy 199.91137 52.05244) (xy 199.91137 52.06064) (xy 199.91137 52.06883) (xy 199.91137 52.07703)
			(xy 199.91137 52.08522) (xy 199.90317 52.08522) (xy 199.90317 52.09342) (xy 199.90317 52.10161) (xy 199.90317 52.1098)
			(xy 199.90317 52.118) (xy 199.89498 52.118) (xy 199.89498 52.1262) (xy 199.89498 52.13439) (xy 199.89498 52.14258)
			(xy 199.88678 52.14258) (xy 199.88678 52.15078) (xy 199.88678 52.15897) (xy 199.88678 52.16717) (xy 199.87859 52.16717)
			(xy 199.87859 52.17536) (xy 199.87859 52.18356) (xy 199.87859 52.19175) (xy 199.87039 52.19175) (xy 199.87039 52.19995)
			(xy 199.87039 52.20814) (xy 199.8622 52.20814) (xy 199.8622 52.21633) (xy 199.8622 52.22453) (xy 199.85401 52.22453)
			(xy 199.85401 52.23272) (xy 199.85401 52.24092) (xy 199.84581 52.24092) (xy 199.84581 52.24911) (xy 199.83762 52.24911)
			(xy 199.83762 52.25731) (xy 199.83762 52.2655) (xy 199.82942 52.2655) (xy 199.82942 52.2737) (xy 199.82123 52.2737)
			(xy 199.82123 52.28189) (xy 199.82123 52.29008) (xy 199.81304 52.29008) (xy 199.81304 52.29828) (xy 199.80484 52.29828)
			(xy 199.80484 52.30647) (xy 199.79664 52.30647) (xy 199.79664 52.31467) (xy 199.79664 52.32286) (xy 199.78845 52.32286)
			(xy 199.78845 52.33106) (xy 199.78025 52.33106) (xy 199.78025 52.33925) (xy 199.77206 52.33925) (xy 199.77206 52.34744)
			(xy 199.76387 52.34744) (xy 199.76387 52.35564) (xy 199.75567 52.35564) (xy 199.75567 52.36384) (xy 199.74748 52.36384)
			(xy 199.74748 52.37203) (xy 199.73928 52.37203) (xy 199.73928 52.38022) (xy 199.73109 52.38022) (xy 199.73109 52.38842)
			(xy 199.7147 52.38842) (xy 199.7147 52.39661) (xy 199.7065 52.39661) (xy 199.7065 52.40481) (xy 199.69831 52.40481)
			(xy 199.69831 52.413) (xy 199.68192 52.413) (xy 199.68192 52.4212) (xy 199.67373 52.4212) (xy 199.67373 52.42939)
			(xy 199.65734 52.42939) (xy 199.65734 52.43759) (xy 199.64914 52.43759) (xy 199.64914 52.44578) (xy 199.63275 52.44578)
			(xy 199.63275 52.45397) (xy 199.61637 52.45397) (xy 199.61637 52.46217) (xy 199.59998 52.46217) (xy 199.59998 52.47036)
			(xy 199.57539 52.47036) (xy 199.57539 52.47856) (xy 199.559 52.47856) (xy 199.559 52.48675) (xy 199.52623 52.48675)
			(xy 199.52623 52.49495) (xy 199.50164 52.49495) (xy 199.50164 52.50314) (xy 199.45248 52.50314) (xy 199.45248 52.51134)
			(xy 198.2151 52.51134) (xy 198.2151 52.51953) (xy 198.14955 52.51953) (xy 198.14955 52.52772) (xy 198.11677 52.52772)
			(xy 198.11677 52.53592) (xy 198.08399 52.53592) (xy 198.08399 52.54411) (xy 198.06761 52.54411) (xy 198.06761 52.55231)
			(xy 198.04302 52.55231) (xy 198.04302 52.5605) (xy 198.02663 52.5605) (xy 198.02663 52.5687) (xy 198.01025 52.5687)
			(xy 198.01025 52.57689) (xy 197.99385 52.57689) (xy 197.99385 52.58509) (xy 197.97747 52.58509) (xy 197.97747 52.59328)
			(xy 197.96927 52.59328) (xy 197.96927 52.60148) (xy 197.95288 52.60148) (xy 197.95288 52.60967) (xy 197.9365 52.60967)
			(xy 197.9365 52.61787) (xy 197.9283 52.61787) (xy 197.9283 52.62606) (xy 197.9201 52.62606) (xy 197.9201 52.63425)
			(xy 197.91191 52.63425) (xy 197.91191 52.64245) (xy 197.89552 52.64245) (xy 197.89552 52.65064) (xy 197.88733 52.65064)
			(xy 197.88733 52.65884) (xy 197.87913 52.65884) (xy 197.87913 52.66703) (xy 197.87094 52.66703) (xy 197.87094 52.67522)
			(xy 197.86274 52.67522) (xy 197.86274 52.68342) (xy 197.85455 52.68342) (xy 197.85455 52.69162) (xy 197.84635 52.69162)
			(xy 197.84635 52.69981) (xy 197.83816 52.69981) (xy 197.83816 52.708) (xy 197.83816 52.7162) (xy 197.82997 52.7162)
			(xy 197.82997 52.72439) (xy 197.82177 52.72439) (xy 197.82177 52.73259) (xy 197.81358 52.73259) (xy 197.81358 52.74078)
			(xy 197.81358 52.74898) (xy 197.80538 52.74898) (xy 197.80538 52.75717) (xy 197.79719 52.75717) (xy 197.79719 52.76536)
			(xy 197.79719 52.77356) (xy 197.78899 52.77356) (xy 197.78899 52.78175) (xy 197.7808 52.78175) (xy 197.7808 52.78995)
			(xy 197.7808 52.79814) (xy 197.7726 52.79814) (xy 197.7726 52.80634) (xy 197.7726 52.81453) (xy 197.76441 52.81453)
			(xy 197.76441 52.82273) (xy 197.76441 52.83092) (xy 197.75621 52.83092) (xy 197.75621 52.83911) (xy 197.75621 52.84731)
			(xy 197.75621 52.85551) (xy 197.74802 52.85551) (xy 197.74802 52.8637) (xy 197.74802 52.87189) (xy 197.73983 52.87189)
			(xy 197.73983 52.88009) (xy 197.73983 52.88828) (xy 197.73983 52.89648) (xy 197.73163 52.89648) (xy 197.73163 52.90467)
			(xy 197.73163 52.91287) (xy 197.73163 52.92106) (xy 197.73163 52.92926) (xy 197.72344 52.92926) (xy 197.72344 52.93745)
			(xy 197.72344 52.94564) (xy 197.72344 52.95384) (xy 197.72344 52.96203) (xy 197.72344 52.97023) (xy 197.72344 52.97842)
			(xy 197.71524 52.97842) (xy 197.71524 52.98662) (xy 197.71524 52.99481) (xy 197.71524 53.00301) (xy 197.71524 53.0112)
			(xy 197.71524 53.01939) (xy 197.71524 53.02759) (xy 197.71524 53.03578) (xy 197.71524 53.04398) (xy 197.71524 53.05217)
			(xy 197.71524 53.06037) (xy 197.71524 53.06856) (xy 197.71524 53.07675) (xy 197.71524 53.08495) (xy 197.71524 53.09315)
			(xy 197.71524 53.10134) (xy 197.71524 53.10953) (xy 197.72344 53.10953) (xy 197.72344 53.11773) (xy 197.72344 53.12592)
			(xy 197.72344 53.13412) (xy 197.72344 53.14231) (xy 197.72344 53.15051) (xy 197.72344 53.1587) (xy 197.73163 53.1587)
			(xy 197.73163 53.16689) (xy 197.73163 53.17509) (xy 197.73163 53.18328) (xy 197.73163 53.19148) (xy 197.73983 53.19148)
			(xy 197.73983 53.19967) (xy 197.73983 53.20787) (xy 197.73983 53.21606) (xy 197.74802 53.21606) (xy 197.74802 53.22426)
			(xy 197.74802 53.23245) (xy 197.74802 53.24065) (xy 197.75621 53.24065) (xy 197.75621 53.24884) (xy 197.75621 53.25703)
			(xy 197.76441 53.25703) (xy 197.76441 53.26523) (xy 197.76441 53.27342) (xy 197.7726 53.27342) (xy 197.7726 53.28162)
			(xy 197.7726 53.28981) (xy 197.7808 53.28981) (xy 197.7808 53.29801) (xy 197.7808 53.3062) (xy 197.78899 53.3062)
			(xy 197.78899 53.31439) (xy 197.78899 53.32259) (xy 197.79719 53.32259) (xy 197.79719 53.33079) (xy 197.80538 53.33079)
			(xy 197.80538 53.33898) (xy 197.80538 53.34718) (xy 197.81358 53.34718) (xy 197.81358 53.35537) (xy 197.82177 53.35537)
			(xy 197.82177 53.36356) (xy 197.82177 53.37176) (xy 197.82997 53.37176) (xy 197.82997 53.37995) (xy 197.83816 53.37995)
			(xy 197.83816 53.38815) (xy 197.84635 53.38815) (xy 197.84635 53.39634) (xy 197.85455 53.39634) (xy 197.85455 53.40453)
			(xy 197.86274 53.40453) (xy 197.86274 53.41273) (xy 197.87094 53.41273) (xy 197.87094 53.42092) (xy 197.87913 53.42092)
			(xy 197.87913 53.42912) (xy 197.88733 53.42912) (xy 197.88733 53.43731) (xy 197.89552 53.43731) (xy 197.89552 53.44551)
			(xy 197.90371 53.44551) (xy 197.90371 53.4537) (xy 197.91191 53.4537) (xy 197.91191 53.4619) (xy 197.9201 53.4619)
			(xy 197.9201 53.47009) (xy 197.9365 53.47009) (xy 197.9365 53.47829) (xy 197.94469 53.47829) (xy 197.94469 53.48648)
			(xy 197.96108 53.48648) (xy 197.96108 53.49467) (xy 197.96927 53.49467) (xy 197.96927 53.50287) (xy 197.98566 53.50287)
			(xy 197.98566 53.51106) (xy 198.00205 53.51106) (xy 198.00205 53.51926) (xy 198.01844 53.51926) (xy 198.01844 53.52745)
			(xy 198.03483 53.52745) (xy 198.03483 53.53565) (xy 198.05122 53.53565) (xy 198.05122 53.54384) (xy 198.0758 53.54384)
			(xy 198.0758 53.55204) (xy 198.10038 53.55204) (xy 198.10038 53.56023) (xy 198.13316 53.56023) (xy 198.13316 53.56843)
			(xy 198.17413 53.56843) (xy 198.17413 53.57662) (xy 204.65598 53.57662) (xy 204.65598 53.58482) (xy 204.66417 53.58482)
			(xy 204.66417 53.57662) (xy 204.67237 53.57662) (xy 204.67237 53.58482) (xy 204.72973 53.58482) (xy 204.72973 53.59301)
			(xy 204.76251 53.59301) (xy 204.76251 53.6012) (xy 204.78709 53.6012) (xy 204.78709 53.6094) (xy 204.81167 53.6094)
			(xy 204.81167 53.61759) (xy 204.83626 53.61759) (xy 204.83626 53.62579) (xy 204.85264 53.62579) (xy 204.85264 53.63398)
			(xy 204.86904 53.63398) (xy 204.86904 53.64218) (xy 204.88543 53.64218) (xy 204.88543 53.65037) (xy 204.90181 53.65037)
			(xy 204.90181 53.65857) (xy 204.91001 53.65857) (xy 204.91001 53.66676) (xy 204.9264 53.66676) (xy 204.9264 53.67495)
			(xy 204.93459 53.67495) (xy 204.93459 53.68315) (xy 204.95098 53.68315) (xy 204.95098 53.69134) (xy 204.95917 53.69134)
			(xy 204.95917 53.69954) (xy 204.96737 53.69954) (xy 204.96737 53.70773) (xy 204.97556 53.70773) (xy 204.97556 53.71593)
			(xy 204.99195 53.71593) (xy 204.99195 53.72412) (xy 205.00015 53.72412) (xy 205.00015 53.73231) (xy 205.00834 53.73231)
			(xy 205.00834 53.74051) (xy 205.01654 53.74051) (xy 205.01654 53.7487) (xy 205.02473 53.7487) (xy 205.02473 53.7569)
			(xy 205.03293 53.7569) (xy 205.03293 53.76509) (xy 205.03293 53.77329) (xy 205.04112 53.77329) (xy 205.04112 53.78148)
			(xy 205.04931 53.78148) (xy 205.04931 53.78968) (xy 205.05751 53.78968) (xy 205.05751 53.79787) (xy 205.0657 53.79787)
			(xy 205.0657 53.80606) (xy 205.0657 53.81426) (xy 205.0739 53.81426) (xy 205.0739 53.82246) (xy 205.08209 53.82246)
			(xy 205.08209 53.83065) (xy 205.08209 53.83884) (xy 205.09029 53.83884) (xy 205.09029 53.84704) (xy 205.09848 53.84704)
			(xy 205.09848 53.85523) (xy 205.09848 53.86343) (xy 205.10668 53.86343) (xy 205.10668 53.87162) (xy 205.10668 53.87982)
			(xy 205.11487 53.87982) (xy 205.11487 53.88801) (xy 205.11487 53.8962) (xy 205.12307 53.8962) (xy 205.12307 53.9044)
			(xy 205.12307 53.91259) (xy 205.12307 53.92079) (xy 205.13126 53.92079) (xy 205.13126 53.92898) (xy 205.13126 53.93718)
			(xy 205.13945 53.93718) (xy 205.13945 53.94537) (xy 205.13945 53.95357) (xy 205.13945 53.96176) (xy 205.14765 53.96176)
			(xy 205.14765 53.96996) (xy 205.14765 53.97815) (xy 205.14765 53.98634) (xy 205.14765 53.99454) (xy 205.15584 53.99454)
			(xy 205.15584 54.00273) (xy 205.15584 54.01093) (xy 205.15584 54.01912) (xy 205.15584 54.02732) (xy 205.15584 54.03551)
			(xy 205.16404 54.03551) (xy 205.16404 54.0437) (xy 205.16404 54.0519) (xy 205.16404 54.0601) (xy 205.16404 54.06829)
			(xy 205.16404 54.07649) (xy 205.16404 54.08468) (xy 205.16404 54.09287) (xy 205.16404 54.10107) (xy 205.16404 54.10926)
			(xy 205.16404 54.11746) (xy 205.16404 54.12565) (xy 205.16404 54.13385) (xy 205.16404 54.14204) (xy 205.16404 54.15023)
			(xy 205.16404 54.15843) (xy 205.16404 54.16662) (xy 205.16404 54.17482) (xy 205.16404 54.18301) (xy 205.16404 54.19121)
			(xy 205.15584 54.19121) (xy 205.15584 54.1994) (xy 205.15584 54.2076) (xy 205.15584 54.21579) (xy 205.15584 54.22398)
			(xy 205.15584 54.23218) (xy 205.14765 54.23218) (xy 205.14765 54.24037) (xy 205.14765 54.24857) (xy 205.14765 54.25676)
			(xy 205.14765 54.26496) (xy 205.13945 54.26496) (xy 205.13945 54.27315) (xy 205.13945 54.28134) (xy 205.13945 54.28954)
			(xy 205.13126 54.28954) (xy 205.13126 54.29774) (xy 205.13126 54.30593) (xy 205.13126 54.31413) (xy 205.12307 54.31413)
			(xy 205.12307 54.32232) (xy 205.12307 54.33051) (xy 205.11487 54.33051) (xy 205.11487 54.33871) (xy 205.11487 54.3469)
			(xy 205.10668 54.3469) (xy 205.10668 54.3551) (xy 205.10668 54.36329) (xy 205.09848 54.36329) (xy 205.09848 54.37149)
			(xy 205.09848 54.37968) (xy 205.09029 54.37968) (xy 205.09029 54.38787) (xy 205.09029 54.39607) (xy 205.08209 54.39607)
			(xy 205.08209 54.40426) (xy 205.0739 54.40426) (xy 205.0739 54.41246) (xy 205.0739 54.42065) (xy 205.0657 54.42065)
			(xy 205.0657 54.42885) (xy 205.05751 54.42885) (xy 205.05751 54.43704) (xy 205.04931 54.43704) (xy 205.04931 54.44524)
			(xy 205.04112 54.44524) (xy 205.04112 54.45343) (xy 205.04112 54.46162) (xy 205.03293 54.46162) (xy 205.03293 54.46982)
			(xy 205.02473 54.46982) (xy 205.02473 54.47801) (xy 205.01654 54.47801) (xy 205.01654 54.48621) (xy 205.00834 54.48621)
			(xy 205.00834 54.4944) (xy 205.00015 54.4944) (xy 205.00015 54.5026) (xy 204.99195 54.5026) (xy 204.99195 54.51079)
			(xy 204.98376 54.51079) (xy 204.98376 54.51899) (xy 204.97556 54.51899) (xy 204.97556 54.52718) (xy 204.95917 54.52718)
			(xy 204.95917 54.53538) (xy 204.95098 54.53538) (xy 204.95098 54.54357) (xy 204.94279 54.54357) (xy 204.94279 54.55176)
			(xy 204.9264 54.55176) (xy 204.9264 54.55996) (xy 204.9182 54.55996) (xy 204.9182 54.56815) (xy 204.90181 54.56815)
			(xy 204.90181 54.57635) (xy 204.88543 54.57635) (xy 204.88543 54.58454) (xy 204.87723 54.58454) (xy 204.87723 54.59274)
			(xy 204.85264 54.59274) (xy 204.85264 54.60093) (xy 204.83626 54.60093) (xy 204.83626 54.60913) (xy 204.81987 54.60913)
			(xy 204.81987 54.61732) (xy 204.79528 54.61732) (xy 204.79528 54.62551) (xy 204.7707 54.62551) (xy 204.7707 54.63371)
			(xy 204.73793 54.63371) (xy 204.73793 54.6419) (xy 204.68876 54.6419) (xy 204.68876 54.6501) (xy 200.43581 54.6501)
			(xy 200.43581 54.65829) (xy 200.38665 54.65829) (xy 200.38665 54.66649) (xy 200.35387 54.66649) (xy 200.35387 54.67468)
			(xy 200.32109 54.67468) (xy 200.32109 54.68288) (xy 200.3047 54.68288) (xy 200.3047 54.69107) (xy 200.28012 54.69107)
			(xy 200.28012 54.69926) (xy 200.26373 54.69926) (xy 200.26373 54.70746) (xy 200.24734 54.70746) (xy 200.24734 54.71565)
			(xy 200.23095 54.71565) (xy 200.23095 54.72385) (xy 200.21456 54.72385) (xy 200.21456 54.73204) (xy 200.20637 54.73204)
			(xy 200.20637 54.74024) (xy 200.18998 54.74024) (xy 200.18998 54.74843) (xy 200.18179 54.74843) (xy 200.18179 54.75663)
			(xy 200.17359 54.75663) (xy 200.17359 54.76482) (xy 200.1572 54.76482) (xy 200.1572 54.77302) (xy 200.14901 54.77302)
			(xy 200.14901 54.78121) (xy 200.14081 54.78121) (xy 200.14081 54.78941) (xy 200.13262 54.78941) (xy 200.13262 54.7976)
			(xy 200.12442 54.7976) (xy 200.12442 54.80579) (xy 200.11623 54.80579) (xy 200.11623 54.81399) (xy 200.10804 54.81399)
			(xy 200.10804 54.82218) (xy 200.09984 54.82218) (xy 200.09984 54.83038) (xy 200.09165 54.83038) (xy 200.09165 54.83857)
			(xy 200.08345 54.83857) (xy 200.08345 54.84677) (xy 200.07526 54.84677) (xy 200.07526 54.85496) (xy 200.06706 54.85496)
			(xy 200.06706 54.86316) (xy 200.06706 54.87135) (xy 200.05887 54.87135) (xy 200.05887 54.87955) (xy 200.05067 54.87955)
			(xy 200.05067 54.88774) (xy 200.05067 54.89593) (xy 200.04248 54.89593) (xy 200.04248 54.90413) (xy 200.03428 54.90413)
			(xy 200.03428 54.91232) (xy 200.03428 54.92052) (xy 200.02609 54.92052) (xy 200.02609 54.92871) (xy 200.02609 54.93691)
			(xy 200.01789 54.93691) (xy 200.01789 54.9451) (xy 200.01789 54.95329) (xy 200.0097 54.95329) (xy 200.0097 54.96149)
			(xy 200.0097 54.96968) (xy 200.00151 54.96968) (xy 200.00151 54.97788) (xy 200.00151 54.98607) (xy 199.99331 54.98607)
			(xy 199.99331 54.99427) (xy 199.99331 55.00246) (xy 199.99331 55.01065) (xy 199.98512 55.01065) (xy 199.98512 55.01885)
			(xy 199.98512 55.02705) (xy 199.98512 55.03524) (xy 199.97692 55.03524) (xy 199.97692 55.04344) (xy 199.97692 55.05163)
			(xy 199.97692 55.05982) (xy 199.97692 55.06802) (xy 199.96873 55.06802) (xy 199.96873 55.07621) (xy 199.96873 55.08441)
			(xy 199.96873 55.0926) (xy 199.96873 55.1008) (xy 199.96873 55.10899) (xy 199.96873 55.11718) (xy 199.96053 55.11718)
			(xy 199.96053 55.12538) (xy 199.96053 55.13357) (xy 199.96053 55.14177) (xy 199.96053 55.14996) (xy 199.96053 55.15816)
			(xy 199.96053 55.16635) (xy 199.96053 55.17455) (xy 199.96053 55.18274) (xy 199.96053 55.19093) (xy 199.96053 55.19913)
			(xy 199.96053 55.20732) (xy 199.96053 55.21552) (xy 199.96053 55.22371) (xy 199.96053 55.23191) (xy 199.96053 55.2401)
			(xy 199.96053 55.2483) (xy 199.96873 55.2483) (xy 199.96873 55.25649) (xy 199.96873 55.26469) (xy 199.96873 55.27288)
			(xy 199.96873 55.28108) (xy 199.96873 55.28927) (xy 199.96873 55.29746) (xy 199.97692 55.29746) (xy 199.97692 55.30566)
			(xy 199.97692 55.31385) (xy 199.97692 55.32205) (xy 199.97692 55.33024) (xy 199.98512 55.33024) (xy 199.98512 55.33844)
			(xy 199.98512 55.34663) (xy 199.98512 55.35482) (xy 199.99331 55.35482) (xy 199.99331 55.36302) (xy 199.99331 55.37122)
			(xy 199.99331 55.37941) (xy 200.00151 55.37941) (xy 200.00151 55.3876) (xy 200.00151 55.3958) (xy 200.0097 55.3958)
			(xy 200.0097 55.40399) (xy 200.0097 55.41219) (xy 200.01789 55.41219) (xy 200.01789 55.42038) (xy 200.01789 55.42857)
			(xy 200.02609 55.42857) (xy 200.02609 55.43677) (xy 200.02609 55.44496) (xy 200.03428 55.44496) (xy 200.03428 55.45316)
			(xy 200.03428 55.46136) (xy 200.04248 55.46136) (xy 200.04248 55.46955) (xy 200.05067 55.46955) (xy 200.05067 55.47774)
			(xy 200.05067 55.48594) (xy 200.05887 55.48594) (xy 200.05887 55.49413) (xy 200.06706 55.49413) (xy 200.06706 55.50233)
			(xy 200.07526 55.50233) (xy 200.07526 55.51052) (xy 200.07526 55.51872) (xy 200.08345 55.51872) (xy 200.08345 55.52691)
			(xy 200.09165 55.52691) (xy 200.09165 55.5351) (xy 200.09984 55.5351) (xy 200.09984 55.5433) (xy 200.10804 55.5433)
			(xy 200.10804 55.55149) (xy 200.11623 55.55149) (xy 200.11623 55.55969) (xy 200.12442 55.55969) (xy 200.12442 55.56788)
			(xy 200.13262 55.56788) (xy 200.13262 55.57608) (xy 200.14081 55.57608) (xy 200.14081 55.58427) (xy 200.14901 55.58427)
			(xy 200.14901 55.59247) (xy 200.16539 55.59247) (xy 200.16539 55.60066) (xy 200.17359 55.60066) (xy 200.17359 55.60885)
			(xy 200.18179 55.60885) (xy 200.18179 55.61705) (xy 200.19817 55.61705) (xy 200.19817 55.62524) (xy 200.20637 55.62524)
			(xy 200.20637 55.63344) (xy 200.22276 55.63344) (xy 200.22276 55.64163) (xy 200.23915 55.64163) (xy 200.23915 55.64983)
			(xy 200.24734 55.64983) (xy 200.24734 55.65802) (xy 200.26373 55.65802) (xy 200.26373 55.66622) (xy 200.28831 55.66622)
			(xy 200.28831 55.67441) (xy 200.3047 55.67441) (xy 200.3047 55.6826) (xy 200.32929 55.6826) (xy 200.32929 55.6908)
			(xy 200.35387 55.6908) (xy 200.35387 55.69899) (xy 200.38665 55.69899) (xy 200.38665 55.70719) (xy 200.44401 55.70719)
			(xy 200.44401 55.71538) (xy 202.01735 55.71538) (xy 202.01735 55.72358) (xy 202.05832 55.72358) (xy 202.05832 55.73177)
			(xy 202.0911 55.73177) (xy 202.0911 55.73997) (xy 202.11569 55.73997) (xy 202.11569 55.74816) (xy 202.14027 55.74816)
			(xy 202.14027 55.75636) (xy 202.16485 55.75636) (xy 202.16485 55.76455) (xy 202.18124 55.76455) (xy 202.18124 55.77274)
			(xy 202.19763 55.77274) (xy 202.19763 55.78094) (xy 202.21402 55.78094) (xy 202.21402 55.78913) (xy 202.23041 55.78913)
			(xy 202.23041 55.79733) (xy 202.2386 55.79733) (xy 202.2386 55.80552) (xy 202.25499 55.80552) (xy 202.25499 55.81372)
			(xy 202.26319 55.81372) (xy 202.26319 55.82191) (xy 202.27138 55.82191) (xy 202.27138 55.83011) (xy 202.28777 55.83011)
			(xy 202.28777 55.8383) (xy 202.29597 55.8383) (xy 202.29597 55.84649) (xy 202.30416 55.84649) (xy 202.30416 55.85469)
			(xy 202.31235 55.85469) (xy 202.31235 55.86288) (xy 202.32055 55.86288) (xy 202.32055 55.87108) (xy 202.32874 55.87108)
			(xy 202.32874 55.87927) (xy 202.33694 55.87927) (xy 202.33694 55.88747) (xy 202.34513 55.88747) (xy 202.34513 55.89566)
			(xy 202.35333 55.89566) (xy 202.35333 55.90386) (xy 202.36152 55.90386) (xy 202.36152 55.91205) (xy 202.36971 55.91205)
			(xy 202.36971 55.92024) (xy 202.37791 55.92024) (xy 202.37791 55.92844) (xy 202.37791 55.93663) (xy 202.3861 55.93663)
			(xy 202.3861 55.94483) (xy 202.3943 55.94483) (xy 202.3943 55.95302) (xy 202.40249 55.95302) (xy 202.40249 55.96122)
			(xy 202.40249 55.96941) (xy 202.41069 55.96941) (xy 202.41069 55.97761) (xy 202.41069 55.9858) (xy 202.41888 55.9858)
			(xy 202.41888 55.994) (xy 202.42708 55.994) (xy 202.42708 56.00219) (xy 202.42708 56.01039) (xy 202.43527 56.01039)
			(xy 202.43527 56.01858) (xy 202.43527 56.02677) (xy 202.44346 56.02677) (xy 202.44346 56.03497) (xy 202.44346 56.04316)
			(xy 202.44346 56.05136) (xy 202.45166 56.05136) (xy 202.45166 56.05955) (xy 202.45166 56.06775) (xy 202.45986 56.06775)
			(xy 202.45986 56.07594) (xy 202.45986 56.08413) (xy 202.45986 56.09233) (xy 202.46805 56.09233) (xy 202.46805 56.10053)
			(xy 202.46805 56.10872) (xy 202.46805 56.11691) (xy 202.46805 56.12511) (xy 202.47624 56.12511) (xy 202.47624 56.1333)
			(xy 202.47624 56.1415) (xy 202.47624 56.14969) (xy 202.47624 56.15788) (xy 202.47624 56.16608) (xy 202.48444 56.16608)
			(xy 202.48444 56.17427) (xy 202.48444 56.18247) (xy 202.48444 56.19066) (xy 202.48444 56.19886) (xy 202.48444 56.20705)
			(xy 202.48444 56.21524) (xy 202.48444 56.22344) (xy 202.48444 56.23164) (xy 202.48444 56.23983) (xy 202.48444 56.24803)
			(xy 202.48444 56.25622) (xy 202.48444 56.26441) (xy 202.48444 56.27261) (xy 202.48444 56.2808) (xy 202.48444 56.289)
			(xy 202.48444 56.29719) (xy 202.48444 56.30539) (xy 202.48444 56.31358) (xy 202.48444 56.32177) (xy 202.48444 56.32997)
			(xy 202.48444 56.33816) (xy 202.47624 56.33816) (xy 202.47624 56.34636) (xy 202.47624 56.35455) (xy 202.47624 56.36275)
			(xy 202.47624 56.37094) (xy 202.47624 56.37914) (xy 202.46805 56.37914) (xy 202.46805 56.38733) (xy 202.46805 56.39553)
			(xy 202.46805 56.40372) (xy 202.45986 56.40372) (xy 202.45986 56.41191) (xy 202.45986 56.42011) (xy 202.45986 56.42831)
			(xy 202.45166 56.42831) (xy 202.45166 56.4365) (xy 202.45166 56.44469) (xy 202.45166 56.45289) (xy 202.44346 56.45289)
			(xy 202.44346 56.46108) (xy 202.44346 56.46928) (xy 202.43527 56.46928) (xy 202.43527 56.47747) (xy 202.43527 56.48567)
			(xy 202.42708 56.48567) (xy 202.42708 56.49386) (xy 202.42708 56.50205) (xy 202.41888 56.50205) (xy 202.41888 56.51025)
			(xy 202.41888 56.51844) (xy 202.41069 56.51844) (xy 202.41069 56.52664) (xy 202.41069 56.53483) (xy 202.40249 56.53483)
			(xy 202.40249 56.54303) (xy 202.3943 56.54303) (xy 202.3943 56.55122) (xy 202.3943 56.55942) (xy 202.3861 56.55942)
			(xy 202.3861 56.56761) (xy 202.37791 56.56761) (xy 202.37791 56.5758) (xy 202.36971 56.5758) (xy 202.36971 56.584)
			(xy 202.36152 56.584) (xy 202.36152 56.59219) (xy 202.36152 56.60039) (xy 202.35333 56.60039) (xy 202.35333 56.60858)
			(xy 202.34513 56.60858) (xy 202.34513 56.61678) (xy 202.33694 56.61678) (xy 202.33694 56.62497) (xy 202.32874 56.62497)
			(xy 202.32874 56.63317) (xy 202.32055 56.63317) (xy 202.32055 56.64136) (xy 202.31235 56.64136) (xy 202.31235 56.64955)
			(xy 202.30416 56.64955) (xy 202.30416 56.65775) (xy 202.28777 56.65775) (xy 202.28777 56.66594) (xy 202.27958 56.66594)
			(xy 202.27958 56.67414) (xy 202.27138 56.67414) (xy 202.27138 56.68233) (xy 202.25499 56.68233) (xy 202.25499 56.69053)
			(xy 202.2468 56.69053) (xy 202.2468 56.69872) (xy 202.23041 56.69872) (xy 202.23041 56.70692) (xy 202.22222 56.70692)
			(xy 202.22222 56.71511) (xy 202.20582 56.71511) (xy 202.20582 56.72331) (xy 202.18944 56.72331) (xy 202.18944 56.7315)
			(xy 202.17305 56.7315) (xy 202.17305 56.73969) (xy 202.15666 56.73969) (xy 202.15666 56.74789) (xy 202.13208 56.74789)
			(xy 202.13208 56.75608) (xy 202.10749 56.75608) (xy 202.10749 56.76428) (xy 202.08291 56.76428) (xy 202.08291 56.77247)
			(xy 202.04194 56.77247) (xy 202.04194 56.78067) (xy 201.98458 56.78067) (xy 201.98458 56.78886) (xy 201.96818 56.78886)
			(xy 201.96818 56.78067) (xy 201.95999 56.78067) (xy 201.95999 56.78886) (xy 199.50164 56.78886) (xy 199.50164 56.78067)
			(xy 199.49345 56.78067) (xy 199.49345 56.78886) (xy 199.4115 56.78886) (xy 199.4115 56.79706) (xy 199.37053 56.79706)
			(xy 199.37053 56.80525) (xy 199.33775 56.80525) (xy 199.33775 56.81345) (xy 199.31317 56.81345) (xy 199.31317 56.82164)
			(xy 199.29678 56.82164) (xy 199.29678 56.82983) (xy 199.2722 56.82983) (xy 199.2722 56.83803) (xy 199.25581 56.83803)
			(xy 199.25581 56.84622) (xy 199.23942 56.84622) (xy 199.23942 56.85442) (xy 199.23122 56.85442) (xy 199.23122 56.86261)
			(xy 199.21483 56.86261) (xy 199.21483 56.87081) (xy 199.19845 56.87081) (xy 199.19845 56.879) (xy 199.19025 56.879)
			(xy 199.19025 56.88719) (xy 199.17386 56.88719) (xy 199.17386 56.89539) (xy 199.16567 56.89539) (xy 199.16567 56.90358)
			(xy 199.15747 56.90358) (xy 199.15747 56.91178) (xy 199.14928 56.91178) (xy 199.14928 56.91997) (xy 199.13289 56.91997)
			(xy 199.13289 56.92817) (xy 199.1247 56.92817) (xy 199.1247 56.93636) (xy 199.1165 56.93636) (xy 199.1165 56.94455)
			(xy 199.10831 56.94455) (xy 199.10831 56.95275) (xy 199.10011 56.95275) (xy 199.10011 56.96095) (xy 199.09192 56.96095)
			(xy 199.09192 56.96914) (xy 199.09192 56.97734) (xy 199.08373 56.97734) (xy 199.08373 56.98553) (xy 199.07553 56.98553)
			(xy 199.07553 56.99372) (xy 199.06733 56.99372) (xy 199.06733 57.00192) (xy 199.05914 57.00192) (xy 199.05914 57.01011)
			(xy 199.05914 57.01831) (xy 199.05094 57.01831) (xy 199.05094 57.0265) (xy 199.04275 57.0265) (xy 199.04275 57.0347)
			(xy 199.04275 57.04289) (xy 199.03456 57.04289) (xy 199.03456 57.05109) (xy 199.02636 57.05109) (xy 199.02636 57.05928)
			(xy 199.02636 57.06747) (xy 199.01817 57.06747) (xy 199.01817 57.07567) (xy 199.01817 57.08386) (xy 199.00997 57.08386)
			(xy 199.00997 57.09206) (xy 199.00997 57.10025) (xy 199.00178 57.10025) (xy 199.00178 57.10845) (xy 199.00178 57.11664)
			(xy 198.99358 57.11664) (xy 198.99358 57.12484) (xy 198.99358 57.13303) (xy 198.99358 57.14122) (xy 198.98539 57.14122)
			(xy 198.98539 57.14942) (xy 198.98539 57.15761) (xy 198.98539 57.16581) (xy 198.9772 57.16581) (xy 198.9772 57.174)
			(xy 198.9772 57.18219) (xy 198.9772 57.19039) (xy 198.969 57.19039) (xy 198.969 57.19859) (xy 198.969 57.20678)
			(xy 198.969 57.21498) (xy 198.969 57.22317) (xy 198.969 57.23136) (xy 198.96081 57.23136) (xy 198.96081 57.23956)
			(xy 198.96081 57.24775) (xy 198.96081 57.25595) (xy 198.96081 57.26414) (xy 198.96081 57.27234) (xy 198.96081 57.28053)
			(xy 198.96081 57.28872) (xy 198.96081 57.29692) (xy 198.96081 57.30511) (xy 198.96081 57.31331) (xy 198.96081 57.3215)
			(xy 198.96081 57.3297) (xy 198.96081 57.33789) (xy 198.96081 57.34609) (xy 198.96081 57.35428) (xy 198.96081 57.36248)
			(xy 198.96081 57.37067) (xy 198.96081 57.37886) (xy 198.96081 57.38706) (xy 198.96081 57.39526) (xy 198.96081 57.40345)
			(xy 198.969 57.40345) (xy 198.969 57.41164) (xy 198.969 57.41984) (xy 198.969 57.42803) (xy 198.969 57.43623)
			(xy 198.969 57.44442) (xy 198.9772 57.44442) (xy 198.9772 57.45262) (xy 198.9772 57.46081) (xy 198.9772 57.469)
			(xy 198.98539 57.469) (xy 198.98539 57.4772) (xy 198.98539 57.48539) (xy 198.98539 57.49359) (xy 198.99358 57.49359)
			(xy 198.99358 57.50178) (xy 198.99358 57.50998) (xy 198.99358 57.51817) (xy 199.00178 57.51817) (xy 199.00178 57.52637)
			(xy 199.00178 57.53456) (xy 199.00997 57.53456) (xy 199.00997 57.54276) (xy 199.00997 57.55095) (xy 199.01817 57.55095)
			(xy 199.01817 57.55914) (xy 199.01817 57.56734) (xy 199.02636 57.56734) (xy 199.02636 57.57553) (xy 199.02636 57.58373)
			(xy 199.03456 57.58373) (xy 199.03456 57.59192) (xy 199.03456 57.60011) (xy 199.04275 57.60011) (xy 199.04275 57.60831)
			(xy 199.05094 57.60831) (xy 199.05094 57.61651) (xy 199.05094 57.6247) (xy 199.05914 57.6247) (xy 199.05914 57.63289)
			(xy 199.06733 57.63289) (xy 199.06733 57.64109) (xy 199.07553 57.64109) (xy 199.07553 57.64928) (xy 199.07553 57.65748)
			(xy 199.08373 57.65748) (xy 199.08373 57.66567) (xy 199.09192 57.66567) (xy 199.09192 57.67387) (xy 199.10011 57.67387)
			(xy 199.10011 57.68206) (xy 199.10831 57.68206) (xy 199.10831 57.69026) (xy 199.1165 57.69026) (xy 199.1165 57.69845)
			(xy 199.1247 57.69845) (xy 199.1247 57.70664) (xy 199.13289 57.70664) (xy 199.13289 57.71484) (xy 199.14108 57.71484)
			(xy 199.14108 57.72303) (xy 199.14928 57.72303) (xy 199.14928 57.73123) (xy 199.16567 57.73123) (xy 199.16567 57.73942)
			(xy 199.17386 57.73942) (xy 199.17386 57.74762) (xy 199.18206 57.74762) (xy 199.18206 57.75581) (xy 199.19845 57.75581)
			(xy 199.19845 57.76401) (xy 199.20664 57.76401) (xy 199.20664 57.7722) (xy 199.22303 57.7722) (xy 199.22303 57.7804)
			(xy 199.23942 57.7804) (xy 199.23942 57.78859) (xy 199.25581 57.78859) (xy 199.25581 57.79678) (xy 199.2722 57.79678)
			(xy 199.2722 57.80498) (xy 199.28858 57.80498) (xy 199.28858 57.81317) (xy 199.31317 57.81317) (xy 199.31317 57.82137)
			(xy 199.32956 57.82137) (xy 199.32956 57.82956) (xy 199.36234 57.82956) (xy 199.36234 57.83776) (xy 199.40331 57.83776)
			(xy 199.40331 57.84595) (xy 199.47706 57.84595) (xy 199.47706 57.85415) (xy 201.17332 57.85415) (xy 201.17332 57.86234)
			(xy 201.21429 57.86234) (xy 201.21429 57.87053) (xy 201.23887 57.87053) (xy 201.23887 57.87873) (xy 201.26346 57.87873)
			(xy 201.26346 57.88692) (xy 201.28804 57.88692) (xy 201.28804 57.89512) (xy 201.31262 57.89512) (xy 201.31262 57.90331)
			(xy 201.32902 57.90331) (xy 201.32902 57.91151) (xy 201.3454 57.91151) (xy 201.3454 57.9197) (xy 201.3536 57.9197)
			(xy 201.3536 57.9279) (xy 201.36999 57.9279) (xy 201.36999 57.93609) (xy 201.38637 57.93609) (xy 201.38637 57.94429)
			(xy 201.39457 57.94429) (xy 201.39457 57.95248) (xy 201.41096 57.95248) (xy 201.41096 57.96067) (xy 201.41915 57.96067)
			(xy 201.41915 57.96887) (xy 201.42735 57.96887) (xy 201.42735 57.97706) (xy 201.43554 57.97706) (xy 201.43554 57.98526)
			(xy 201.45193 57.98526) (xy 201.45193 57.99345) (xy 201.46013 57.99345) (xy 201.46013 58.00165) (xy 201.46832 58.00165)
			(xy 201.46832 58.00984) (xy 201.47651 58.00984) (xy 201.47651 58.01804) (xy 201.48471 58.01804) (xy 201.48471 58.02623)
			(xy 201.49291 58.02623) (xy 201.49291 58.03442) (xy 201.49291 58.04262) (xy 201.5011 58.04262) (xy 201.5011 58.05081)
			(xy 201.50929 58.05081) (xy 201.50929 58.05901) (xy 201.51749 58.05901) (xy 201.51749 58.0672) (xy 201.52568 58.0672)
			(xy 201.52568 58.0754) (xy 201.52568 58.08359) (xy 201.53388 58.08359) (xy 201.53388 58.09178) (xy 201.54207 58.09178)
			(xy 201.54207 58.09998) (xy 201.54207 58.10817) (xy 201.55027 58.10817) (xy 201.55027 58.11637) (xy 201.55846 58.11637)
			(xy 201.55846 58.12456) (xy 201.55846 58.13276) (xy 201.56666 58.13276) (xy 201.56666 58.14095) (xy 201.56666 58.14915)
			(xy 201.57485 58.14915) (xy 201.57485 58.15734) (xy 201.57485 58.16554) (xy 201.58304 58.16554) (xy 201.58304 58.17373)
			(xy 201.58304 58.18193) (xy 201.59124 58.18193) (xy 201.59124 58.19012) (xy 201.59124 58.19831) (xy 201.59124 58.20651)
			(xy 201.59943 58.20651) (xy 201.59943 58.2147) (xy 201.59943 58.2229) (xy 201.59943 58.23109) (xy 201.60763 58.23109)
			(xy 201.60763 58.23929) (xy 201.60763 58.24748) (xy 201.60763 58.25568) (xy 201.61582 58.25568) (xy 201.61582 58.26387)
			(xy 201.61582 58.27207) (xy 201.61582 58.28026) (xy 201.61582 58.28845) (xy 201.61582 58.29665) (xy 201.61582 58.30484)
			(xy 201.62402 58.30484) (xy 201.62402 58.31304) (xy 201.62402 58.32123) (xy 201.62402 58.32942) (xy 201.62402 58.33762)
			(xy 201.62402 58.34582) (xy 201.62402 58.35401) (xy 201.62402 58.36221) (xy 201.62402 58.3704) (xy 201.62402 58.37859)
			(xy 201.63221 58.37859) (xy 201.63221 58.38679) (xy 201.63221 58.39498) (xy 201.62402 58.39498) (xy 201.62402 58.40318)
			(xy 201.62402 58.41137) (xy 201.62402 58.41957) (xy 201.62402 58.42776) (xy 201.62402 58.43595) (xy 201.62402 58.44415)
			(xy 201.62402 58.45234) (xy 201.62402 58.46054) (xy 201.62402 58.46874) (xy 201.62402 58.47693) (xy 201.61582 58.47693)
			(xy 201.61582 58.48512) (xy 201.61582 58.49332) (xy 201.61582 58.50151) (xy 201.61582 58.50971) (xy 201.61582 58.5179)
			(xy 201.60763 58.5179) (xy 201.60763 58.52609) (xy 201.60763 58.53429) (xy 201.60763 58.54248) (xy 201.59943 58.54248)
			(xy 201.59943 58.55068) (xy 201.59943 58.55887) (xy 201.59943 58.56707) (xy 201.59124 58.56707) (xy 201.59124 58.57526)
			(xy 201.59124 58.58345) (xy 201.59124 58.59165) (xy 201.58304 58.59165) (xy 201.58304 58.59985) (xy 201.58304 58.60804)
			(xy 201.58304 58.61623) (xy 201.57485 58.61623) (xy 201.57485 58.62443) (xy 201.57485 58.63262) (xy 201.56666 58.63262)
			(xy 201.56666 58.64082) (xy 201.56666 58.64901) (xy 201.55846 58.64901) (xy 201.55846 58.65721) (xy 201.55846 58.6654)
			(xy 201.55027 58.6654) (xy 201.55027 58.67359) (xy 201.54207 58.67359) (xy 201.54207 58.68179) (xy 201.54207 58.68998)
			(xy 201.53388 58.68998) (xy 201.53388 58.69818) (xy 201.52568 58.69818) (xy 201.52568 58.70637) (xy 201.52568 58.71457)
			(xy 201.51749 58.71457) (xy 201.51749 58.72276) (xy 201.50929 58.72276) (xy 201.50929 58.73096) (xy 201.5011 58.73096)
			(xy 201.5011 58.73915) (xy 201.5011 58.74735) (xy 201.49291 58.74735) (xy 201.49291 58.75554) (xy 201.48471 58.75554)
			(xy 201.48471 58.76374) (xy 201.47651 58.76374) (xy 201.47651 58.77193) (xy 201.46832 58.77193) (xy 201.46832 58.78012)
			(xy 201.46013 58.78012) (xy 201.46013 58.78832) (xy 201.45193 58.78832) (xy 201.45193 58.79651) (xy 201.44374 58.79651)
			(xy 201.44374 58.80471) (xy 201.43554 58.80471) (xy 201.43554 58.8129) (xy 201.42735 58.8129) (xy 201.42735 58.82109)
			(xy 201.41915 58.82109) (xy 201.41915 58.82929) (xy 201.40276 58.82929) (xy 201.40276 58.83748) (xy 201.39457 58.83748)
			(xy 201.39457 58.84568) (xy 201.38637 58.84568) (xy 201.38637 58.85387) (xy 201.36999 58.85387) (xy 201.36999 58.86207)
			(xy 201.36179 58.86207) (xy 201.36179 58.87026) (xy 201.3454 58.87026) (xy 201.3454 58.87846) (xy 201.32902 58.87846)
			(xy 201.32902 58.88665) (xy 201.31262 58.88665) (xy 201.31262 58.89485) (xy 201.29624 58.89485) (xy 201.29624 58.90304)
			(xy 201.27165 58.90304) (xy 201.27165 58.91124) (xy 201.23887 58.91124) (xy 201.23887 58.91943) (xy 195.33884 58.91943)
			(xy 195.33884 58.92762) (xy 195.32245 58.92762) (xy 195.32245 58.93582) (xy 195.31425 58.93582) (xy 195.31425 58.94401)
			(xy 195.30606 58.94401) (xy 195.30606 58.95221) (xy 195.29787 58.95221) (xy 195.29787 58.9604) (xy 195.29787 58.9686)
			(xy 195.28967 58.9686) (xy 195.28967 58.97679) (xy 195.28967 58.98499) (xy 195.28967 58.99318) (xy 195.28967 59.00138)
			(xy 195.28967 59.00957) (xy 195.28967 59.01776) (xy 195.28967 59.02596) (xy 195.28967 59.03415) (xy 195.28967 59.04235)
			(xy 195.28967 59.05054) (xy 195.28967 59.05874) (xy 195.28967 59.06693) (xy 195.28967 59.07513) (xy 195.28967 59.08332)
			(xy 195.28967 59.09151) (xy 195.28967 59.09971) (xy 195.28967 59.1079) (xy 195.28967 59.1161) (xy 195.28967 59.12429)
			(xy 195.28967 59.13249) (xy 195.28967 59.14068) (xy 195.28967 59.14888) (xy 195.28967 59.15707) (xy 195.28967 59.16526)
			(xy 195.28967 59.17346) (xy 195.28967 59.18165) (xy 195.28967 59.18985) (xy 195.28967 59.19805) (xy 195.28967 59.20624)
			(xy 195.28967 59.21443) (xy 195.28967 59.22263) (xy 195.28967 59.23082) (xy 195.28967 59.23902) (xy 195.28967 59.24721)
			(xy 195.28967 59.2554) (xy 195.28967 59.2636) (xy 195.28967 59.27179) (xy 195.28967 59.27999) (xy 195.28967 59.28818)
			(xy 195.28967 59.29638) (xy 195.28967 59.30457) (xy 195.28967 59.31276) (xy 195.28967 59.32096) (xy 195.28967 59.32916)
			(xy 195.28967 59.33735) (xy 195.28967 59.34554) (xy 195.28967 59.35374) (xy 195.28967 59.36193) (xy 195.28967 59.37013)
			(xy 195.28967 59.37832) (xy 195.28967 59.38652) (xy 195.28967 59.39471) (xy 195.28967 59.4029) (xy 195.28967 59.4111)
			(xy 195.28967 59.41929) (xy 195.28967 59.42749) (xy 195.28967 59.43568) (xy 195.28967 59.44388) (xy 195.28967 59.45207)
			(xy 195.28967 59.46027) (xy 195.28967 59.46846) (xy 195.28967 59.47665) (xy 195.28967 59.48485) (xy 195.28967 59.49305)
			(xy 195.28967 59.50124) (xy 195.28967 59.50943) (xy 195.28967 59.51763) (xy 195.28967 59.52582) (xy 195.28967 59.53402)
			(xy 195.28967 59.54221) (xy 195.28967 59.5504) (xy 195.28967 59.5586) (xy 195.28967 59.5668) (xy 195.28967 59.57499)
			(xy 195.28967 59.58318) (xy 195.28967 59.59138) (xy 195.28967 59.59957) (xy 195.28967 59.60777) (xy 195.28967 59.61596)
			(xy 195.28967 59.62416) (xy 195.28967 59.63235) (xy 195.28967 59.64054) (xy 195.28967 59.64874) (xy 195.28967 59.65693)
			(xy 195.28967 59.66513) (xy 195.28967 59.67332) (xy 195.28967 59.68152) (xy 195.28967 59.68971) (xy 195.28967 59.69791)
			(xy 195.28967 59.7061) (xy 195.28967 59.7143) (xy 195.28967 59.72249) (xy 195.28967 59.73069) (xy 195.28967 59.73888)
			(xy 195.28967 59.74707) (xy 195.28967 59.75527) (xy 195.28967 59.76346) (xy 195.28967 59.77166) (xy 195.28967 59.77985)
			(xy 195.28148 59.77985) (xy 195.28148 59.78805) (xy 195.28148 59.79624) (xy 195.27328 59.79624) (xy 195.27328 59.80443)
			(xy 195.27328 59.81263) (xy 195.26509 59.81263) (xy 195.26509 59.82082) (xy 195.2487 59.82082) (xy 195.2487 59.82902)
			(xy 195.23231 59.82902) (xy 195.23231 59.83721) (xy 193.66716 59.83721) (xy 193.66716 59.82902) (xy 193.64258 59.82902)
			(xy 193.64258 59.82082) (xy 193.63438 59.82082) (xy 193.63438 59.81263) (xy 193.62619 59.81263) (xy 193.62619 59.80443)
			(xy 193.618 59.80443) (xy 193.618 59.79624) (xy 193.618 59.78805) (xy 193.6098 59.78805) (xy 193.6098 59.77985)
			(xy 193.6098 59.77166) (xy 193.6098 59.76346) (xy 193.6098 59.75527) (xy 193.6098 59.74707) (xy 193.6098 59.73888)
			(xy 193.6098 59.73069) (xy 193.6098 59.72249) (xy 193.6098 59.7143) (xy 193.6098 59.7061) (xy 193.6098 59.69791)
			(xy 193.6098 59.68971) (xy 193.6098 59.68152) (xy 193.6098 59.67332) (xy 193.6098 59.66513) (xy 193.6098 59.65693)
			(xy 193.6098 59.64874) (xy 193.6098 59.64054) (xy 193.6098 59.63235) (xy 193.6098 59.62416) (xy 193.6098 59.61596)
			(xy 193.6098 59.60777) (xy 193.6098 59.59957) (xy 193.6098 59.59138) (xy 193.6098 59.58318) (xy 193.6098 59.57499)
			(xy 193.6098 59.5668) (xy 193.6098 59.5586) (xy 193.6098 59.5504) (xy 193.6098 59.54221) (xy 193.6098 59.53402)
			(xy 193.6098 59.52582) (xy 193.6098 59.51763) (xy 193.6098 59.50943) (xy 193.6098 59.50124) (xy 193.6098 59.49305)
			(xy 193.6098 59.48485) (xy 193.6098 59.47665) (xy 193.6098 59.46846) (xy 193.6098 59.46027) (xy 193.6098 59.45207)
			(xy 193.6098 59.44388) (xy 193.6098 59.43568) (xy 193.6098 59.42749) (xy 193.6098 59.41929) (xy 193.6098 59.4111)
			(xy 193.6098 59.4029) (xy 193.6098 59.39471) (xy 193.6098 59.38652) (xy 193.6098 59.37832) (xy 193.6098 59.37013)
			(xy 193.6098 59.36193) (xy 193.6098 59.35374) (xy 193.6098 59.34554) (xy 193.6098 59.33735) (xy 193.6098 59.32916)
			(xy 193.6098 59.32096) (xy 193.6098 59.31276) (xy 193.6098 59.30457) (xy 193.6098 59.29638) (xy 193.6098 59.28818)
			(xy 193.60161 59.28818) (xy 193.60161 59.27999) (xy 193.60161 59.27179) (xy 193.60161 59.2636) (xy 193.59341 59.2636)
			(xy 193.59341 59.2554) (xy 193.59341 59.24721) (xy 193.58522 59.24721) (xy 193.58522 59.23902) (xy 193.56883 59.23902)
			(xy 193.56883 59.23082) (xy 193.54425 59.23082) (xy 193.54425 59.22263) (xy 193.51966 59.22263) (xy 193.51966 59.23082)
			(xy 193.49508 59.23082) (xy 193.49508 59.23902) (xy 193.48688 59.23902) (xy 193.48688 59.24721) (xy 193.47869 59.24721)
			(xy 193.47869 59.2554) (xy 193.4705 59.2554) (xy 193.4705 59.2636) (xy 193.4623 59.2636) (xy 193.4623 59.27179)
			(xy 193.4623 59.27999) (xy 193.4623 59.28818) (xy 193.4623 59.29638) (xy 193.4541 59.29638) (xy 193.4541 59.30457)
			(xy 193.4541 59.31276) (xy 193.4541 59.32096) (xy 193.4541 59.32916) (xy 193.4541 59.33735) (xy 193.4541 59.34554)
			(xy 193.4541 59.35374) (xy 193.4541 59.36193) (xy 193.4541 59.37013) (xy 193.4541 59.37832) (xy 193.4541 59.38652)
			(xy 193.4541 59.39471) (xy 193.4541 59.4029) (xy 193.4541 59.4111) (xy 193.4541 59.41929) (xy 193.4541 59.42749)
			(xy 193.4541 59.43568) (xy 193.4541 59.44388) (xy 193.4541 59.45207) (xy 193.4541 59.46027) (xy 193.4541 59.46846)
			(xy 193.4541 59.47665) (xy 193.4541 59.48485) (xy 193.4541 59.49305) (xy 193.4541 59.50124) (xy 193.4541 59.50943)
			(xy 193.4541 59.51763) (xy 193.4541 59.52582) (xy 193.4541 59.53402) (xy 193.4541 59.54221) (xy 193.4541 59.5504)
			(xy 193.4541 59.5586) (xy 193.4541 59.5668) (xy 193.4541 59.57499) (xy 193.4541 59.58318) (xy 193.4541 59.59138)
			(xy 193.4541 59.59957) (xy 193.4541 59.60777) (xy 193.4541 59.61596) (xy 193.4541 59.62416) (xy 193.4541 59.63235)
			(xy 193.4541 59.64054) (xy 193.4541 59.64874) (xy 193.4541 59.65693) (xy 193.4541 59.66513) (xy 193.4541 59.67332)
			(xy 193.4541 59.68152) (xy 193.4541 59.68971) (xy 193.4541 59.69791) (xy 193.4541 59.7061) (xy 193.4541 59.7143)
			(xy 193.4541 59.72249) (xy 193.4541 59.73069) (xy 193.4541 59.73888) (xy 193.4541 59.74707) (xy 193.4541 59.75527)
			(xy 193.4541 59.76346) (xy 193.4541 59.77166) (xy 193.4541 59.77985) (xy 193.4541 59.78805) (xy 193.4541 59.79624)
			(xy 193.44591 59.79624) (xy 193.44591 59.80443) (xy 193.43772 59.80443) (xy 193.43772 59.81263) (xy 193.42952 59.81263)
			(xy 193.42952 59.82082) (xy 193.42133 59.82082) (xy 193.42133 59.82902) (xy 193.39674 59.82902) (xy 193.39674 59.83721)
			(xy 192.59368 59.83721) (xy 192.59368 59.82902) (xy 192.5773 59.82902) (xy 192.5773 59.82082) (xy 192.56091 59.82082)
			(xy 192.56091 59.81263) (xy 192.55271 59.81263) (xy 192.55271 59.80443) (xy 192.55271 59.79624) (xy 192.54452 59.79624)
			(xy 192.54452 59.78805) (xy 192.54452 59.77985) (xy 192.54452 59.77166) (xy 192.53632 59.77166) (xy 192.53632 59.76346)
			(xy 192.53632 59.75527) (xy 192.53632 59.74707) (xy 192.53632 59.73888) (xy 192.53632 59.73069) (xy 192.53632 59.72249)
			(xy 192.53632 59.7143) (xy 192.53632 59.7061) (xy 192.53632 59.69791) (xy 192.53632 59.68971) (xy 192.53632 59.68152)
			(xy 192.53632 59.67332) (xy 192.53632 59.66513) (xy 192.53632 59.65693) (xy 192.53632 59.64874) (xy 192.53632 59.64054)
			(xy 192.53632 59.63235) (xy 192.53632 59.62416) (xy 192.53632 59.61596) (xy 192.53632 59.60777) (xy 192.53632 59.59957)
			(xy 192.53632 59.59138) (xy 192.53632 59.58318) (xy 192.53632 59.57499) (xy 192.53632 59.5668) (xy 192.53632 59.5586)
			(xy 192.53632 59.5504) (xy 192.53632 59.54221) (xy 192.53632 59.53402) (xy 192.53632 59.52582) (xy 192.53632 59.51763)
			(xy 192.53632 59.50943) (xy 192.53632 59.50124) (xy 192.53632 59.49305) (xy 192.53632 59.48485) (xy 192.53632 59.47665)
			(xy 192.53632 59.46846) (xy 192.53632 59.46027) (xy 192.53632 59.45207) (xy 192.53632 59.44388) (xy 192.53632 59.43568)
			(xy 192.53632 59.42749) (xy 192.53632 59.41929) (xy 192.53632 59.4111) (xy 192.53632 59.4029) (xy 192.53632 59.39471)
			(xy 192.53632 59.38652) (xy 192.53632 59.37832) (xy 192.53632 59.37013) (xy 192.53632 59.36193) (xy 192.53632 59.35374)
			(xy 192.53632 59.34554) (xy 192.53632 59.33735) (xy 192.53632 59.32916) (xy 192.53632 59.32096) (xy 192.53632 59.31276)
			(xy 192.53632 59.30457) (xy 192.53632 59.29638) (xy 192.53632 59.28818) (xy 192.53632 59.27999) (xy 192.53632 59.27179)
			(xy 192.53632 59.2636) (xy 192.53632 59.2554) (xy 192.53632 59.24721) (xy 192.53632 59.23902) (xy 192.53632 59.23082)
			(xy 192.53632 59.22263) (xy 192.53632 59.21443) (xy 192.53632 59.20624) (xy 192.53632 59.19805) (xy 192.53632 59.18985)
			(xy 192.53632 59.18165) (xy 192.53632 59.17346) (xy 192.53632 59.16526) (xy 192.53632 59.15707) (xy 192.53632 59.14888)
			(xy 192.53632 59.14068) (xy 192.53632 59.13249) (xy 192.53632 59.12429) (xy 192.53632 59.1161) (xy 192.53632 59.1079)
			(xy 192.54452 59.1079) (xy 192.54452 59.09971) (xy 192.53632 59.09971) (xy 192.53632 59.09151) (xy 192.53632 59.08332)
			(xy 192.53632 59.07513) (xy 192.53632 59.06693) (xy 192.53632 59.05874) (xy 192.53632 59.05054) (xy 192.53632 59.04235)
			(xy 192.53632 59.03415) (xy 192.53632 59.02596) (xy 192.52813 59.02596) (xy 192.52813 59.01776) (xy 192.52813 59.00957)
			(xy 192.51993 59.00957) (xy 192.51993 59.00138) (xy 192.51993 58.99318) (xy 192.51174 58.99318) (xy 192.51174 58.98499)
			(xy 192.51174 58.97679) (xy 192.50355 58.97679) (xy 192.50355 58.9686) (xy 192.49535 58.9686) (xy 192.49535 58.9604)
			(xy 192.48715 58.9604) (xy 192.48715 58.95221) (xy 192.47896 58.95221) (xy 192.47896 58.94401) (xy 192.46257 58.94401)
			(xy 192.46257 58.93582) (xy 192.44618 58.93582) (xy 192.44618 58.92762) (xy 192.4216 58.92762) (xy 192.4216 58.91943)
			(xy 192.35604 58.91943) (xy 192.35604 58.92762) (xy 192.33146 58.92762) (xy 192.33146 58.93582) (xy 192.31507 58.93582)
			(xy 192.31507 58.94401) (xy 192.29868 58.94401) (xy 192.29868 58.95221) (xy 192.29049 58.95221) (xy 192.29049 58.9604)
			(xy 192.28229 58.9604) (xy 192.28229 58.9686) (xy 192.2741 58.9686) (xy 192.2741 58.97679) (xy 192.2659 58.97679)
			(xy 192.2659 58.98499) (xy 192.25771 58.98499) (xy 192.25771 58.99318) (xy 192.25771 59.00138) (xy 192.24951 59.00138)
			(xy 192.24951 59.00957) (xy 192.24951 59.01776) (xy 192.24132 59.01776) (xy 192.24132 59.02596) (xy 192.24132 59.03415)
			(xy 192.24132 59.04235) (xy 192.24132 59.05054) (xy 192.24132 59.05874) (xy 192.24132 59.06693) (xy 192.23313 59.06693)
			(xy 192.23313 59.07513) (xy 192.24132 59.07513) (xy 192.24132 59.08332) (xy 192.24132 59.09151) (xy 192.23313 59.09151)
			(xy 192.23313 59.09971) (xy 192.24132 59.09971) (xy 192.24132 59.1079) (xy 192.24132 59.1161) (xy 192.24132 59.12429)
			(xy 192.24132 59.13249) (xy 192.24132 59.14068) (xy 192.24132 59.14888) (xy 192.24132 59.15707) (xy 192.24132 59.16526)
			(xy 192.24132 59.17346) (xy 192.24132 59.18165) (xy 192.24132 59.18985) (xy 192.24132 59.19805) (xy 192.24132 59.20624)
			(xy 192.24132 59.21443) (xy 192.24132 59.22263) (xy 192.24132 59.23082) (xy 192.24132 59.23902) (xy 192.24132 59.24721)
			(xy 192.24132 59.2554) (xy 192.24132 59.2636) (xy 192.24132 59.27179) (xy 192.24132 59.27999) (xy 192.24132 59.28818)
			(xy 192.24132 59.29638) (xy 192.24132 59.30457) (xy 192.24132 59.31276) (xy 192.24132 59.32096) (xy 192.24132 59.32916)
			(xy 192.24132 59.33735) (xy 192.24132 59.34554) (xy 192.24132 59.35374) (xy 192.24132 59.36193) (xy 192.24132 59.37013)
			(xy 192.24132 59.37832) (xy 192.24132 59.38652) (xy 192.24132 59.39471) (xy 192.24132 59.4029) (xy 192.24132 59.4111)
			(xy 192.24132 59.41929) (xy 192.24132 59.42749) (xy 192.24132 59.43568) (xy 192.24132 59.44388) (xy 192.24132 59.45207)
			(xy 192.23313 59.45207) (xy 192.23313 59.46027) (xy 192.23313 59.46846) (xy 192.23313 59.47665) (xy 192.23313 59.48485)
			(xy 192.22493 59.48485) (xy 192.22493 59.49305) (xy 192.21674 59.49305) (xy 192.21674 59.50124) (xy 192.20854 59.50124)
			(xy 192.20854 59.50943) (xy 192.20035 59.50943) (xy 192.20035 59.51763) (xy 192.17576 59.51763) (xy 192.17576 59.52582)
			(xy 191.6841 59.52582) (xy 191.6841 59.51763) (xy 191.65951 59.51763) (xy 191.65951 59.50943) (xy 191.65132 59.50943)
			(xy 191.65132 59.50124) (xy 191.64312 59.50124) (xy 191.64312 59.49305) (xy 191.63493 59.49305) (xy 191.63493 59.48485)
			(xy 191.62673 59.48485) (xy 191.62673 59.47665) (xy 191.62673 59.46846) (xy 191.62673 59.46027) (xy 191.61854 59.46027)
			(xy 191.61854 59.45207) (xy 191.61854 59.44388) (xy 191.61854 59.43568) (xy 191.61854 59.42749) (xy 191.61854 59.41929)
			(xy 191.61854 59.4111) (xy 191.61854 59.4029) (xy 191.61854 59.39471) (xy 191.61854 59.38652) (xy 191.61854 59.37832)
			(xy 191.61854 59.37013) (xy 191.61854 59.36193) (xy 191.61854 59.35374) (xy 191.61854 59.34554) (xy 191.61854 59.33735)
			(xy 191.61854 59.32916) (xy 191.61854 59.32096) (xy 191.61854 59.31276) (xy 191.61854 59.30457) (xy 191.61854 59.29638)
			(xy 191.61854 59.28818) (xy 191.61854 59.27999) (xy 191.61854 59.27179) (xy 191.61854 59.2636) (xy 191.61854 59.2554)
			(xy 191.61854 59.24721) (xy 191.61854 59.23902) (xy 191.61854 59.23082) (xy 191.61854 59.22263) (xy 191.61854 59.21443)
			(xy 191.61854 59.20624) (xy 191.61854 59.19805) (xy 191.61854 59.18985) (xy 191.61854 59.18165) (xy 191.61854 59.17346)
			(xy 191.61854 59.16526) (xy 191.61854 59.15707) (xy 191.61854 59.14888) (xy 191.61854 59.14068) (xy 191.61854 59.13249)
			(xy 191.61854 59.12429) (xy 191.61854 59.1161) (xy 191.61854 59.1079) (xy 191.61854 59.09971) (xy 191.61854 59.09151)
			(xy 191.61854 59.08332) (xy 191.61854 59.07513) (xy 191.61854 59.06693) (xy 191.61854 59.05874) (xy 191.61854 59.05054)
			(xy 191.61854 59.04235) (xy 191.62673 59.04235) (xy 191.62673 59.03415) (xy 191.62673 59.02596) (xy 191.61854 59.02596)
			(xy 191.61854 59.01776) (xy 191.62673 59.01776) (xy 191.62673 59.00957) (xy 191.61854 59.00957) (xy 191.61854 59.00138)
			(xy 191.61854 58.99318) (xy 191.61854 58.98499) (xy 191.61854 58.97679) (xy 191.61854 58.9686) (xy 191.61854 58.9604)
			(xy 191.61034 58.9604) (xy 191.61034 58.95221) (xy 191.61034 58.94401) (xy 191.60215 58.94401) (xy 191.60215 58.93582)
			(xy 191.58576 58.93582) (xy 191.58576 58.92762) (xy 191.56937 58.92762) (xy 191.56937 58.91943) (xy 190.29923 58.91943)
			(xy 190.29923 58.92762) (xy 190.28284 58.92762) (xy 190.28284 58.93582) (xy 190.27464 58.93582) (xy 190.27464 58.94401)
			(xy 190.26645 58.94401) (xy 190.26645 58.95221) (xy 190.25825 58.95221) (xy 190.25825 58.9604) (xy 190.25825 58.9686)
			(xy 190.25006 58.9686) (xy 190.25006 58.97679) (xy 190.25006 58.98499) (xy 190.25006 58.99318) (xy 190.25006 59.00138)
			(xy 190.25006 59.00957) (xy 190.25006 59.01776) (xy 190.25006 59.02596) (xy 190.25006 59.03415) (xy 190.25006 59.04235)
			(xy 190.25006 59.05054) (xy 190.25006 59.05874) (xy 190.25006 59.06693) (xy 190.25006 59.07513) (xy 190.25006 59.08332)
			(xy 190.25006 59.09151) (xy 190.25006 59.09971) (xy 190.25006 59.1079) (xy 190.25006 59.1161) (xy 190.25006 59.12429)
			(xy 190.25006 59.13249) (xy 190.25006 59.14068) (xy 190.25006 59.14888) (xy 190.25006 59.15707) (xy 190.25006 59.16526)
			(xy 190.25006 59.17346) (xy 190.25006 59.18165) (xy 190.25006 59.18985) (xy 190.25006 59.19805) (xy 190.25006 59.20624)
			(xy 190.25006 59.21443) (xy 190.25006 59.22263) (xy 190.25006 59.23082) (xy 190.25006 59.23902) (xy 190.25006 59.24721)
			(xy 190.25006 59.2554) (xy 190.25006 59.2636) (xy 190.25006 59.27179) (xy 190.25006 59.27999) (xy 190.25006 59.28818)
			(xy 190.25006 59.29638) (xy 190.25006 59.30457) (xy 190.25006 59.31276) (xy 190.25006 59.32096) (xy 190.25006 59.32916)
			(xy 190.25006 59.33735) (xy 190.25006 59.34554) (xy 190.25006 59.35374) (xy 190.25006 59.36193) (xy 190.25006 59.37013)
			(xy 190.25006 59.37832) (xy 190.25006 59.38652) (xy 190.25006 59.39471) (xy 190.25006 59.4029) (xy 190.25006 59.4111)
			(xy 190.25006 59.41929) (xy 190.25006 59.42749) (xy 190.25006 59.43568) (xy 190.25006 59.44388) (xy 190.25006 59.45207)
			(xy 190.25006 59.46027) (xy 190.25006 59.46846) (xy 190.25006 59.47665) (xy 190.25006 59.48485) (xy 190.25006 59.49305)
			(xy 190.25006 59.50124) (xy 190.25006 59.50943) (xy 190.25006 59.51763) (xy 190.25006 59.52582) (xy 190.25006 59.53402)
			(xy 190.25006 59.54221) (xy 190.25006 59.5504) (xy 190.25006 59.5586) (xy 190.25006 59.5668) (xy 190.25006 59.57499)
			(xy 190.25006 59.58318) (xy 190.25006 59.59138) (xy 190.25006 59.59957) (xy 190.25006 59.60777) (xy 190.25006 59.61596)
			(xy 190.25006 59.62416) (xy 190.25006 59.63235) (xy 190.25006 59.64054) (xy 190.25006 59.64874) (xy 190.25006 59.65693)
			(xy 190.25006 59.66513) (xy 190.25006 59.67332) (xy 190.25006 59.68152) (xy 189.02908 59.68152) (xy 189.02908 59.67332)
			(xy 189.02908 59.66513) (xy 189.02908 59.65693) (xy 189.02908 59.64874) (xy 189.02908 59.64054) (xy 189.02908 59.63235)
			(xy 189.02908 59.62416) (xy 189.02908 59.61596) (xy 189.02908 59.60777) (xy 189.02908 59.59957) (xy 189.02908 59.59138)
			(xy 189.02908 59.58318) (xy 189.02908 59.57499) (xy 189.02908 59.5668) (xy 189.02908 59.5586) (xy 189.02908 59.5504)
			(xy 189.02908 59.54221) (xy 189.02908 59.53402) (xy 189.02908 59.52582) (xy 189.02908 59.51763) (xy 189.02908 59.50943)
			(xy 189.02908 59.50124) (xy 189.02908 59.49305) (xy 189.02908 59.48485) (xy 189.02908 59.47665) (xy 189.02908 59.46846)
			(xy 189.02908 59.46027) (xy 189.02908 59.45207) (xy 189.02908 59.44388) (xy 189.02908 59.43568) (xy 189.02908 59.42749)
			(xy 189.02908 59.41929) (xy 189.02908 59.4111) (xy 189.02908 59.4029) (xy 189.02908 59.39471) (xy 189.02908 59.38652)
			(xy 189.02908 59.37832) (xy 189.02908 59.37013) (xy 189.02908 59.36193) (xy 189.02908 59.35374) (xy 189.02908 59.34554)
			(xy 189.02908 59.33735) (xy 189.02908 59.32916) (xy 189.02908 59.32096) (xy 189.02908 59.31276) (xy 189.02908 59.30457)
			(xy 189.02908 59.29638) (xy 189.02908 59.28818) (xy 189.02908 59.27999) (xy 189.02908 59.27179) (xy 189.02908 59.2636)
			(xy 189.02908 59.2554) (xy 189.02908 59.24721) (xy 189.02908 59.23902) (xy 189.02908 59.23082) (xy 189.02908 59.22263)
			(xy 189.02908 59.21443) (xy 189.02908 59.20624) (xy 189.02908 59.19805) (xy 189.02908 59.18985) (xy 189.02908 59.18165)
			(xy 189.02908 59.17346) (xy 189.02908 59.16526) (xy 189.02908 59.15707) (xy 189.02908 59.14888) (xy 189.02908 59.14068)
			(xy 189.02908 59.13249) (xy 189.02908 59.12429) (xy 189.02908 59.1161) (xy 189.02908 59.1079) (xy 189.02908 59.09971)
			(xy 189.02908 59.09151) (xy 189.02908 59.08332) (xy 189.02908 59.07513) (xy 189.02908 59.06693) (xy 189.02908 59.05874)
			(xy 189.02908 59.05054) (xy 189.02908 59.04235) (xy 189.02908 59.03415) (xy 189.02908 59.02596) (xy 189.02908 59.01776)
			(xy 189.02908 59.00957) (xy 189.02908 59.00138) (xy 189.02908 58.99318) (xy 189.02908 58.98499) (xy 189.02908 58.97679)
			(xy 189.02908 58.9686) (xy 189.02908 58.9604) (xy 189.02908 58.95221) (xy 189.02908 58.94401) (xy 189.82394 58.94401)
			(xy 189.82394 58.93582) (xy 189.82394 58.92762) (xy 189.82394 58.91943) (xy 189.82394 58.91124) (xy 189.82394 58.90304)
			(xy 189.82394 58.89485) (xy 189.82394 58.88665) (xy 189.82394 58.87846) (xy 189.82394 58.87026) (xy 189.82394 58.86207)
			(xy 189.82394 58.85387) (xy 189.82394 58.84568) (xy 189.82394 58.83748) (xy 189.82394 58.82929) (xy 189.82394 58.82109)
			(xy 189.82394 58.8129) (xy 189.82394 58.80471) (xy 189.82394 58.79651) (xy 189.82394 58.78832) (xy 189.82394 58.78012)
			(xy 189.82394 58.77193) (xy 189.82394 58.76374) (xy 189.82394 58.75554) (xy 189.82394 58.74735) (xy 189.82394 58.73915)
			(xy 189.82394 58.73096) (xy 189.82394 58.72276) (xy 189.82394 58.71457) (xy 189.82394 58.70637) (xy 189.82394 58.69818)
			(xy 189.82394 58.68998) (xy 189.82394 58.68179) (xy 189.82394 58.67359) (xy 189.82394 58.6654) (xy 189.82394 58.65721)
			(xy 189.82394 58.64901) (xy 189.82394 58.64082) (xy 189.82394 58.63262) (xy 189.82394 58.62443) (xy 189.82394 58.61623)
			(xy 189.82394 58.60804) (xy 189.82394 58.59985) (xy 189.82394 58.59165) (xy 189.82394 58.58345) (xy 189.82394 58.57526)
			(xy 189.82394 58.56707) (xy 189.82394 58.55887) (xy 189.82394 58.55068) (xy 189.82394 58.54248) (xy 189.82394 58.53429)
			(xy 189.82394 58.52609) (xy 189.82394 58.5179) (xy 189.82394 58.50971) (xy 189.82394 58.50151) (xy 189.82394 58.49332)
			(xy 189.82394 58.48512) (xy 189.82394 58.47693) (xy 189.82394 58.46874) (xy 189.82394 58.46054) (xy 189.82394 58.45234)
			(xy 189.82394 58.44415) (xy 189.82394 58.43595) (xy 189.82394 58.42776) (xy 189.82394 58.41957) (xy 189.82394 58.41137)
			(xy 189.82394 58.40318) (xy 189.82394 58.39498) (xy 189.82394 58.38679) (xy 189.82394 58.37859) (xy 189.82394 58.3704)
			(xy 189.82394 58.36221) (xy 189.82394 58.35401) (xy 189.82394 58.34582) (xy 189.82394 58.33762) (xy 189.82394 58.32942)
			(xy 189.82394 58.32123) (xy 189.82394 58.31304) (xy 189.82394 58.30484) (xy 189.82394 58.29665) (xy 189.82394 58.28845)
			(xy 189.82394 58.28026) (xy 189.82394 58.27207) (xy 189.82394 58.26387) (xy 189.82394 58.25568) (xy 189.82394 58.24748)
			(xy 189.82394 58.23929) (xy 189.82394 58.23109) (xy 189.82394 58.2229) (xy 189.82394 58.2147) (xy 189.82394 58.20651)
			(xy 189.82394 58.19831) (xy 189.82394 58.19012) (xy 189.82394 58.18193) (xy 189.82394 58.17373) (xy 189.82394 58.16554)
			(xy 189.82394 58.15734) (xy 189.82394 58.14915) (xy 189.82394 58.14095) (xy 189.82394 58.13276) (xy 189.82394 58.12456)
			(xy 189.82394 58.11637) (xy 189.82394 58.10817) (xy 189.82394 58.09998) (xy 189.82394 58.09178) (xy 189.82394 58.08359)
			(xy 189.82394 58.0754) (xy 189.82394 58.0672) (xy 189.82394 58.05901) (xy 189.82394 58.05081) (xy 189.82394 58.04262)
			(xy 189.02908 58.04262) (xy 189.02908 58.03442) (xy 189.02908 58.02623) (xy 189.02908 58.01804) (xy 189.02908 58.00984)
			(xy 189.02908 58.00165) (xy 189.02908 57.99345) (xy 189.02908 57.98526) (xy 189.02908 57.97706) (xy 189.02908 57.96887)
			(xy 189.02908 57.96067) (xy 189.02908 57.95248) (xy 189.02908 57.94429) (xy 189.02908 57.93609) (xy 189.02908 57.9279)
			(xy 189.02908 57.9197) (xy 189.02908 57.91151) (xy 189.02908 57.90331) (xy 189.02908 57.89512) (xy 189.02908 57.88692)
			(xy 189.02908 57.87873) (xy 189.02908 57.87053) (xy 189.02908 57.86234) (xy 189.02908 57.85415) (xy 189.02908 57.84595)
			(xy 189.02908 57.83776) (xy 189.82394 57.83776) (xy 189.82394 57.82956) (xy 189.82394 57.82137) (xy 189.82394 57.81317)
			(xy 189.82394 57.80498) (xy 189.82394 57.79678) (xy 189.82394 57.78859) (xy 189.82394 57.7804) (xy 189.82394 57.7722)
			(xy 189.82394 57.76401) (xy 189.82394 57.75581) (xy 189.82394 57.74762) (xy 189.82394 57.73942) (xy 189.82394 57.73123)
			(xy 189.82394 57.72303) (xy 189.82394 57.71484) (xy 189.82394 57.70664) (xy 189.82394 57.69845) (xy 189.82394 57.69026)
			(xy 189.82394 57.68206) (xy 189.82394 57.67387) (xy 189.82394 57.66567) (xy 189.82394 57.65748) (xy 189.82394 57.64928)
			(xy 189.82394 57.64109) (xy 189.82394 57.63289) (xy 189.82394 57.6247) (xy 189.82394 57.61651) (xy 189.82394 57.60831)
			(xy 189.82394 57.60011) (xy 189.82394 57.59192) (xy 189.82394 57.58373) (xy 189.82394 57.57553) (xy 189.82394 57.56734)
			(xy 189.82394 57.55914) (xy 189.82394 57.55095) (xy 189.82394 57.54276) (xy 189.82394 57.53456) (xy 189.82394 57.52637)
			(xy 189.82394 57.51817) (xy 189.82394 57.50998) (xy 189.82394 57.50178) (xy 189.82394 57.49359) (xy 189.82394 57.48539)
			(xy 189.82394 57.4772) (xy 189.82394 57.469) (xy 189.82394 57.46081) (xy 189.82394 57.45262) (xy 189.82394 57.44442)
			(xy 189.82394 57.43623) (xy 189.82394 57.42803) (xy 189.82394 57.41984) (xy 189.82394 57.41164) (xy 189.82394 57.40345)
			(xy 189.82394 57.39526) (xy 189.82394 57.38706) (xy 189.82394 57.37886) (xy 189.82394 57.37067) (xy 189.82394 57.36248)
			(xy 189.82394 57.35428) (xy 189.82394 57.34609) (xy 189.82394 57.33789) (xy 189.82394 57.3297) (xy 189.82394 57.3215)
			(xy 189.82394 57.31331) (xy 189.82394 57.30511) (xy 189.82394 57.29692) (xy 189.82394 57.28872) (xy 189.82394 57.28053)
			(xy 189.82394 57.27234) (xy 189.82394 57.26414) (xy 189.82394 57.25595) (xy 189.82394 57.24775) (xy 189.82394 57.23956)
			(xy 189.82394 57.23136) (xy 189.82394 57.22317) (xy 189.82394 57.21498) (xy 189.82394 57.20678) (xy 189.82394 57.19859)
			(xy 189.82394 57.19039) (xy 189.82394 57.18219) (xy 189.82394 57.174) (xy 189.82394 57.16581) (xy 189.82394 57.15761)
			(xy 189.82394 57.14942) (xy 189.82394 57.14122) (xy 189.82394 57.13303) (xy 189.82394 57.12484) (xy 189.82394 57.11664)
			(xy 189.82394 57.10845) (xy 189.82394 57.10025) (xy 189.82394 57.09206) (xy 189.82394 57.08386) (xy 189.82394 57.07567)
			(xy 189.82394 57.06747) (xy 189.82394 57.05928) (xy 189.82394 57.05109) (xy 189.82394 57.04289) (xy 189.82394 57.0347)
			(xy 189.82394 57.0265) (xy 189.82394 57.01831) (xy 189.82394 57.01011) (xy 189.82394 57.00192) (xy 189.82394 56.99372)
			(xy 189.82394 56.98553) (xy 189.82394 56.97734) (xy 189.82394 56.96914) (xy 189.82394 56.96095) (xy 189.82394 56.95275)
			(xy 189.82394 56.94455) (xy 189.82394 56.93636) (xy 189.03727 56.93636) (xy 189.03727 56.92817) (xy 189.02908 56.92817)
			(xy 189.02908 56.91997) (xy 189.02908 56.91178) (xy 189.02908 56.90358) (xy 189.02908 56.89539) (xy 189.02908 56.88719)
			(xy 189.02908 56.879) (xy 189.02908 56.87081) (xy 189.02908 56.86261) (xy 189.02908 56.85442) (xy 189.02908 56.84622)
			(xy 189.02908 56.83803) (xy 189.02908 56.82983) (xy 189.02908 56.82164) (xy 189.02908 56.81345) (xy 189.02908 56.80525)
			(xy 189.02908 56.79706) (xy 189.02908 56.78886) (xy 189.02908 56.78067) (xy 189.02908 56.77247) (xy 189.02908 56.76428)
			(xy 189.02908 56.75608) (xy 189.02908 56.74789) (xy 189.02908 56.73969) (xy 189.02908 56.7315) (xy 189.82394 56.7315)
			(xy 189.82394 56.72331) (xy 189.82394 56.71511) (xy 189.82394 56.70692) (xy 189.82394 56.69872) (xy 189.82394 56.69053)
			(xy 189.82394 56.68233) (xy 189.82394 56.67414) (xy 189.82394 56.66594) (xy 189.82394 56.65775) (xy 189.82394 56.64955)
			(xy 189.82394 56.64136) (xy 189.82394 56.63317) (xy 189.82394 56.62497) (xy 189.82394 56.61678) (xy 189.82394 56.60858)
			(xy 189.82394 56.60039) (xy 189.82394 56.59219) (xy 189.82394 56.584) (xy 189.82394 56.5758) (xy 189.82394 56.56761)
			(xy 189.82394 56.55942) (xy 189.82394 56.55122) (xy 189.82394 56.54303) (xy 189.82394 56.53483) (xy 189.82394 56.52664)
			(xy 189.82394 56.51844) (xy 189.82394 56.51025) (xy 189.82394 56.50205) (xy 189.82394 56.49386) (xy 189.82394 56.48567)
			(xy 189.82394 56.47747) (xy 189.82394 56.46928) (xy 189.82394 56.46108) (xy 189.82394 56.45289) (xy 189.82394 56.44469)
			(xy 189.82394 56.4365) (xy 189.82394 56.42831) (xy 189.82394 56.42011) (xy 189.82394 56.41191) (xy 189.82394 56.40372)
			(xy 189.82394 56.39553) (xy 189.82394 56.38733) (xy 189.82394 56.37914) (xy 189.82394 56.37094) (xy 189.82394 56.36275)
			(xy 189.82394 56.35455) (xy 189.82394 56.34636) (xy 189.82394 56.33816) (xy 189.82394 56.32997) (xy 189.82394 56.32177)
			(xy 189.82394 56.31358) (xy 189.82394 56.30539) (xy 189.82394 56.29719) (xy 189.82394 56.289) (xy 189.82394 56.2808)
			(xy 189.82394 56.27261) (xy 189.82394 56.26441) (xy 189.82394 56.25622) (xy 189.82394 56.24803) (xy 189.82394 56.23983)
			(xy 189.82394 56.23164) (xy 189.82394 56.22344) (xy 189.82394 56.21524) (xy 189.82394 56.20705) (xy 189.82394 56.19886)
			(xy 189.82394 56.19066) (xy 189.82394 56.18247) (xy 189.82394 56.17427) (xy 189.82394 56.16608) (xy 189.82394 56.15788)
			(xy 189.82394 56.14969) (xy 189.82394 56.1415) (xy 189.82394 56.1333) (xy 189.82394 56.12511) (xy 189.82394 56.11691)
			(xy 189.82394 56.10872) (xy 189.82394 56.10053) (xy 189.82394 56.09233) (xy 189.82394 56.08413) (xy 189.82394 56.07594)
			(xy 189.82394 56.06775) (xy 189.82394 56.05955) (xy 189.82394 56.05136) (xy 189.82394 56.04316) (xy 189.82394 56.03497)
			(xy 189.82394 56.02677) (xy 189.82394 56.01858) (xy 189.82394 56.01039) (xy 189.82394 56.00219) (xy 189.82394 55.994)
			(xy 189.82394 55.9858) (xy 189.82394 55.97761) (xy 189.82394 55.96941) (xy 189.82394 55.96122) (xy 189.82394 55.95302)
			(xy 189.82394 55.94483) (xy 189.82394 55.93663) (xy 189.82394 55.92844) (xy 189.82394 55.92024) (xy 189.82394 55.91205)
			(xy 189.82394 55.90386) (xy 189.82394 55.89566) (xy 189.82394 55.88747) (xy 189.82394 55.87927) (xy 189.82394 55.87108)
			(xy 189.82394 55.86288) (xy 189.82394 55.85469) (xy 189.82394 55.84649) (xy 189.82394 55.8383) (xy 189.82394 55.83011)
			(xy 189.82394 55.82191) (xy 189.02908 55.82191) (xy 189.02908 55.81372) (xy 189.02908 55.80552) (xy 189.02908 55.79733)
			(xy 189.02908 55.78913) (xy 189.02908 55.78094) (xy 189.02908 55.77274) (xy 189.02908 55.76455) (xy 189.02908 55.75636)
			(xy 189.02908 55.74816) (xy 189.02908 55.73997) (xy 189.02908 55.73177) (xy 189.02908 55.72358) (xy 189.02908 55.71538)
			(xy 189.02908 55.70719) (xy 189.02908 55.69899) (xy 189.02908 55.6908) (xy 189.02908 55.6826) (xy 189.02908 55.67441)
			(xy 189.02908 55.66622) (xy 189.02908 55.65802) (xy 189.02908 55.64983) (xy 189.02908 55.64163) (xy 189.02908 55.63344)
			(xy 189.02908 55.62524) (xy 189.03727 55.62524) (xy 189.03727 55.61705) (xy 189.82394 55.61705) (xy 189.82394 55.60885)
			(xy 189.82394 55.60066) (xy 189.82394 55.59247) (xy 189.82394 55.58427) (xy 189.82394 55.57608) (xy 189.82394 55.56788)
			(xy 189.82394 55.55969) (xy 189.82394 55.55149) (xy 189.82394 55.5433) (xy 189.82394 55.5351) (xy 189.82394 55.52691)
			(xy 189.82394 55.51872) (xy 189.82394 55.51052) (xy 189.82394 55.50233) (xy 189.82394 55.49413) (xy 189.82394 55.48594)
			(xy 189.82394 55.47774) (xy 189.82394 55.46955) (xy 189.82394 55.46136) (xy 189.82394 55.45316) (xy 189.82394 55.44496)
			(xy 189.82394 55.43677) (xy 189.82394 55.42857) (xy 189.82394 55.42038) (xy 189.82394 55.41219) (xy 189.82394 55.40399)
			(xy 189.82394 55.3958) (xy 189.82394 55.3876) (xy 190.92201 55.3876) (xy 190.92201 55.3958) (xy 190.92201 55.40399)
			(xy 190.92201 55.41219) (xy 190.92201 55.42038) (xy 190.92201 55.42857) (xy 190.92201 55.43677) (xy 190.92201 55.44496)
			(xy 190.92201 55.45316) (xy 190.92201 55.46136) (xy 190.92201 55.46955) (xy 190.9302 55.46955) (xy 190.9302 55.47774)
			(xy 190.9302 55.48594) (xy 190.9302 55.49413) (xy 190.9302 55.50233) (xy 190.9302 55.51052) (xy 190.9302 55.51872)
			(xy 190.9302 55.52691) (xy 190.9302 55.5351) (xy 190.9302 55.5433) (xy 190.9302 55.55149) (xy 190.9302 55.55969)
			(xy 190.9384 55.55969) (xy 190.9384 55.56788) (xy 190.9302 55.56788) (xy 190.9302 55.57608) (xy 190.9384 55.57608)
			(xy 190.9384 55.58427) (xy 190.9384 55.59247) (xy 190.9384 55.60066) (xy 190.9384 55.60885) (xy 190.9384 55.61705)
			(xy 190.9384 55.62524) (xy 190.9384 55.63344) (xy 190.9384 55.64163) (xy 190.9384 55.64983) (xy 190.9384 55.65802)
			(xy 190.94659 55.65802) (xy 190.94659 55.66622) (xy 190.94659 55.67441) (xy 190.94659 55.6826) (xy 190.94659 55.6908)
			(xy 190.94659 55.69899) (xy 190.94659 55.70719) (xy 190.94659 55.71538) (xy 190.94659 55.72358) (xy 190.95479 55.72358)
			(xy 190.95479 55.73177) (xy 190.95479 55.73997) (xy 190.95479 55.74816) (xy 190.95479 55.75636) (xy 190.95479 55.76455)
			(xy 190.95479 55.77274) (xy 190.95479 55.78094) (xy 190.96298 55.78094) (xy 190.96298 55.78913) (xy 190.96298 55.79733)
			(xy 190.96298 55.80552) (xy 190.96298 55.81372) (xy 190.96298 55.82191) (xy 190.96298 55.83011) (xy 190.97117 55.83011)
			(xy 190.97117 55.8383) (xy 190.97117 55.84649) (xy 190.97117 55.85469) (xy 190.97117 55.86288) (xy 190.97117 55.87108)
			(xy 190.97937 55.87108) (xy 190.97937 55.87927) (xy 190.97937 55.88747) (xy 190.97937 55.89566) (xy 190.97937 55.90386)
			(xy 190.97937 55.91205) (xy 190.98756 55.91205) (xy 190.98756 55.92024) (xy 190.98756 55.92844) (xy 190.98756 55.93663)
			(xy 190.98756 55.94483) (xy 190.98756 55.95302) (xy 190.99576 55.95302) (xy 190.99576 55.96122) (xy 190.99576 55.96941)
			(xy 190.99576 55.97761) (xy 190.99576 55.9858) (xy 190.99576 55.994) (xy 191.00395 55.994) (xy 191.00395 56.00219)
			(xy 191.00395 56.01039) (xy 191.00395 56.01858) (xy 191.00395 56.02677) (xy 191.01215 56.02677) (xy 191.01215 56.03497)
			(xy 191.01215 56.04316) (xy 191.01215 56.05136) (xy 191.01215 56.05955) (xy 191.02034 56.05955) (xy 191.02034 56.06775)
			(xy 191.02034 56.07594) (xy 191.02034 56.08413) (xy 191.02034 56.09233) (xy 191.02853 56.09233) (xy 191.02853 56.10053)
			(xy 191.02853 56.10872) (xy 191.02853 56.11691) (xy 191.02853 56.12511) (xy 191.03673 56.12511) (xy 191.03673 56.1333)
			(xy 191.03673 56.1415) (xy 191.03673 56.14969) (xy 191.04492 56.14969) (xy 191.04492 56.15788) (xy 191.04492 56.16608)
			(xy 191.04492 56.17427) (xy 191.04492 56.18247) (xy 191.05312 56.18247) (xy 191.05312 56.19066) (xy 191.05312 56.19886)
			(xy 191.05312 56.20705) (xy 191.06132 56.20705) (xy 191.06132 56.21524) (xy 191.06132 56.22344) (xy 191.06132 56.23164)
			(xy 191.06951 56.23164) (xy 191.06951 56.23983) (xy 191.06951 56.24803) (xy 191.06951 56.25622) (xy 191.0777 56.25622)
			(xy 191.0777 56.26441) (xy 191.0777 56.27261) (xy 191.0777 56.2808) (xy 191.0859 56.2808) (xy 191.0859 56.289)
			(xy 191.0859 56.29719) (xy 191.0859 56.30539) (xy 191.09409 56.30539) (xy 191.09409 56.31358) (xy 191.09409 56.32177)
			(xy 191.09409 56.32997) (xy 191.10229 56.32997) (xy 191.10229 56.33816) (xy 191.10229 56.34636) (xy 191.10229 56.35455)
			(xy 191.11048 56.35455) (xy 191.11048 56.36275) (xy 191.11048 56.37094) (xy 191.11048 56.37914) (xy 191.11867 56.37914)
			(xy 191.11867 56.38733) (xy 191.11867 56.39553) (xy 191.11867 56.40372) (xy 191.12687 56.40372) (xy 191.12687 56.41191)
			(xy 191.12687 56.42011) (xy 191.13506 56.42011) (xy 191.13506 56.42831) (xy 191.13506 56.4365) (xy 191.13506 56.44469)
			(xy 191.14326 56.44469) (xy 191.14326 56.45289) (xy 191.14326 56.46108) (xy 191.15145 56.46108) (xy 191.15145 56.46928)
			(xy 191.15145 56.47747) (xy 191.15145 56.48567) (xy 191.15965 56.48567) (xy 191.15965 56.49386) (xy 191.15965 56.50205)
			(xy 191.16784 56.50205) (xy 191.16784 56.51025) (xy 191.16784 56.51844) (xy 191.16784 56.52664) (xy 191.17604 56.52664)
			(xy 191.17604 56.53483) (xy 191.17604 56.54303) (xy 191.18423 56.54303) (xy 191.18423 56.55122) (xy 191.18423 56.55942)
			(xy 191.19243 56.55942) (xy 191.19243 56.56761) (xy 191.19243 56.5758) (xy 191.19243 56.584) (xy 191.20062 56.584)
			(xy 191.20062 56.59219) (xy 191.20062 56.60039) (xy 191.20881 56.60039) (xy 191.20881 56.60858) (xy 191.20881 56.61678)
			(xy 191.21701 56.61678) (xy 191.21701 56.62497) (xy 191.21701 56.63317) (xy 191.2252 56.63317) (xy 191.2252 56.64136)
			(xy 191.2252 56.64955) (xy 191.2334 56.64955) (xy 191.2334 56.65775) (xy 191.2334 56.66594) (xy 191.24159 56.66594)
			(xy 191.24159 56.67414) (xy 191.24159 56.68233) (xy 191.24979 56.68233) (xy 191.24979 56.69053) (xy 191.24979 56.69872)
			(xy 191.25798 56.69872) (xy 191.25798 56.70692) (xy 191.25798 56.71511) (xy 191.26618 56.71511) (xy 191.26618 56.72331)
			(xy 191.26618 56.7315) (xy 191.27437 56.7315) (xy 191.27437 56.73969) (xy 191.27437 56.74789) (xy 191.28256 56.74789)
			(xy 191.28256 56.75608) (xy 191.28256 56.76428) (xy 191.29076 56.76428) (xy 191.29076 56.77247) (xy 191.29076 56.78067)
			(xy 191.29896 56.78067) (xy 191.29896 56.78886) (xy 191.29896 56.79706) (xy 191.30715 56.79706) (xy 191.30715 56.80525)
			(xy 191.31534 56.80525) (xy 191.31534 56.81345) (xy 191.31534 56.82164) (xy 191.32354 56.82164) (xy 191.32354 56.82983)
			(xy 191.32354 56.83803) (xy 191.33173 56.83803) (xy 191.33173 56.84622) (xy 191.33173 56.85442) (xy 191.33993 56.85442)
			(xy 191.33993 56.86261) (xy 191.33993 56.87081) (xy 191.34812 56.87081) (xy 191.34812 56.879) (xy 191.35632 56.879)
			(xy 191.35632 56.88719) (xy 191.35632 56.89539) (xy 191.36451 56.89539) (xy 191.36451 56.90358) (xy 191.36451 56.91178)
			(xy 191.3727 56.91178) (xy 191.3727 56.91997) (xy 191.3727 56.92817) (xy 191.3809 56.92817) (xy 191.3809 56.93636)
			(xy 191.38909 56.93636) (xy 191.38909 56.94455) (xy 191.38909 56.95275) (xy 191.39729 56.95275) (xy 191.39729 56.96095)
			(xy 191.40548 56.96095) (xy 191.40548 56.96914) (xy 191.40548 56.97734) (xy 191.41367 56.97734) (xy 191.41367 56.98553)
			(xy 191.41367 56.99372) (xy 191.42187 56.99372) (xy 191.42187 57.00192) (xy 191.43007 57.00192) (xy 191.43007 57.01011)
			(xy 191.43007 57.01831) (xy 191.43826 57.01831) (xy 191.43826 57.0265) (xy 191.44645 57.0265) (xy 191.44645 57.0347)
			(xy 191.44645 57.04289) (xy 191.45465 57.04289) (xy 191.45465 57.05109) (xy 191.46284 57.05109) (xy 191.46284 57.05928)
			(xy 191.46284 57.06747) (xy 191.47104 57.06747) (xy 191.47104 57.07567) (xy 191.47923 57.07567) (xy 191.47923 57.08386)
			(xy 191.47923 57.09206) (xy 191.48743 57.09206) (xy 191.48743 57.10025) (xy 191.49562 57.10025) (xy 191.49562 57.10845)
			(xy 191.50382 57.10845) (xy 191.50382 57.11664) (xy 191.50382 57.12484) (xy 191.51201 57.12484) (xy 191.51201 57.13303)
			(xy 191.5202 57.13303) (xy 191.5202 57.14122) (xy 191.5202 57.14942) (xy 191.5284 57.14942) (xy 191.5284 57.15761)
			(xy 191.53659 57.15761) (xy 191.53659 57.16581) (xy 191.54479 57.16581) (xy 191.54479 57.174) (xy 191.54479 57.18219)
			(xy 191.55298 57.18219) (xy 191.55298 57.19039) (xy 191.56118 57.19039) (xy 191.56118 57.19859) (xy 191.56937 57.19859)
			(xy 191.56937 57.20678) (xy 191.56937 57.21498) (xy 191.57757 57.21498) (xy 191.57757 57.22317) (xy 191.58576 57.22317)
			(xy 191.58576 57.23136) (xy 191.59396 57.23136) (xy 191.59396 57.23956) (xy 191.60215 57.23956) (xy 191.60215 57.24775)
			(xy 191.60215 57.25595) (xy 191.61034 57.25595) (xy 191.61034 57.26414) (xy 191.61854 57.26414) (xy 191.61854 57.27234)
			(xy 191.62673 57.27234) (xy 191.62673 57.28053) (xy 191.63493 57.28053) (xy 191.63493 57.28872) (xy 191.63493 57.29692)
			(xy 191.64312 57.29692) (xy 191.64312 57.30511) (xy 191.65132 57.30511) (xy 191.65132 57.31331) (xy 191.65951 57.31331)
			(xy 191.65951 57.3215) (xy 191.66771 57.3215) (xy 191.66771 57.3297) (xy 191.66771 57.33789) (xy 191.6759 57.33789)
			(xy 191.6759 57.34609) (xy 191.6841 57.34609) (xy 191.6841 57.35428) (xy 191.69229 57.35428) (xy 191.69229 57.36248)
			(xy 191.70048 57.36248) (xy 191.70048 57.37067) (xy 191.70868 57.37067) (xy 191.70868 57.37886) (xy 191.71687 57.37886)
			(xy 191.71687 57.38706) (xy 191.72507 57.38706) (xy 191.72507 57.39526) (xy 191.72507 57.40345) (xy 191.73326 57.40345)
			(xy 191.73326 57.41164) (xy 191.74146 57.41164) (xy 191.74146 57.41984) (xy 191.74965 57.41984) (xy 191.74965 57.42803)
			(xy 191.75784 57.42803) (xy 191.75784 57.43623) (xy 191.76604 57.43623) (xy 191.76604 57.44442) (xy 191.77424 57.44442)
			(xy 191.77424 57.45262) (xy 191.78243 57.45262) (xy 191.78243 57.46081) (xy 191.79063 57.46081) (xy 191.79063 57.469)
			(xy 191.79882 57.469) (xy 191.79882 57.4772) (xy 191.80701 57.4772) (xy 191.80701 57.48539) (xy 191.81521 57.48539)
			(xy 191.81521 57.49359) (xy 191.8234 57.49359) (xy 191.8234 57.50178) (xy 191.8316 57.50178) (xy 191.8316 57.50998)
			(xy 191.83979 57.50998) (xy 191.83979 57.51817) (xy 191.84798 57.51817) (xy 191.84798 57.52637) (xy 191.85618 57.52637)
			(xy 191.85618 57.53456) (xy 191.86437 57.53456) (xy 191.86437 57.54276) (xy 191.87257 57.54276) (xy 191.87257 57.55095)
			(xy 191.88076 57.55095) (xy 191.88076 57.55914) (xy 191.88896 57.55914) (xy 191.88896 57.56734) (xy 191.89715 57.56734)
			(xy 191.89715 57.57553) (xy 191.90534 57.57553) (xy 191.90534 57.58373) (xy 191.91354 57.58373) (xy 191.91354 57.59192)
			(xy 191.92174 57.59192) (xy 191.92174 57.60011) (xy 191.92993 57.60011) (xy 191.92993 57.60831) (xy 191.93812 57.60831)
			(xy 191.93812 57.61651) (xy 191.94632 57.61651) (xy 191.94632 57.6247) (xy 191.95451 57.6247) (xy 191.95451 57.63289)
			(xy 191.96271 57.63289) (xy 191.96271 57.64109) (xy 191.9709 57.64109) (xy 191.9709 57.64928) (xy 191.98729 57.64928)
			(xy 191.98729 57.65748) (xy 191.99548 57.65748) (xy 191.99548 57.66567) (xy 192.00368 57.66567) (xy 192.00368 57.67387)
			(xy 192.01188 57.67387) (xy 192.01188 57.68206) (xy 192.02007 57.68206) (xy 192.02007 57.69026) (xy 192.02826 57.69026)
			(xy 192.02826 57.69845) (xy 192.03646 57.69845) (xy 192.03646 57.70664) (xy 192.05285 57.70664) (xy 192.05285 57.71484)
			(xy 192.06104 57.71484) (xy 192.06104 57.72303) (xy 192.06924 57.72303) (xy 192.06924 57.73123) (xy 192.07743 57.73123)
			(xy 192.07743 57.73942) (xy 192.08563 57.73942) (xy 192.08563 57.74762) (xy 192.10201 57.74762) (xy 192.10201 57.75581)
			(xy 192.11021 57.75581) (xy 192.11021 57.76401) (xy 192.1184 57.76401) (xy 192.1184 57.7722) (xy 192.1266 57.7722)
			(xy 192.1266 57.7804) (xy 192.14298 57.7804) (xy 192.14298 57.78859) (xy 192.15118 57.78859) (xy 192.15118 57.79678)
			(xy 192.15938 57.79678) (xy 192.15938 57.80498) (xy 192.17576 57.80498) (xy 192.17576 57.81317) (xy 192.18396 57.81317)
			(xy 192.18396 57.82137) (xy 192.19215 57.82137) (xy 192.19215 57.82956) (xy 192.20854 57.82956) (xy 192.20854 57.83776)
			(xy 192.21674 57.83776) (xy 192.21674 57.84595) (xy 192.22493 57.84595) (xy 192.22493 57.85415) (xy 192.24132 57.85415)
			(xy 192.24132 57.86234) (xy 192.24951 57.86234) (xy 192.24951 57.87053) (xy 192.2659 57.87053) (xy 192.2659 57.87873)
			(xy 192.2741 57.87873) (xy 192.2741 57.88692) (xy 192.28229 57.88692) (xy 192.28229 57.89512) (xy 192.29868 57.89512)
			(xy 192.29868 57.90331) (xy 192.30688 57.90331) (xy 192.30688 57.91151) (xy 192.32327 57.91151) (xy 192.32327 57.9197)
			(xy 192.33146 57.9197) (xy 192.33146 57.9279) (xy 192.34785 57.9279) (xy 192.34785 57.93609) (xy 192.35604 57.93609)
			(xy 192.35604 57.94429) (xy 192.37243 57.94429) (xy 192.37243 57.95248) (xy 192.38063 57.95248) (xy 192.38063 57.96067)
			(xy 192.39702 57.96067) (xy 192.39702 57.96887) (xy 192.4134 57.96887) (xy 192.4134 57.97706) (xy 192.4216 57.97706)
			(xy 192.4216 57.98526) (xy 192.43799 57.98526) (xy 192.43799 57.99345) (xy 192.44618 57.99345) (xy 192.44618 58.00165)
			(xy 192.46257 58.00165) (xy 192.46257 58.00984) (xy 192.47896 58.00984) (xy 192.47896 58.01804) (xy 192.48715 58.01804)
			(xy 192.48715 58.02623) (xy 192.50355 58.02623) (xy 192.50355 58.03442) (xy 192.51993 58.03442) (xy 192.51993 58.04262)
			(xy 192.53632 58.04262) (xy 192.53632 58.05081) (xy 192.54452 58.05081) (xy 192.54452 58.05901) (xy 192.56091 58.05901)
			(xy 192.56091 58.0672) (xy 192.5773 58.0672) (xy 192.5773 58.0754) (xy 192.59368 58.0754) (xy 192.59368 58.08359)
			(xy 192.61007 58.08359) (xy 192.61007 58.09178) (xy 192.62646 58.09178) (xy 192.62646 58.09998) (xy 192.64285 58.09998)
			(xy 192.64285 58.10817) (xy 192.65924 58.10817) (xy 192.65924 58.11637) (xy 192.67563 58.11637) (xy 192.67563 58.12456)
			(xy 192.69202 58.12456) (xy 192.69202 58.13276) (xy 192.70841 58.13276) (xy 192.70841 58.14095) (xy 192.72479 58.14095)
			(xy 192.72479 58.14915) (xy 192.74119 58.14915) (xy 192.74119 58.15734) (xy 192.75757 58.15734) (xy 192.75757 58.16554)
			(xy 192.77396 58.16554) (xy 192.77396 58.17373) (xy 192.79035 58.17373) (xy 192.79035 58.18193) (xy 192.81494 58.18193)
			(xy 192.81494 58.19012) (xy 192.83132 58.19012) (xy 192.83132 58.19831) (xy 192.84771 58.19831) (xy 192.84771 58.20651)
			(xy 192.8723 58.20651) (xy 192.8723 58.2147) (xy 192.88869 58.2147) (xy 192.88869 58.2229) (xy 192.91327 58.2229)
			(xy 192.91327 58.23109) (xy 192.92966 58.23109) (xy 192.92966 58.23929) (xy 192.95424 58.23929) (xy 192.95424 58.24748)
			(xy 192.97063 58.24748) (xy 192.97063 58.25568) (xy 192.99521 58.25568) (xy 192.99521 58.26387) (xy 193.0198 58.26387)
			(xy 193.0198 58.27207) (xy 193.04438 58.27207) (xy 193.04438 58.28026) (xy 193.06077 58.28026) (xy 193.06077 58.28845)
			(xy 193.08535 58.28845) (xy 193.08535 58.29665) (xy 193.10994 58.29665) (xy 193.10994 58.30484) (xy 193.14271 58.30484)
			(xy 193.14271 58.31304) (xy 193.1673 58.31304) (xy 193.1673 58.32123) (xy 193.19188 58.32123) (xy 193.19188 58.32942)
			(xy 193.22466 58.32942) (xy 193.22466 58.33762) (xy 193.24924 58.33762) (xy 193.24924 58.34582) (xy 193.28202 58.34582)
			(xy 193.28202 58.35401) (xy 193.3148 58.35401) (xy 193.3148 58.36221) (xy 193.34758 58.36221) (xy 193.34758 58.3704)
			(xy 193.38036 58.3704) (xy 193.38036 58.37859) (xy 193.42133 58.37859) (xy 193.42133 58.38679) (xy 193.4541 58.38679)
			(xy 193.4541 58.39498) (xy 193.49508 58.39498) (xy 193.49508 58.40318) (xy 193.54425 58.40318) (xy 193.54425 58.41137)
			(xy 193.59341 58.41137) (xy 193.59341 58.41957) (xy 193.65077 58.41957) (xy 193.65077 58.42776) (xy 193.70814 58.42776)
			(xy 193.70814 58.43595) (xy 193.79008 58.43595) (xy 193.79008 58.44415) (xy 193.88841 58.44415) (xy 193.88841 58.45234)
			(xy 194.28175 58.45234) (xy 194.28175 58.44415) (xy 194.38828 58.44415) (xy 194.38828 58.43595) (xy 194.46203 58.43595)
			(xy 194.46203 58.42776) (xy 194.52759 58.42776) (xy 194.52759 58.41957) (xy 194.58495 58.41957) (xy 194.58495 58.41137)
			(xy 194.63411 58.41137) (xy 194.63411 58.40318) (xy 194.67509 58.40318) (xy 194.67509 58.39498) (xy 194.72425 58.39498)
			(xy 194.72425 58.38679) (xy 194.75703 58.38679) (xy 194.75703 58.37859) (xy 194.78981 58.37859) (xy 194.78981 58.3704)
			(xy 194.83078 58.3704) (xy 194.83078 58.36221) (xy 194.86356 58.36221) (xy 194.86356 58.35401) (xy 194.89633 58.35401)
			(xy 194.89633 58.34582) (xy 194.92912 58.34582) (xy 194.92912 58.33762) (xy 194.9537 58.33762) (xy 194.9537 58.32942)
			(xy 194.98648 58.32942) (xy 194.98648 58.32123) (xy 195.01106 58.32123) (xy 195.01106 58.31304) (xy 195.03564 58.31304)
			(xy 195.03564 58.30484) (xy 195.06023 58.30484) (xy 195.06023 58.29665) (xy 195.08481 58.29665) (xy 195.08481 58.28845)
			(xy 195.10939 58.28845) (xy 195.10939 58.28026) (xy 195.13398 58.28026) (xy 195.13398 58.27207) (xy 195.15856 58.27207)
			(xy 195.15856 58.26387) (xy 195.18314 58.26387) (xy 195.18314 58.25568) (xy 195.20773 58.25568) (xy 195.20773 58.24748)
			(xy 195.22412 58.24748) (xy 195.22412 58.23929) (xy 195.2487 58.23929) (xy 195.2487 58.23109) (xy 195.26509 58.23109)
			(xy 195.26509 58.2229) (xy 195.28967 58.2229) (xy 195.28967 58.2147) (xy 195.30606 58.2147) (xy 195.30606 58.20651)
			(xy 195.33064 58.20651) (xy 195.33064 58.19831) (xy 195.34703 58.19831) (xy 195.34703 58.19012) (xy 195.36342 58.19012)
			(xy 195.36342 58.18193) (xy 195.388 58.18193) (xy 195.388 58.17373) (xy 195.4044 58.17373) (xy 195.4044 58.16554)
			(xy 195.42078 58.16554) (xy 195.42078 58.15734) (xy 195.43717 58.15734) (xy 195.43717 58.14915) (xy 195.45356 58.14915)
			(xy 195.45356 58.14095) (xy 195.46995 58.14095) (xy 195.46995 58.13276) (xy 195.48634 58.13276) (xy 195.48634 58.12456)
			(xy 195.50273 58.12456) (xy 195.50273 58.11637) (xy 195.51912 58.11637) (xy 195.51912 58.10817) (xy 195.53551 58.10817)
			(xy 195.53551 58.09998) (xy 195.5519 58.09998) (xy 195.5519 58.09178) (xy 195.56828 58.09178) (xy 195.56828 58.08359)
			(xy 195.58467 58.08359) (xy 195.58467 58.0754) (xy 195.60106 58.0754) (xy 195.60106 58.0672) (xy 195.61745 58.0672)
			(xy 195.61745 58.05901) (xy 195.62564 58.05901) (xy 195.62564 58.05081) (xy 195.64204 58.05081) (xy 195.64204 58.04262)
			(xy 195.65843 58.04262) (xy 195.65843 58.03442) (xy 195.67481 58.03442) (xy 195.67481 58.02623) (xy 195.68301 58.02623)
			(xy 195.68301 58.01804) (xy 195.6994 58.01804) (xy 195.6994 58.00984) (xy 195.71579 58.00984) (xy 195.71579 58.00165)
			(xy 195.72398 58.00165) (xy 195.72398 57.99345) (xy 195.74037 57.99345) (xy 195.74037 57.98526) (xy 195.75676 57.98526)
			(xy 195.75676 57.97706) (xy 195.76495 57.97706) (xy 195.76495 57.96887) (xy 195.78134 57.96887) (xy 195.78134 57.96067)
			(xy 195.78954 57.96067) (xy 195.78954 57.95248) (xy 195.80592 57.95248) (xy 195.80592 57.94429) (xy 195.82231 57.94429)
			(xy 195.82231 57.93609) (xy 195.83051 57.93609) (xy 195.83051 57.9279) (xy 195.8469 57.9279) (xy 195.8469 57.9197)
			(xy 195.85509 57.9197) (xy 195.85509 57.91151) (xy 195.87148 57.91151) (xy 195.87148 57.90331) (xy 195.87968 57.90331)
			(xy 195.87968 57.89512) (xy 195.88787 57.89512) (xy 195.88787 57.88692) (xy 195.90426 57.88692) (xy 195.90426 57.87873)
			(xy 195.91245 57.87873) (xy 195.91245 57.87053) (xy 195.92884 57.87053) (xy 195.92884 57.86234) (xy 195.93704 57.86234)
			(xy 195.93704 57.85415) (xy 195.95343 57.85415) (xy 195.95343 57.84595) (xy 195.96162 57.84595) (xy 195.96162 57.83776)
			(xy 195.96981 57.83776) (xy 195.96981 57.82956) (xy 195.98621 57.82956) (xy 195.98621 57.82137) (xy 195.9944 57.82137)
			(xy 195.9944 57.81317) (xy 196.00259 57.81317) (xy 196.00259 57.80498) (xy 196.01898 57.80498) (xy 196.01898 57.79678)
			(xy 196.02718 57.79678) (xy 196.02718 57.78859) (xy 196.03537 57.78859) (xy 196.03537 57.7804) (xy 196.04356 57.7804)
			(xy 196.04356 57.7722) (xy 196.05995 57.7722) (xy 196.05995 57.76401) (xy 196.06815 57.76401) (xy 196.06815 57.75581)
			(xy 196.07634 57.75581) (xy 196.07634 57.74762) (xy 196.08454 57.74762) (xy 196.08454 57.73942) (xy 196.10093 57.73942)
			(xy 196.10093 57.73123) (xy 196.10912 57.73123) (xy 196.10912 57.72303) (xy 196.11732 57.72303) (xy 196.11732 57.71484)
			(xy 196.12551 57.71484) (xy 196.12551 57.70664) (xy 196.13371 57.70664) (xy 196.13371 57.69845) (xy 196.15009 57.69845)
			(xy 196.15009 57.69026) (xy 196.15829 57.69026) (xy 196.15829 57.68206) (xy 196.16648 57.68206) (xy 196.16648 57.67387)
			(xy 196.17468 57.67387) (xy 196.17468 57.66567) (xy 196.18287 57.66567) (xy 196.18287 57.65748) (xy 196.19107 57.65748)
			(xy 196.19107 57.64928) (xy 196.19926 57.64928) (xy 196.19926 57.64109) (xy 196.21565 57.64109) (xy 196.21565 57.63289)
			(xy 196.22385 57.63289) (xy 196.22385 57.6247) (xy 196.23204 57.6247) (xy 196.23204 57.61651) (xy 196.24023 57.61651)
			(xy 196.24023 57.60831) (xy 196.24843 57.60831) (xy 196.24843 57.60011) (xy 196.25662 57.60011) (xy 196.25662 57.59192)
			(xy 196.26482 57.59192) (xy 196.26482 57.58373) (xy 196.27301 57.58373) (xy 196.27301 57.57553) (xy 196.28121 57.57553)
			(xy 196.28121 57.56734) (xy 196.2894 57.56734) (xy 196.2894 57.55914) (xy 196.29759 57.55914) (xy 196.29759 57.55095)
			(xy 196.30579 57.55095) (xy 196.30579 57.54276) (xy 196.31398 57.54276) (xy 196.31398 57.53456) (xy 196.32218 57.53456)
			(xy 196.32218 57.52637) (xy 196.33037 57.52637) (xy 196.33037 57.51817) (xy 196.33857 57.51817) (xy 196.33857 57.50998)
			(xy 196.34676 57.50998) (xy 196.34676 57.50178) (xy 196.35496 57.50178) (xy 196.35496 57.49359) (xy 196.36315 57.49359)
			(xy 196.36315 57.48539) (xy 196.37135 57.48539) (xy 196.37135 57.4772) (xy 196.37954 57.4772) (xy 196.37954 57.469)
			(xy 196.38773 57.469) (xy 196.38773 57.46081) (xy 196.39593 57.46081) (xy 196.39593 57.45262) (xy 196.40412 57.45262)
			(xy 196.40412 57.44442) (xy 196.41232 57.44442) (xy 196.41232 57.43623) (xy 196.42051 57.43623) (xy 196.42051 57.42803)
			(xy 196.42871 57.42803) (xy 196.42871 57.41984) (xy 196.4369 57.41984) (xy 196.4369 57.41164) (xy 196.4451 57.41164)
			(xy 196.4451 57.40345) (xy 196.4451 57.39526) (xy 196.45329 57.39526) (xy 196.45329 57.38706) (xy 196.46148 57.38706)
			(xy 196.46148 57.37886) (xy 196.46968 57.37886) (xy 196.46968 57.37067) (xy 196.47787 57.37067) (xy 196.47787 57.36248)
			(xy 196.48607 57.36248) (xy 196.48607 57.35428) (xy 196.49426 57.35428) (xy 196.49426 57.34609) (xy 196.50246 57.34609)
			(xy 196.50246 57.33789) (xy 196.50246 57.3297) (xy 196.51065 57.3297) (xy 196.51065 57.3215) (xy 196.37954 57.3215)
			(xy 196.37954 57.3297) (xy 196.37135 57.3297) (xy 196.37135 57.33789) (xy 196.36315 57.33789) (xy 196.36315 57.34609)
			(xy 196.36315 57.35428) (xy 196.35496 57.35428) (xy 196.35496 57.36248) (xy 196.34676 57.36248) (xy 196.34676 57.37067)
			(xy 196.33857 57.37067) (xy 196.33857 57.37886) (xy 196.33037 57.37886) (xy 196.33037 57.38706) (xy 196.32218 57.38706)
			(xy 196.32218 57.39526) (xy 196.31398 57.39526) (xy 196.31398 57.40345) (xy 196.30579 57.40345) (xy 196.30579 57.41164)
			(xy 196.29759 57.41164) (xy 196.29759 57.41984) (xy 196.2894 57.41984) (xy 196.2894 57.42803) (xy 196.28121 57.42803)
			(xy 196.28121 57.43623) (xy 196.27301 57.43623) (xy 196.27301 57.44442) (xy 196.26482 57.44442) (xy 196.26482 57.45262)
			(xy 196.25662 57.45262) (xy 196.25662 57.46081) (xy 196.24843 57.46081) (xy 196.24843 57.469) (xy 196.24023 57.469)
			(xy 196.24023 57.4772) (xy 196.23204 57.4772) (xy 196.23204 57.48539) (xy 196.22385 57.48539) (xy 196.22385 57.49359)
			(xy 196.21565 57.49359) (xy 196.21565 57.50178) (xy 196.20746 57.50178) (xy 196.20746 57.50998) (xy 196.19926 57.50998)
			(xy 196.19926 57.51817) (xy 196.19107 57.51817) (xy 196.19107 57.52637) (xy 196.18287 57.52637) (xy 196.18287 57.53456)
			(xy 196.17468 57.53456) (xy 196.17468 57.54276) (xy 196.16648 57.54276) (xy 196.16648 57.55095) (xy 196.15829 57.55095)
			(xy 196.15829 57.55914) (xy 196.1419 57.55914) (xy 196.1419 57.56734) (xy 196.13371 57.56734) (xy 196.13371 57.57553)
			(xy 196.12551 57.57553) (xy 196.12551 57.58373) (xy 196.11732 57.58373) (xy 196.11732 57.59192) (xy 196.10912 57.59192)
			(xy 196.10912 57.60011) (xy 196.10093 57.60011) (xy 196.10093 57.60831) (xy 196.09273 57.60831) (xy 196.09273 57.61651)
			(xy 196.07634 57.61651) (xy 196.07634 57.6247) (xy 196.06815 57.6247) (xy 196.06815 57.63289) (xy 196.05995 57.63289)
			(xy 196.05995 57.64109) (xy 196.05176 57.64109) (xy 196.05176 57.64928) (xy 196.04356 57.64928) (xy 196.04356 57.65748)
			(xy 196.02718 57.65748) (xy 196.02718 57.66567) (xy 196.01898 57.66567) (xy 196.01898 57.67387) (xy 196.01079 57.67387)
			(xy 196.01079 57.68206) (xy 196.00259 57.68206) (xy 196.00259 57.69026) (xy 195.98621 57.69026) (xy 195.98621 57.69845)
			(xy 195.97801 57.69845) (xy 195.97801 57.70664) (xy 195.96981 57.70664) (xy 195.96981 57.71484) (xy 195.96162 57.71484)
			(xy 195.96162 57.72303) (xy 195.94523 57.72303) (xy 195.94523 57.73123) (xy 195.93704 57.73123) (xy 195.93704 57.73942)
			(xy 195.92884 57.73942) (xy 195.92884 57.74762) (xy 195.91245 57.74762) (xy 195.91245 57.75581) (xy 195.90426 57.75581)
			(xy 195.90426 57.76401) (xy 195.89607 57.76401) (xy 195.89607 57.7722) (xy 195.87968 57.7722) (xy 195.87968 57.7804)
			(xy 195.87148 57.7804) (xy 195.87148 57.78859) (xy 195.85509 57.78859) (xy 195.85509 57.79678) (xy 195.8469 57.79678)
			(xy 195.8469 57.80498) (xy 195.8387 57.80498) (xy 195.8387 57.81317) (xy 195.82231 57.81317) (xy 195.82231 57.82137)
			(xy 195.81412 57.82137) (xy 195.81412 57.82956) (xy 195.79773 57.82956) (xy 195.79773 57.83776) (xy 195.78954 57.83776)
			(xy 195.78954 57.84595) (xy 195.77315 57.84595) (xy 195.77315 57.85415) (xy 195.76495 57.85415) (xy 195.76495 57.86234)
			(xy 195.74856 57.86234) (xy 195.74856 57.87053) (xy 195.74037 57.87053) (xy 195.74037 57.87873) (xy 195.72398 57.87873)
			(xy 195.72398 57.88692) (xy 195.70759 57.88692) (xy 195.70759 57.89512) (xy 195.6994 57.89512) (xy 195.6994 57.90331)
			(xy 195.68301 57.90331) (xy 195.68301 57.91151) (xy 195.66662 57.91151) (xy 195.66662 57.9197) (xy 195.65843 57.9197)
			(xy 195.65843 57.9279) (xy 195.64204 57.9279) (xy 195.64204 57.93609) (xy 195.62564 57.93609) (xy 195.62564 57.94429)
			(xy 195.61745 57.94429) (xy 195.61745 57.95248) (xy 195.60106 57.95248) (xy 195.60106 57.96067) (xy 195.58467 57.96067)
			(xy 195.58467 57.96887) (xy 195.56828 57.96887) (xy 195.56828 57.97706) (xy 195.56009 57.97706) (xy 195.56009 57.98526)
			(xy 195.5437 57.98526) (xy 195.5437 57.99345) (xy 195.52731 57.99345) (xy 195.52731 58.00165) (xy 195.51092 58.00165)
			(xy 195.51092 58.00984) (xy 195.49454 58.00984) (xy 195.49454 58.01804) (xy 195.47815 58.01804) (xy 195.47815 58.02623)
			(xy 195.46176 58.02623) (xy 195.46176 58.03442) (xy 195.44537 58.03442) (xy 195.44537 58.04262) (xy 195.42898 58.04262)
			(xy 195.42898 58.05081) (xy 195.41259 58.05081) (xy 195.41259 58.05901) (xy 195.3962 58.05901) (xy 195.3962 58.0672)
			(xy 195.37981 58.0672) (xy 195.37981 58.0754) (xy 195.36342 58.0754) (xy 195.36342 58.08359) (xy 195.34703 58.08359)
			(xy 195.34703 58.09178) (xy 195.32245 58.09178) (xy 195.32245 58.09998) (xy 195.30606 58.09998) (xy 195.30606 58.10817)
			(xy 195.28148 58.10817) (xy 195.28148 58.11637) (xy 195.26509 58.11637) (xy 195.26509 58.12456) (xy 195.2487 58.12456)
			(xy 195.2487 58.13276) (xy 195.22412 58.13276) (xy 195.22412 58.14095) (xy 195.20773 58.14095) (xy 195.20773 58.14915)
			(xy 195.18314 58.14915) (xy 195.18314 58.15734) (xy 195.15856 58.15734) (xy 195.15856 58.16554) (xy 195.14217 58.16554)
			(xy 195.14217 58.17373) (xy 195.11759 58.17373) (xy 195.11759 58.18193) (xy 195.093 58.18193) (xy 195.093 58.19012)
			(xy 195.06842 58.19012) (xy 195.06842 58.19831) (xy 195.04384 58.19831) (xy 195.04384 58.20651) (xy 195.01925 58.20651)
			(xy 195.01925 58.2147) (xy 194.99467 58.2147) (xy 194.99467 58.2229) (xy 194.97009 58.2229) (xy 194.97009 58.23109)
			(xy 194.93731 58.23109) (xy 194.93731 58.23929) (xy 194.91273 58.23929) (xy 194.91273 58.24748) (xy 194.87995 58.24748)
			(xy 194.87995 58.25568) (xy 194.84717 58.25568) (xy 194.84717 58.26387) (xy 194.81439 58.26387) (xy 194.81439 58.27207)
			(xy 194.78161 58.27207) (xy 194.78161 58.28026) (xy 194.74064 58.28026) (xy 194.74064 58.28845) (xy 194.70786 58.28845)
			(xy 194.70786 58.29665) (xy 194.66689 58.29665) (xy 194.66689 58.30484) (xy 194.61772 58.30484) (xy 194.61772 58.31304)
			(xy 194.56856 58.31304) (xy 194.56856 58.32123) (xy 194.51119 58.32123) (xy 194.51119 58.32942) (xy 194.46203 58.32942)
			(xy 194.46203 58.33762) (xy 194.36369 58.33762) (xy 194.36369 58.34582) (xy 194.27356 58.34582) (xy 194.27356 58.35401)
			(xy 194.26536 58.35401) (xy 194.26536 58.34582) (xy 194.24897 58.34582) (xy 194.24897 58.35401) (xy 193.92938 58.35401)
			(xy 193.92938 58.34582) (xy 193.80647 58.34582) (xy 193.80647 58.33762) (xy 193.73272 58.33762) (xy 193.73272 58.32942)
			(xy 193.66716 58.32942) (xy 193.66716 58.32123) (xy 193.6098 58.32123) (xy 193.6098 58.31304) (xy 193.56063 58.31304)
			(xy 193.56063 58.30484) (xy 193.51147 58.30484) (xy 193.51147 58.29665) (xy 193.4705 58.29665) (xy 193.4705 58.28845)
			(xy 193.42952 58.28845) (xy 193.42952 58.28026) (xy 193.39674 58.28026) (xy 193.39674 58.27207) (xy 193.36397 58.27207)
			(xy 193.36397 58.26387) (xy 193.33119 58.26387) (xy 193.33119 58.25568) (xy 193.29841 58.25568) (xy 193.29841 58.24748)
			(xy 193.26563 58.24748) (xy 193.26563 58.23929) (xy 193.24105 58.23929) (xy 193.24105 58.23109) (xy 193.20827 58.23109)
			(xy 193.20827 58.2229) (xy 193.18369 58.2229) (xy 193.18369 58.2147) (xy 193.1591 58.2147) (xy 193.1591 58.20651)
			(xy 193.13452 58.20651) (xy 193.13452 58.19831) (xy 193.10994 58.19831) (xy 193.10994 58.19012) (xy 193.08535 58.19012)
			(xy 193.08535 58.18193) (xy 193.06077 58.18193) (xy 193.06077 58.17373) (xy 193.03619 58.17373) (xy 193.03619 58.16554)
			(xy 193.0116 58.16554) (xy 193.0116 58.15734) (xy 192.99521 58.15734) (xy 192.99521 58.14915) (xy 192.97063 58.14915)
			(xy 192.97063 58.14095) (xy 192.95424 58.14095) (xy 192.95424 58.13276) (xy 192.92966 58.13276) (xy 192.92966 58.12456)
			(xy 192.91327 58.12456) (xy 192.91327 58.11637) (xy 192.88869 58.11637) (xy 192.88869 58.10817) (xy 192.8723 58.10817)
			(xy 192.8723 58.09998) (xy 192.85591 58.09998) (xy 192.85591 58.09178) (xy 192.83952 58.09178) (xy 192.83952 58.08359)
			(xy 192.81494 58.08359) (xy 192.81494 58.0754) (xy 192.79855 58.0754) (xy 192.79855 58.0672) (xy 192.78216 58.0672)
			(xy 192.78216 58.05901) (xy 192.76577 58.05901) (xy 192.76577 58.05081) (xy 192.74938 58.05081) (xy 192.74938 58.04262)
			(xy 192.73299 58.04262) (xy 192.73299 58.03442) (xy 192.7166 58.03442) (xy 192.7166 58.02623) (xy 192.70021 58.02623)
			(xy 192.70021 58.01804) (xy 192.68382 58.01804) (xy 192.68382 58.00984) (xy 192.66743 58.00984) (xy 192.66743 58.00165)
			(xy 192.65105 58.00165) (xy 192.65105 57.99345) (xy 192.63466 57.99345) (xy 192.63466 57.98526) (xy 192.61827 57.98526)
			(xy 192.61827 57.97706) (xy 192.61007 57.97706) (xy 192.61007 57.96887) (xy 192.59368 57.96887) (xy 192.59368 57.96067)
			(xy 192.5773 57.96067) (xy 192.5773 57.95248) (xy 192.56091 57.95248) (xy 192.56091 57.94429) (xy 192.54452 57.94429)
			(xy 192.54452 57.93609) (xy 192.53632 57.93609) (xy 192.53632 57.9279) (xy 192.51993 57.9279) (xy 192.51993 57.9197)
			(xy 192.50355 57.9197) (xy 192.50355 57.91151) (xy 192.49535 57.91151) (xy 192.49535 57.90331) (xy 192.47896 57.90331)
			(xy 192.47896 57.89512) (xy 192.47077 57.89512) (xy 192.47077 57.88692) (xy 192.45438 57.88692) (xy 192.45438 57.87873)
			(xy 192.43799 57.87873) (xy 192.43799 57.87053) (xy 192.42979 57.87053) (xy 192.42979 57.86234) (xy 192.4134 57.86234)
			(xy 192.4134 57.85415) (xy 192.40521 57.85415) (xy 192.40521 57.84595) (xy 192.38882 57.84595) (xy 192.38882 57.83776)
			(xy 192.38063 57.83776) (xy 192.38063 57.82956) (xy 192.36424 57.82956) (xy 192.36424 57.82137) (xy 192.35604 57.82137)
			(xy 192.35604 57.81317) (xy 192.33965 57.81317) (xy 192.33965 57.80498) (xy 192.33146 57.80498) (xy 192.33146 57.79678)
			(xy 192.31507 57.79678) (xy 192.31507 57.78859) (xy 192.30688 57.78859) (xy 192.30688 57.7804) (xy 192.29868 57.7804)
			(xy 192.29868 57.7722) (xy 192.28229 57.7722) (xy 192.28229 57.76401) (xy 192.2741 57.76401) (xy 192.2741 57.75581)
			(xy 192.2659 57.75581) (xy 192.2659 57.74762) (xy 192.24951 57.74762) (xy 192.24951 57.73942) (xy 192.24132 57.73942)
			(xy 192.24132 57.73123) (xy 192.23313 57.73123) (xy 192.23313 57.72303) (xy 192.21674 57.72303) (xy 192.21674 57.71484)
			(xy 192.20854 57.71484) (xy 192.20854 57.70664) (xy 192.20035 57.70664) (xy 192.20035 57.69845) (xy 192.18396 57.69845)
			(xy 192.18396 57.69026) (xy 192.17576 57.69026) (xy 192.17576 57.68206) (xy 192.16757 57.68206) (xy 192.16757 57.67387)
			(xy 192.15938 57.67387) (xy 192.15938 57.66567) (xy 192.14298 57.66567) (xy 192.14298 57.65748) (xy 192.13479 57.65748)
			(xy 192.13479 57.64928) (xy 192.1266 57.64928) (xy 192.1266 57.64109) (xy 192.1184 57.64109) (xy 192.1184 57.63289)
			(xy 192.11021 57.63289) (xy 192.11021 57.6247) (xy 192.09382 57.6247) (xy 192.09382 57.61651) (xy 192.08563 57.61651)
			(xy 192.08563 57.60831) (xy 192.07743 57.60831) (xy 192.07743 57.60011) (xy 192.06924 57.60011) (xy 192.06924 57.59192)
			(xy 192.06104 57.59192) (xy 192.06104 57.58373) (xy 192.05285 57.58373) (xy 192.05285 57.57553) (xy 192.04465 57.57553)
			(xy 192.04465 57.56734) (xy 192.02826 57.56734) (xy 192.02826 57.55914) (xy 192.02007 57.55914) (xy 192.02007 57.55095)
			(xy 192.01188 57.55095) (xy 192.01188 57.54276) (xy 192.00368 57.54276) (xy 192.00368 57.53456) (xy 191.99548 57.53456)
			(xy 191.99548 57.52637) (xy 191.98729 57.52637) (xy 191.98729 57.51817) (xy 191.9791 57.51817) (xy 191.9791 57.50998)
			(xy 191.9709 57.50998) (xy 191.9709 57.50178) (xy 191.96271 57.50178) (xy 191.96271 57.49359) (xy 191.95451 57.49359)
			(xy 191.95451 57.48539) (xy 191.94632 57.48539) (xy 191.94632 57.4772) (xy 191.93812 57.4772) (xy 191.93812 57.469)
			(xy 191.92993 57.469) (xy 191.92993 57.46081) (xy 191.92174 57.46081) (xy 191.92174 57.45262) (xy 191.91354 57.45262)
			(xy 191.91354 57.44442) (xy 191.90534 57.44442) (xy 191.90534 57.43623) (xy 191.89715 57.43623) (xy 191.89715 57.42803)
			(xy 191.88896 57.42803) (xy 191.88896 57.41984) (xy 191.88076 57.41984) (xy 191.88076 57.41164) (xy 191.87257 57.41164)
			(xy 191.87257 57.40345) (xy 191.86437 57.40345) (xy 191.86437 57.39526) (xy 191.85618 57.39526) (xy 191.85618 57.38706)
			(xy 191.84798 57.38706) (xy 191.84798 57.37886) (xy 191.83979 57.37886) (xy 191.83979 57.37067) (xy 191.8316 57.37067)
			(xy 191.8316 57.36248) (xy 191.8234 57.36248) (xy 191.8234 57.35428) (xy 191.81521 57.35428) (xy 191.81521 57.34609)
			(xy 191.80701 57.34609) (xy 191.80701 57.33789) (xy 191.80701 57.3297) (xy 191.79882 57.3297) (xy 191.79882 57.3215)
			(xy 191.79063 57.3215) (xy 191.79063 57.31331) (xy 191.78243 57.31331) (xy 191.78243 57.30511) (xy 191.77424 57.30511)
			(xy 191.77424 57.29692) (xy 191.76604 57.29692) (xy 191.76604 57.28872) (xy 191.75784 57.28872) (xy 191.75784 57.28053)
			(xy 191.74965 57.28053) (xy 191.74965 57.27234) (xy 191.74965 57.26414) (xy 191.74146 57.26414) (xy 191.74146 57.25595)
			(xy 191.73326 57.25595) (xy 191.73326 57.24775) (xy 191.72507 57.24775) (xy 191.72507 57.23956) (xy 191.71687 57.23956)
			(xy 191.71687 57.23136) (xy 191.70868 57.23136) (xy 191.70868 57.22317) (xy 191.70868 57.21498) (xy 191.70048 57.21498)
			(xy 191.70048 57.20678) (xy 191.69229 57.20678) (xy 191.69229 57.19859) (xy 191.6841 57.19859) (xy 191.6841 57.19039)
			(xy 191.6759 57.19039) (xy 191.6759 57.18219) (xy 191.6759 57.174) (xy 191.66771 57.174) (xy 191.66771 57.16581)
			(xy 191.65951 57.16581) (xy 191.65951 57.15761) (xy 191.65132 57.15761) (xy 191.65132 57.14942) (xy 191.65132 57.14122)
			(xy 191.64312 57.14122) (xy 191.64312 57.13303) (xy 191.63493 57.13303) (xy 191.63493 57.12484) (xy 191.62673 57.12484)
			(xy 191.62673 57.11664) (xy 191.62673 57.10845) (xy 191.61854 57.10845) (xy 191.61854 57.10025) (xy 191.61034 57.10025)
			(xy 191.61034 57.09206) (xy 191.60215 57.09206) (xy 191.60215 57.08386) (xy 191.60215 57.07567) (xy 191.59396 57.07567)
			(xy 191.59396 57.06747) (xy 191.58576 57.06747) (xy 191.58576 57.05928) (xy 191.57757 57.05928) (xy 191.57757 57.05109)
			(xy 191.57757 57.04289) (xy 191.56937 57.04289) (xy 191.56937 57.0347) (xy 191.56118 57.0347) (xy 191.56118 57.0265)
			(xy 191.56118 57.01831) (xy 191.55298 57.01831) (xy 191.55298 57.01011) (xy 191.54479 57.01011) (xy 191.54479 57.00192)
			(xy 191.54479 56.99372) (xy 191.53659 56.99372) (xy 191.53659 56.98553) (xy 191.5284 56.98553) (xy 191.5284 56.97734)
			(xy 191.5284 56.96914) (xy 191.5202 56.96914) (xy 191.5202 56.96095) (xy 191.51201 56.96095) (xy 191.51201 56.95275)
			(xy 191.51201 56.94455) (xy 191.50382 56.94455) (xy 191.50382 56.93636) (xy 191.49562 56.93636) (xy 191.49562 56.92817)
			(xy 191.49562 56.91997) (xy 191.48743 56.91997) (xy 191.48743 56.91178) (xy 191.48743 56.90358) (xy 191.47923 56.90358)
			(xy 191.47923 56.89539) (xy 191.47104 56.89539) (xy 191.47104 56.88719) (xy 191.47104 56.879) (xy 191.46284 56.879)
			(xy 191.46284 56.87081) (xy 191.45465 56.87081) (xy 191.45465 56.86261) (xy 191.45465 56.85442) (xy 191.44645 56.85442)
			(xy 191.44645 56.84622) (xy 191.44645 56.83803) (xy 191.43826 56.83803) (xy 191.43826 56.82983) (xy 191.43826 56.82164)
			(xy 191.43007 56.82164) (xy 191.43007 56.81345) (xy 191.42187 56.81345) (xy 191.42187 56.80525) (xy 191.42187 56.79706)
			(xy 191.41367 56.79706) (xy 191.41367 56.78886) (xy 191.41367 56.78067) (xy 191.40548 56.78067) (xy 191.40548 56.77247)
			(xy 191.40548 56.76428) (xy 191.39729 56.76428) (xy 191.39729 56.75608) (xy 191.38909 56.75608) (xy 191.38909 56.74789)
			(xy 191.38909 56.73969) (xy 191.3809 56.73969) (xy 191.3809 56.7315) (xy 191.3809 56.72331) (xy 191.3727 56.72331)
			(xy 191.3727 56.71511) (xy 191.3727 56.70692) (xy 191.36451 56.70692) (xy 191.36451 56.69872) (xy 191.36451 56.69053)
			(xy 191.35632 56.69053) (xy 191.35632 56.68233) (xy 191.35632 56.67414) (xy 191.34812 56.67414) (xy 191.34812 56.66594)
			(xy 191.34812 56.65775) (xy 191.33993 56.65775) (xy 191.33993 56.64955) (xy 191.33993 56.64136) (xy 191.33173 56.64136)
			(xy 191.33173 56.63317) (xy 191.33173 56.62497) (xy 191.32354 56.62497) (xy 191.32354 56.61678) (xy 191.32354 56.60858)
			(xy 191.31534 56.60858) (xy 191.31534 56.60039) (xy 191.31534 56.59219) (xy 191.30715 56.59219) (xy 191.30715 56.584)
			(xy 191.30715 56.5758) (xy 191.29896 56.5758) (xy 191.29896 56.56761) (xy 191.29896 56.55942) (xy 191.29076 56.55942)
			(xy 191.29076 56.55122) (xy 191.29076 56.54303) (xy 191.29076 56.53483) (xy 191.28256 56.53483) (xy 191.28256 56.52664)
			(xy 191.28256 56.51844) (xy 191.27437 56.51844) (xy 191.27437 56.51025) (xy 191.27437 56.50205) (xy 191.26618 56.50205)
			(xy 191.26618 56.49386) (xy 191.26618 56.48567) (xy 191.26618 56.47747) (xy 191.25798 56.47747) (xy 191.25798 56.46928)
			(xy 191.25798 56.46108) (xy 191.24979 56.46108) (xy 191.24979 56.45289) (xy 191.24979 56.44469) (xy 191.24159 56.44469)
			(xy 191.24159 56.4365) (xy 191.24159 56.42831) (xy 191.24159 56.42011) (xy 191.2334 56.42011) (xy 191.2334 56.41191)
			(xy 191.2334 56.40372) (xy 191.2252 56.40372) (xy 191.2252 56.39553) (xy 191.2252 56.38733) (xy 191.2252 56.37914)
			(xy 191.21701 56.37914) (xy 191.21701 56.37094) (xy 191.21701 56.36275) (xy 191.21701 56.35455) (xy 191.20881 56.35455)
			(xy 191.20881 56.34636) (xy 191.20881 56.33816) (xy 191.20062 56.33816) (xy 191.20062 56.32997) (xy 191.20062 56.32177)
			(xy 191.20062 56.31358) (xy 191.19243 56.31358) (xy 191.19243 56.30539) (xy 191.19243 56.29719) (xy 191.19243 56.289)
			(xy 191.18423 56.289) (xy 191.18423 56.2808) (xy 191.18423 56.27261) (xy 191.18423 56.26441) (xy 191.17604 56.26441)
			(xy 191.17604 56.25622) (xy 191.17604 56.24803) (xy 191.17604 56.23983) (xy 191.16784 56.23983) (xy 191.16784 56.23164)
			(xy 191.16784 56.22344) (xy 191.16784 56.21524) (xy 191.15965 56.21524) (xy 191.15965 56.20705) (xy 191.15965 56.19886)
			(xy 191.15965 56.19066) (xy 191.15145 56.19066) (xy 191.15145 56.18247) (xy 191.15145 56.17427) (xy 191.15145 56.16608)
			(xy 191.14326 56.16608) (xy 191.14326 56.15788) (xy 191.14326 56.14969) (xy 191.14326 56.1415) (xy 191.14326 56.1333)
			(xy 191.13506 56.1333) (xy 191.13506 56.12511) (xy 191.13506 56.11691) (xy 191.13506 56.10872) (xy 191.12687 56.10872)
			(xy 191.12687 56.10053) (xy 191.12687 56.09233) (xy 191.12687 56.08413) (xy 191.12687 56.07594) (xy 191.11867 56.07594)
			(xy 191.11867 56.06775) (xy 191.11867 56.05955) (xy 191.11867 56.05136) (xy 191.11867 56.04316) (xy 191.11048 56.04316)
			(xy 191.11048 56.03497) (xy 191.11048 56.02677) (xy 191.11048 56.01858) (xy 191.11048 56.01039) (xy 191.10229 56.01039)
			(xy 191.10229 56.00219) (xy 191.10229 55.994) (xy 191.10229 55.9858) (xy 191.10229 55.97761) (xy 191.09409 55.97761)
			(xy 191.09409 55.96941) (xy 191.09409 55.96122) (xy 191.09409 55.95302) (xy 191.09409 55.94483) (xy 191.09409 55.93663)
			(xy 191.0859 55.93663) (xy 191.0859 55.92844) (xy 191.0859 55.92024) (xy 191.0859 55.91205) (xy 191.0859 55.90386)
			(xy 191.0859 55.89566) (xy 191.0777 55.89566) (xy 191.0777 55.88747) (xy 191.0777 55.87927) (xy 191.0777 55.87108)
			(xy 191.0777 55.86288) (xy 191.0777 55.85469) (xy 191.06951 55.85469) (xy 191.06951 55.84649) (xy 191.06951 55.8383)
			(xy 191.06951 55.83011) (xy 191.06951 55.82191) (xy 191.06951 55.81372) (xy 191.06132 55.81372) (xy 191.06132 55.80552)
			(xy 191.06132 55.79733) (xy 191.06132 55.78913) (xy 191.06132 55.78094) (xy 191.06132 55.77274) (xy 191.06132 55.76455)
			(xy 191.05312 55.76455) (xy 191.05312 55.75636) (xy 191.05312 55.74816) (xy 191.05312 55.73997) (xy 191.05312 55.73177)
			(xy 191.05312 55.72358) (xy 191.05312 55.71538) (xy 191.05312 55.70719) (xy 191.04492 55.70719) (xy 191.04492 55.69899)
			(xy 191.04492 55.6908) (xy 191.04492 55.6826) (xy 191.04492 55.67441) (xy 191.77424 55.67441) (xy 191.77424 55.6826)
			(xy 191.77424 55.6908) (xy 191.77424 55.69899) (xy 191.77424 55.70719) (xy 191.77424 55.71538) (xy 191.77424 55.72358)
			(xy 191.77424 55.73177) (xy 191.77424 55.73997) (xy 191.77424 55.74816) (xy 191.77424 55.75636) (xy 191.77424 55.76455)
			(xy 191.77424 55.77274) (xy 191.77424 55.78094) (xy 191.77424 55.78913) (xy 191.77424 55.79733) (xy 191.77424 55.80552)
			(xy 191.77424 55.81372) (xy 191.77424 55.82191) (xy 191.77424 55.83011) (xy 191.77424 55.8383) (xy 191.77424 55.84649)
			(xy 191.77424 55.85469) (xy 191.77424 55.86288) (xy 191.77424 55.87108) (xy 191.77424 55.87927) (xy 191.77424 55.88747)
			(xy 191.77424 55.89566) (xy 191.77424 55.90386) (xy 191.77424 55.91205) (xy 191.77424 55.92024) (xy 191.77424 55.92844)
			(xy 191.77424 55.93663) (xy 191.77424 55.94483) (xy 191.77424 55.95302) (xy 191.77424 55.96122) (xy 191.77424 55.96941)
			(xy 191.77424 55.97761) (xy 191.77424 55.9858) (xy 191.77424 55.994) (xy 191.77424 56.00219) (xy 191.77424 56.01039)
			(xy 191.77424 56.01858) (xy 191.77424 56.02677) (xy 191.77424 56.03497) (xy 191.77424 56.04316) (xy 191.77424 56.05136)
			(xy 191.77424 56.05955) (xy 191.77424 56.06775) (xy 191.77424 56.07594) (xy 191.77424 56.08413) (xy 191.77424 56.09233)
			(xy 191.77424 56.10053) (xy 191.77424 56.10872) (xy 191.77424 56.11691) (xy 191.77424 56.12511) (xy 191.77424 56.1333)
			(xy 191.77424 56.1415) (xy 191.77424 56.14969) (xy 191.77424 56.15788) (xy 191.77424 56.16608) (xy 191.77424 56.17427)
			(xy 191.77424 56.18247) (xy 191.77424 56.19066) (xy 191.77424 56.19886) (xy 191.77424 56.20705) (xy 191.77424 56.21524)
			(xy 191.77424 56.22344) (xy 191.77424 56.23164) (xy 191.77424 56.23983) (xy 191.77424 56.24803) (xy 191.77424 56.25622)
			(xy 191.77424 56.26441) (xy 191.77424 56.27261) (xy 191.77424 56.2808) (xy 191.77424 56.289) (xy 191.77424 56.29719)
			(xy 191.77424 56.30539) (xy 191.77424 56.31358) (xy 191.77424 56.32177) (xy 191.77424 56.32997) (xy 191.77424 56.33816)
			(xy 191.77424 56.34636) (xy 191.77424 56.35455) (xy 191.77424 56.36275) (xy 191.77424 56.37094) (xy 191.77424 56.37914)
			(xy 191.77424 56.38733) (xy 191.77424 56.39553) (xy 191.77424 56.40372) (xy 191.77424 56.41191) (xy 191.77424 56.42011)
			(xy 191.77424 56.42831) (xy 191.77424 56.4365) (xy 191.77424 56.44469) (xy 191.77424 56.45289) (xy 191.77424 56.46108)
			(xy 191.77424 56.46928) (xy 191.77424 56.47747) (xy 191.77424 56.48567) (xy 191.77424 56.49386) (xy 191.77424 56.50205)
			(xy 191.77424 56.51025) (xy 191.77424 56.51844) (xy 191.77424 56.52664) (xy 191.77424 56.53483) (xy 191.77424 56.54303)
			(xy 191.77424 56.55122) (xy 191.77424 56.55942) (xy 191.77424 56.56761) (xy 191.77424 56.5758) (xy 191.77424 56.584)
			(xy 191.77424 56.59219) (xy 191.77424 56.60039) (xy 191.77424 56.60858) (xy 191.77424 56.61678) (xy 191.77424 56.62497)
			(xy 191.77424 56.63317) (xy 191.77424 56.64136) (xy 191.77424 56.64955) (xy 191.77424 56.65775) (xy 191.77424 56.66594)
			(xy 191.77424 56.67414) (xy 191.77424 56.68233) (xy 191.77424 56.69053) (xy 191.77424 56.69872) (xy 191.77424 56.70692)
			(xy 191.77424 56.71511) (xy 191.77424 56.72331) (xy 191.77424 56.7315) (xy 191.77424 56.73969) (xy 191.77424 56.74789)
			(xy 191.77424 56.75608) (xy 191.77424 56.76428) (xy 191.77424 56.77247) (xy 191.77424 56.78067) (xy 191.77424 56.78886)
			(xy 191.77424 56.79706) (xy 191.77424 56.80525) (xy 191.77424 56.81345) (xy 191.77424 56.82164) (xy 191.77424 56.82983)
			(xy 191.77424 56.83803) (xy 191.77424 56.84622) (xy 191.77424 56.85442) (xy 191.77424 56.86261) (xy 191.78243 56.86261)
			(xy 191.78243 56.87081) (xy 191.78243 56.879) (xy 191.78243 56.88719) (xy 191.79063 56.88719) (xy 191.79063 56.89539)
			(xy 191.79063 56.90358) (xy 191.79882 56.90358) (xy 191.79882 56.91178) (xy 191.80701 56.91178) (xy 191.80701 56.91997)
			(xy 191.81521 56.91997) (xy 191.81521 56.92817) (xy 191.8234 56.92817) (xy 191.8234 56.93636) (xy 191.8316 56.93636)
			(xy 191.8316 56.94455) (xy 191.83979 56.94455) (xy 191.83979 56.95275) (xy 191.84798 56.95275) (xy 191.84798 56.96095)
			(xy 191.85618 56.96095) (xy 191.85618 56.96914) (xy 191.86437 56.96914) (xy 191.86437 56.97734) (xy 191.87257 56.97734)
			(xy 191.87257 56.98553) (xy 191.88076 56.98553) (xy 191.88076 56.99372) (xy 191.88896 56.99372) (xy 191.88896 57.00192)
			(xy 191.89715 57.00192) (xy 191.89715 57.01011) (xy 191.90534 57.01011) (xy 191.90534 57.01831) (xy 191.91354 57.01831)
			(xy 191.91354 57.0265) (xy 191.92174 57.0265) (xy 191.92174 57.0347) (xy 191.92993 57.0347) (xy 191.92993 57.04289)
			(xy 191.93812 57.04289) (xy 191.93812 57.05109) (xy 191.94632 57.05109) (xy 191.94632 57.05928) (xy 191.95451 57.05928)
			(xy 191.95451 57.06747) (xy 191.96271 57.06747) (xy 191.96271 57.07567) (xy 191.9709 57.07567) (xy 191.9709 57.08386)
			(xy 191.9791 57.08386) (xy 191.9791 57.09206) (xy 191.98729 57.09206) (xy 191.98729 57.10025) (xy 191.99548 57.10025)
			(xy 191.99548 57.10845) (xy 192.00368 57.10845) (xy 192.00368 57.11664) (xy 192.01188 57.11664) (xy 192.01188 57.12484)
			(xy 192.02007 57.12484) (xy 192.02007 57.13303) (xy 192.02826 57.13303) (xy 192.02826 57.14122) (xy 192.04465 57.14122)
			(xy 192.04465 57.14942) (xy 192.06924 57.14942) (xy 192.06924 57.15761) (xy 193.10994 57.15761) (xy 193.10994 57.14942)
			(xy 193.11813 57.14942) (xy 193.11813 57.14122) (xy 193.12633 57.14122) (xy 193.12633 57.13303) (xy 193.13452 57.13303)
			(xy 193.13452 57.12484) (xy 193.13452 57.11664) (xy 193.13452 57.10845) (xy 193.13452 57.10025) (xy 193.13452 57.09206)
			(xy 193.13452 57.08386) (xy 193.13452 57.07567) (xy 193.13452 57.06747) (xy 193.13452 57.05928) (xy 193.13452 57.05109)
			(xy 193.13452 57.04289) (xy 193.13452 57.0347) (xy 193.13452 57.0265) (xy 193.13452 57.01831) (xy 193.13452 57.01011)
			(xy 193.13452 57.00192) (xy 193.13452 56.99372) (xy 193.13452 56.98553) (xy 193.13452 56.97734) (xy 193.13452 56.96914)
			(xy 193.13452 56.96095) (xy 193.13452 56.95275) (xy 193.13452 56.94455) (xy 193.13452 56.93636) (xy 193.13452 56.92817)
			(xy 193.13452 56.91997) (xy 193.13452 56.91178) (xy 193.13452 56.90358) (xy 193.13452 56.89539) (xy 193.13452 56.88719)
			(xy 193.13452 56.879) (xy 193.13452 56.87081) (xy 193.13452 56.86261) (xy 193.13452 56.85442) (xy 193.13452 56.84622)
			(xy 193.13452 56.83803) (xy 193.13452 56.82983) (xy 193.13452 56.82164) (xy 193.13452 56.81345) (xy 193.13452 56.80525)
			(xy 193.13452 56.79706) (xy 193.13452 56.78886) (xy 193.13452 56.78067) (xy 193.13452 56.77247) (xy 193.13452 56.76428)
			(xy 193.13452 56.75608) (xy 193.13452 56.74789) (xy 193.12633 56.74789) (xy 193.12633 56.73969) (xy 193.11813 56.73969)
			(xy 193.11813 56.7315) (xy 193.10174 56.7315) (xy 193.10174 56.72331) (xy 192.24951 56.72331) (xy 192.24951 56.71511)
			(xy 192.23313 56.71511) (xy 192.23313 56.70692) (xy 192.23313 56.69872) (xy 192.22493 56.69872) (xy 192.22493 56.69053)
			(xy 192.22493 56.68233) (xy 192.22493 56.67414) (xy 192.22493 56.66594) (xy 192.22493 56.65775) (xy 192.22493 56.64955)
			(xy 192.22493 56.64136) (xy 192.22493 56.63317) (xy 192.22493 56.62497) (xy 192.22493 56.61678) (xy 192.22493 56.60858)
			(xy 192.22493 56.60039) (xy 192.22493 56.59219) (xy 192.22493 56.584) (xy 192.22493 56.5758) (xy 192.22493 56.56761)
			(xy 192.22493 56.55942) (xy 192.22493 56.55122) (xy 192.22493 56.54303) (xy 192.22493 56.53483) (xy 192.22493 56.52664)
			(xy 192.22493 56.51844) (xy 192.22493 56.51025) (xy 192.22493 56.50205) (xy 192.22493 56.49386) (xy 192.22493 56.48567)
			(xy 192.22493 56.47747) (xy 192.22493 56.46928) (xy 192.22493 56.46108) (xy 192.22493 56.45289) (xy 192.22493 56.44469)
			(xy 192.22493 56.4365) (xy 192.22493 56.42831) (xy 192.22493 56.42011) (xy 192.22493 56.41191) (xy 192.22493 56.40372)
			(xy 192.22493 56.39553) (xy 192.22493 56.38733) (xy 192.22493 56.37914) (xy 192.22493 56.37094) (xy 192.22493 56.36275)
			(xy 192.22493 56.35455) (xy 192.22493 56.34636) (xy 192.22493 56.33816) (xy 192.22493 56.32997) (xy 192.22493 56.32177)
			(xy 192.22493 56.31358) (xy 192.22493 56.30539) (xy 192.22493 56.29719) (xy 192.22493 56.289) (xy 192.22493 56.2808)
			(xy 192.22493 56.27261) (xy 192.22493 56.26441) (xy 192.22493 56.25622) (xy 192.22493 56.24803) (xy 192.22493 56.23983)
			(xy 192.22493 56.23164) (xy 192.22493 56.22344) (xy 192.22493 56.21524) (xy 192.22493 56.20705) (xy 192.22493 56.19886)
			(xy 192.22493 56.19066) (xy 192.22493 56.18247) (xy 192.22493 56.17427) (xy 192.22493 56.16608) (xy 192.22493 56.15788)
			(xy 192.22493 56.14969) (xy 192.22493 56.1415) (xy 192.22493 56.1333) (xy 192.22493 56.12511) (xy 192.22493 56.11691)
			(xy 192.22493 56.10872) (xy 192.22493 56.10053) (xy 192.22493 56.09233) (xy 192.22493 56.08413) (xy 192.22493 56.07594)
			(xy 192.22493 56.06775) (xy 192.22493 56.05955) (xy 192.22493 56.05136) (xy 192.93785 56.05136) (xy 192.93785 56.05955)
			(xy 192.93785 56.06775) (xy 192.93785 56.07594) (xy 192.93785 56.08413) (xy 192.93785 56.09233) (xy 192.93785 56.10053)
			(xy 192.93785 56.10872) (xy 192.93785 56.11691) (xy 192.93785 56.12511) (xy 192.93785 56.1333) (xy 192.93785 56.1415)
			(xy 192.93785 56.14969) (xy 192.93785 56.15788) (xy 192.93785 56.16608) (xy 192.93785 56.17427) (xy 192.93785 56.18247)
			(xy 192.93785 56.19066) (xy 192.93785 56.19886) (xy 192.93785 56.20705) (xy 192.93785 56.21524) (xy 192.93785 56.22344)
			(xy 192.93785 56.23164) (xy 192.93785 56.23983) (xy 192.93785 56.24803) (xy 192.93785 56.25622) (xy 192.93785 56.26441)
			(xy 192.93785 56.27261) (xy 192.93785 56.2808) (xy 192.93785 56.289) (xy 192.93785 56.29719) (xy 192.93785 56.30539)
			(xy 192.93785 56.31358) (xy 192.93785 56.32177) (xy 192.93785 56.32997) (xy 192.93785 56.33816) (xy 192.93785 56.34636)
			(xy 192.93785 56.35455) (xy 192.93785 56.36275) (xy 192.93785 56.37094) (xy 192.93785 56.37914) (xy 192.93785 56.38733)
			(xy 192.93785 56.39553) (xy 192.93785 56.40372) (xy 192.93785 56.41191) (xy 192.93785 56.42011) (xy 192.94605 56.42011)
			(xy 192.94605 56.42831) (xy 192.95424 56.42831) (xy 192.95424 56.4365) (xy 192.95424 56.44469) (xy 192.96243 56.44469)
			(xy 192.96243 56.45289) (xy 192.97063 56.45289) (xy 192.97063 56.46108) (xy 192.97063 56.46928) (xy 192.97883 56.46928)
			(xy 192.97883 56.47747) (xy 192.98702 56.47747) (xy 192.98702 56.48567) (xy 192.99521 56.48567) (xy 192.99521 56.49386)
			(xy 193.00341 56.49386) (xy 193.00341 56.50205) (xy 193.0116 56.50205) (xy 193.0116 56.51025) (xy 193.0198 56.51025)
			(xy 193.0198 56.51844) (xy 193.02799 56.51844) (xy 193.02799 56.52664) (xy 193.03619 56.52664) (xy 193.03619 56.53483)
			(xy 193.04438 56.53483) (xy 193.04438 56.54303) (xy 193.06077 56.54303) (xy 193.06077 56.53483) (xy 193.06896 56.53483)
			(xy 193.06896 56.52664) (xy 193.07716 56.52664) (xy 193.07716 56.51844) (xy 193.08535 56.51844) (xy 193.08535 56.51025)
			(xy 193.09355 56.51025) (xy 193.09355 56.50205) (xy 193.10174 56.50205) (xy 193.10174 56.49386) (xy 193.10994 56.49386)
			(xy 193.10994 56.48567) (xy 193.11813 56.48567) (xy 193.11813 56.47747) (xy 193.12633 56.47747) (xy 193.33938 56.47747)
			(xy 193.33938 56.48567) (xy 193.33938 56.49386) (xy 193.33938 56.50205) (xy 193.33938 56.51025) (xy 193.33938 56.51844)
			(xy 193.33938 56.52664) (xy 193.33938 56.53483) (xy 193.33938 56.54303) (xy 193.33938 56.55122) (xy 193.33938 56.55942)
			(xy 193.33938 56.56761) (xy 193.33938 56.5758) (xy 193.33938 56.584) (xy 193.33938 56.59219) (xy 193.33938 56.60039)
			(xy 193.33938 56.60858) (xy 193.33938 56.61678) (xy 193.33938 56.62497) (xy 193.33938 56.63317) (xy 193.33938 56.64136)
			(xy 193.33938 56.64955) (xy 193.33938 56.65775) (xy 193.33938 56.66594) (xy 193.33938 56.67414) (xy 193.33938 56.68233)
			(xy 193.33938 56.69053) (xy 193.33938 56.69872) (xy 193.33938 56.70692) (xy 193.33938 56.71511) (xy 193.33938 56.72331)
			(xy 193.33938 56.7315) (xy 193.33938 56.73969) (xy 193.33938 56.74789) (xy 193.33938 56.75608) (xy 193.33938 56.76428)
			(xy 193.33938 56.77247) (xy 193.33938 56.78067) (xy 193.33938 56.78886) (xy 193.33938 56.79706) (xy 193.33938 56.80525)
			(xy 193.33938 56.81345) (xy 193.33938 56.82164) (xy 193.33938 56.82983) (xy 193.33938 56.83803) (xy 193.33938 56.84622)
			(xy 193.33938 56.85442) (xy 193.33938 56.86261) (xy 193.33938 56.87081) (xy 193.33938 56.879) (xy 193.33938 56.88719)
			(xy 193.33938 56.89539) (xy 193.33938 56.90358) (xy 193.33938 56.91178) (xy 193.33938 56.91997) (xy 193.33938 56.92817)
			(xy 193.33938 56.93636) (xy 193.33938 56.94455) (xy 193.33938 56.95275) (xy 193.33938 56.96095) (xy 193.33938 56.96914)
			(xy 193.33938 56.97734) (xy 193.33938 56.98553) (xy 193.33938 56.99372) (xy 193.33938 57.00192) (xy 193.33938 57.01011)
			(xy 193.33938 57.01831) (xy 193.33938 57.0265) (xy 193.33938 57.0347) (xy 193.33938 57.04289) (xy 193.33938 57.05109)
			(xy 193.33938 57.05928) (xy 193.33938 57.06747) (xy 193.33938 57.07567) (xy 193.33938 57.08386) (xy 193.33938 57.09206)
			(xy 193.33938 57.10025) (xy 193.33938 57.10845) (xy 193.33938 57.11664) (xy 193.33938 57.12484) (xy 193.33938 57.13303)
			(xy 193.34758 57.13303) (xy 193.34758 57.14122) (xy 193.35577 57.14122) (xy 193.35577 57.14942) (xy 193.37216 57.14942)
			(xy 193.37216 57.15761) (xy 193.7573 57.15761) (xy 193.7573 57.14942) (xy 193.77369 57.14942) (xy 193.77369 57.14122)
			(xy 193.78189 57.14122) (xy 193.78189 57.13303) (xy 193.78189 57.12484) (xy 193.79008 57.12484) (xy 193.79008 57.11664)
			(xy 193.79008 57.10845) (xy 193.79008 57.10025) (xy 193.79008 57.09206) (xy 193.79008 57.08386) (xy 193.79008 57.07567)
			(xy 193.79008 57.06747) (xy 193.79008 57.05928) (xy 193.79008 57.05109) (xy 193.79008 57.04289) (xy 193.79008 57.0347)
			(xy 193.79008 57.0265) (xy 193.79008 57.01831) (xy 193.79008 57.01011) (xy 193.79008 57.00192) (xy 193.79008 56.99372)
			(xy 193.79008 56.98553) (xy 193.79008 56.97734) (xy 193.79008 56.96914) (xy 193.79008 56.96095) (xy 193.79008 56.95275)
			(xy 193.79008 56.94455) (xy 193.79008 56.93636) (xy 193.79008 56.92817) (xy 193.79008 56.91997) (xy 193.79008 56.91178)
			(xy 193.79008 56.90358) (xy 193.79008 56.89539) (xy 193.79008 56.88719) (xy 193.79008 56.879) (xy 193.79008 56.87081)
			(xy 193.79008 56.86261) (xy 193.79008 56.85442) (xy 193.79008 56.84622) (xy 193.79008 56.83803) (xy 193.79008 56.82983)
			(xy 193.79008 56.82164) (xy 193.79008 56.81345) (xy 193.79008 56.80525) (xy 193.79008 56.79706) (xy 193.79008 56.78886)
			(xy 193.79008 56.78067) (xy 193.79008 56.77247) (xy 193.79008 56.76428) (xy 193.79008 56.75608) (xy 193.79008 56.74789)
			(xy 193.79008 56.73969) (xy 193.79008 56.7315) (xy 193.79008 56.72331) (xy 193.79008 56.71511) (xy 193.79008 56.70692)
			(xy 193.79008 56.69872) (xy 193.79008 56.69053) (xy 193.79008 56.68233) (xy 193.79008 56.67414) (xy 193.79008 56.66594)
			(xy 193.79008 56.65775) (xy 193.79008 56.64955) (xy 193.79008 56.64136) (xy 193.79008 56.63317) (xy 193.79827 56.63317)
			(xy 193.79827 56.62497) (xy 193.79827 56.61678) (xy 193.81466 56.61678) (xy 193.81466 56.60858) (xy 194.36369 56.60858)
			(xy 194.36369 56.61678) (xy 194.38008 56.61678) (xy 194.38008 56.62497) (xy 194.38008 56.63317) (xy 194.38828 56.63317)
			(xy 194.38828 56.64136) (xy 194.38828 56.64955) (xy 194.38828 56.65775) (xy 194.38828 56.66594) (xy 194.38828 56.67414)
			(xy 194.38828 56.68233) (xy 194.38828 56.69053) (xy 194.38828 56.69872) (xy 194.38828 56.70692) (xy 194.38828 56.71511)
			(xy 194.38828 56.72331) (xy 194.38828 56.7315) (xy 194.38828 56.73969) (xy 194.38828 56.74789) (xy 194.38828 56.75608)
			(xy 194.38828 56.76428) (xy 194.38828 56.77247) (xy 194.38828 56.78067) (xy 194.38828 56.78886) (xy 194.38828 56.79706)
			(xy 194.38828 56.80525) (xy 194.38828 56.81345) (xy 194.38828 56.82164) (xy 194.38828 56.82983) (xy 194.38828 56.83803)
			(xy 194.38828 56.84622) (xy 194.38828 56.85442) (xy 194.38828 56.86261) (xy 194.38828 56.87081) (xy 194.38828 56.879)
			(xy 194.38828 56.88719) (xy 194.38828 56.89539) (xy 194.38828 56.90358) (xy 194.38828 56.91178) (xy 194.38828 56.91997)
			(xy 194.38828 56.92817) (xy 194.38828 56.93636) (xy 194.38828 56.94455) (xy 194.38828 56.95275) (xy 194.38828 56.96095)
			(xy 194.38828 56.96914) (xy 194.38828 56.97734) (xy 194.38828 56.98553) (xy 194.38828 56.99372) (xy 194.38828 57.00192)
			(xy 194.38828 57.01011) (xy 194.38828 57.01831) (xy 194.38828 57.0265) (xy 194.38828 57.0347) (xy 194.38828 57.04289)
			(xy 194.38828 57.05109) (xy 194.38828 57.05928) (xy 194.38828 57.06747) (xy 194.38828 57.07567) (xy 194.38828 57.08386)
			(xy 194.38828 57.09206) (xy 194.38828 57.10025) (xy 194.38828 57.10845) (xy 194.38828 57.11664) (xy 194.38828 57.12484)
			(xy 194.38828 57.13303) (xy 194.39647 57.13303) (xy 194.39647 57.14122) (xy 194.40467 57.14122) (xy 194.40467 57.14942)
			(xy 194.42105 57.14942) (xy 194.42105 57.15761) (xy 194.8062 57.15761) (xy 194.8062 57.14942) (xy 194.82259 57.14942)
			(xy 194.82259 57.14122) (xy 194.83078 57.14122) (xy 194.83078 57.13303) (xy 194.83078 57.12484) (xy 194.83898 57.12484)
			(xy 194.83898 57.11664) (xy 194.83898 57.10845) (xy 194.83898 57.10025) (xy 194.83898 57.09206) (xy 194.83898 57.08386)
			(xy 194.83898 57.07567) (xy 194.83898 57.06747) (xy 194.83898 57.05928) (xy 194.83898 57.05109) (xy 194.83898 57.04289)
			(xy 194.83898 57.0347) (xy 194.83898 57.0265) (xy 194.83898 57.01831) (xy 194.83898 57.01011) (xy 194.83898 57.00192)
			(xy 194.83898 56.99372) (xy 194.83898 56.98553) (xy 194.83898 56.97734) (xy 194.83898 56.96914) (xy 194.83898 56.96095)
			(xy 194.83898 56.95275) (xy 194.83898 56.94455) (xy 194.83898 56.93636) (xy 194.83898 56.92817) (xy 194.83898 56.91997)
			(xy 194.83898 56.91178) (xy 194.83898 56.90358) (xy 194.83898 56.89539) (xy 194.83898 56.88719) (xy 194.83898 56.879)
			(xy 194.83898 56.87081) (xy 194.83898 56.86261) (xy 194.83898 56.85442) (xy 194.83898 56.84622) (xy 194.83898 56.83803)
			(xy 194.83898 56.82983) (xy 194.83898 56.82164) (xy 194.83898 56.81345) (xy 194.83898 56.80525) (xy 194.83898 56.79706)
			(xy 194.83898 56.78886) (xy 194.83898 56.78067) (xy 194.83898 56.77247) (xy 194.83898 56.76428) (xy 194.83898 56.75608)
			(xy 194.83898 56.74789) (xy 194.83898 56.73969) (xy 194.83898 56.7315) (xy 194.83898 56.72331) (xy 194.83898 56.71511)
			(xy 194.83898 56.70692) (xy 194.83898 56.69872) (xy 194.83898 56.69053) (xy 194.83898 56.68233) (xy 194.83898 56.67414)
			(xy 194.83898 56.66594) (xy 194.83898 56.65775) (xy 194.83898 56.64955) (xy 194.83898 56.64136) (xy 194.83898 56.63317)
			(xy 194.83898 56.62497) (xy 194.83898 56.61678) (xy 194.83898 56.60858) (xy 194.83898 56.60039) (xy 194.83898 56.59219)
			(xy 194.83898 56.584) (xy 194.83898 56.5758) (xy 194.83898 56.56761) (xy 194.83898 56.55942) (xy 194.83898 56.55122)
			(xy 194.83898 56.54303) (xy 194.83898 56.53483) (xy 194.83898 56.52664) (xy 194.83898 56.51844) (xy 194.83898 56.51025)
			(xy 194.83898 56.50205) (xy 194.83898 56.49386) (xy 194.83898 56.48567) (xy 194.83898 56.47747) (xy 194.83898 56.46928)
			(xy 194.83898 56.46108) (xy 194.83898 56.45289) (xy 194.83898 56.44469) (xy 194.83898 56.4365) (xy 194.83898 56.42831)
			(xy 194.83898 56.42011) (xy 194.83898 56.41191) (xy 194.83898 56.40372) (xy 194.83898 56.39553) (xy 194.83898 56.38733)
			(xy 194.83898 56.37914) (xy 194.83898 56.37094) (xy 194.83898 56.36275) (xy 194.83898 56.35455) (xy 194.83898 56.34636)
			(xy 194.83898 56.33816) (xy 194.83898 56.32997) (xy 194.83898 56.32177) (xy 194.83898 56.31358) (xy 194.83898 56.30539)
			(xy 194.83898 56.29719) (xy 194.83898 56.289) (xy 194.83898 56.2808) (xy 194.83898 56.27261) (xy 194.83898 56.26441)
			(xy 194.83898 56.25622) (xy 194.83898 56.24803) (xy 194.83898 56.23983) (xy 194.83898 56.23164) (xy 194.83898 56.22344)
			(xy 194.83898 56.21524) (xy 194.83898 56.20705) (xy 194.83898 56.19886) (xy 194.83898 56.19066) (xy 194.83898 56.18247)
			(xy 194.83898 56.17427) (xy 194.83898 56.16608) (xy 194.83898 56.15788) (xy 194.83898 56.14969) (xy 194.83898 56.1415)
			(xy 194.83898 56.1333) (xy 194.83898 56.12511) (xy 194.83898 56.11691) (xy 194.83898 56.10872) (xy 194.83898 56.10053)
			(xy 194.83898 56.09233) (xy 194.83898 56.08413) (xy 194.83898 56.07594) (xy 194.83898 56.06775) (xy 194.83898 56.05955)
			(xy 194.83898 56.05136) (xy 194.83898 56.04316) (xy 194.83898 56.03497) (xy 194.83898 56.02677) (xy 194.83898 56.01858)
			(xy 194.83898 56.01039) (xy 194.83898 56.00219) (xy 194.83898 55.994) (xy 194.83898 55.9858) (xy 194.83898 55.97761)
			(xy 194.83898 55.96941) (xy 194.83898 55.96122) (xy 194.83898 55.95302) (xy 194.83898 55.94483) (xy 194.83898 55.93663)
			(xy 194.83898 55.92844) (xy 194.83898 55.92024) (xy 194.83898 55.91205) (xy 194.83898 55.90386) (xy 194.83898 55.89566)
			(xy 194.83898 55.88747) (xy 194.83898 55.87927) (xy 194.83898 55.87108) (xy 194.83898 55.86288) (xy 194.83898 55.85469)
			(xy 194.83898 55.84649) (xy 194.83898 55.8383) (xy 194.83898 55.83011) (xy 194.83898 55.82191) (xy 194.83898 55.81372)
			(xy 194.83898 55.80552) (xy 194.83898 55.79733) (xy 194.83898 55.78913) (xy 194.83898 55.78094) (xy 194.83898 55.77274)
			(xy 194.83898 55.76455) (xy 194.83898 55.75636) (xy 194.83898 55.74816) (xy 194.83898 55.73997) (xy 194.83898 55.73177)
			(xy 194.83898 55.72358) (xy 194.83898 55.71538) (xy 194.83898 55.70719) (xy 194.83898 55.69899) (xy 194.83898 55.6908)
			(xy 194.83898 55.6826) (xy 194.83078 55.6826) (xy 194.83078 55.67441) (xy 194.83078 55.66622) (xy 194.83078 55.65802)
			(xy 194.83078 55.64983) (xy 194.82259 55.64983) (xy 194.82259 55.64163) (xy 194.82259 55.63344) (xy 194.82259 55.62524)
			(xy 194.81439 55.62524) (xy 194.81439 55.61705) (xy 194.8062 55.61705) (xy 194.8062 55.60885) (xy 194.798 55.60885)
			(xy 194.798 55.60066) (xy 194.78981 55.60066) (xy 194.78981 55.59247) (xy 194.78161 55.59247) (xy 194.78161 55.58427)
			(xy 194.77342 55.58427) (xy 194.77342 55.57608) (xy 194.76522 55.57608) (xy 194.76522 55.56788) (xy 194.75703 55.56788)
			(xy 194.75703 55.55969) (xy 194.74884 55.55969) (xy 194.74884 55.55149) (xy 194.74064 55.55149) (xy 194.74064 55.5433)
			(xy 194.73245 55.5433) (xy 194.73245 55.5351) (xy 194.72425 55.5351) (xy 194.72425 55.52691) (xy 194.71606 55.52691)
			(xy 194.71606 55.51872) (xy 194.70786 55.51872) (xy 194.70786 55.51052) (xy 194.69967 55.51052) (xy 194.69967 55.50233)
			(xy 194.69148 55.50233) (xy 194.69148 55.49413) (xy 194.68328 55.49413) (xy 194.68328 55.48594) (xy 194.67509 55.48594)
			(xy 194.67509 55.47774) (xy 194.66689 55.47774) (xy 194.66689 55.46955) (xy 194.65869 55.46955) (xy 194.65869 55.46136)
			(xy 194.6505 55.46136) (xy 194.6505 55.45316) (xy 194.64231 55.45316) (xy 194.64231 55.44496) (xy 194.63411 55.44496)
			(xy 194.63411 55.43677) (xy 194.62592 55.43677) (xy 194.62592 55.42857) (xy 194.61772 55.42857) (xy 194.61772 55.42038)
			(xy 195.01106 55.42038) (xy 195.01106 55.42857) (xy 195.01106 55.43677) (xy 195.01106 55.44496) (xy 195.01106 55.45316)
			(xy 195.01106 55.46136) (xy 195.01106 55.46955) (xy 195.01106 55.47774) (xy 195.01106 55.48594) (xy 195.01106 55.49413)
			(xy 195.01106 55.50233) (xy 195.01106 55.51052) (xy 195.01106 55.51872) (xy 195.01106 55.52691) (xy 195.01106 55.5351)
			(xy 195.01106 55.5433) (xy 195.01106 55.55149) (xy 195.01106 55.55969) (xy 195.01106 55.56788) (xy 195.01106 55.57608)
			(xy 195.01106 55.58427) (xy 195.01106 55.59247) (xy 195.01106 55.60066) (xy 195.01106 55.60885) (xy 195.01106 55.61705)
			(xy 195.01106 55.62524) (xy 195.01106 55.63344) (xy 195.01106 55.64163) (xy 195.01106 55.64983) (xy 195.01106 55.65802)
			(xy 195.01106 55.66622) (xy 195.01106 55.67441) (xy 195.01106 55.6826) (xy 195.01106 55.6908) (xy 195.01106 55.69899)
			(xy 195.01106 55.70719) (xy 195.01106 55.71538) (xy 195.01106 55.72358) (xy 195.01106 55.73177) (xy 195.01106 55.73997)
			(xy 195.01106 55.74816) (xy 195.01106 55.75636) (xy 195.01106 55.76455) (xy 195.01106 55.77274) (xy 195.01106 55.78094)
			(xy 195.01106 55.78913) (xy 195.01106 55.79733) (xy 195.01106 55.80552) (xy 195.01106 55.81372) (xy 195.01106 55.82191)
			(xy 195.01106 55.83011) (xy 195.01106 55.8383) (xy 195.01106 55.84649) (xy 195.01106 55.85469) (xy 195.01106 55.86288)
			(xy 195.01106 55.87108) (xy 195.01106 55.87927) (xy 195.01106 55.88747) (xy 195.01106 55.89566) (xy 195.01106 55.90386)
			(xy 195.01106 55.91205) (xy 195.01106 55.92024) (xy 195.01106 55.92844) (xy 195.01106 55.93663) (xy 195.01106 55.94483)
			(xy 195.01106 55.95302) (xy 195.01106 55.96122) (xy 195.01106 55.96941) (xy 195.01106 55.97761) (xy 195.01106 55.9858)
			(xy 195.01106 55.994) (xy 195.01106 56.00219) (xy 195.01106 56.01039) (xy 195.01106 56.01858) (xy 195.01106 56.02677)
			(xy 195.01106 56.03497) (xy 195.01106 56.04316) (xy 195.01106 56.05136) (xy 195.01106 56.05955) (xy 195.01106 56.06775)
			(xy 195.01106 56.07594) (xy 195.01106 56.08413) (xy 195.01106 56.09233) (xy 195.01106 56.10053) (xy 195.01106 56.10872)
			(xy 195.01106 56.11691) (xy 195.01106 56.12511) (xy 195.01106 56.1333) (xy 195.01106 56.1415) (xy 195.01106 56.14969)
			(xy 195.01106 56.15788) (xy 195.01106 56.16608) (xy 195.01106 56.17427) (xy 195.01106 56.18247) (xy 195.01106 56.19066)
			(xy 195.01106 56.19886) (xy 195.01106 56.20705) (xy 195.01106 56.21524) (xy 195.01106 56.22344) (xy 195.01106 56.23164)
			(xy 195.01106 56.23983) (xy 195.01106 56.24803) (xy 195.01106 56.25622) (xy 195.01106 56.26441) (xy 195.01106 56.27261)
			(xy 195.01106 56.2808) (xy 195.01106 56.289) (xy 195.01106 56.29719) (xy 195.01106 56.30539) (xy 195.01106 56.31358)
			(xy 195.01106 56.32177) (xy 195.01106 56.32997) (xy 195.01106 56.33816) (xy 195.01106 56.34636) (xy 195.01106 56.35455)
			(xy 195.01106 56.36275) (xy 195.01106 56.37094) (xy 195.01106 56.37914) (xy 195.01106 56.38733) (xy 195.01106 56.39553)
			(xy 195.01106 56.40372) (xy 195.01106 56.41191) (xy 195.01106 56.42011) (xy 195.01106 56.42831) (xy 195.01106 56.4365)
			(xy 195.01106 56.44469) (xy 195.01106 56.45289) (xy 195.01106 56.46108) (xy 195.01106 56.46928) (xy 195.01106 56.47747)
			(xy 195.01106 56.48567) (xy 195.01106 56.49386) (xy 195.01106 56.50205) (xy 195.01106 56.51025) (xy 195.01106 56.51844)
			(xy 195.01106 56.52664) (xy 195.01106 56.53483) (xy 195.01106 56.54303) (xy 195.01106 56.55122) (xy 195.01106 56.55942)
			(xy 195.01106 56.56761) (xy 195.01106 56.5758) (xy 195.01106 56.584) (xy 195.01106 56.59219) (xy 195.01106 56.60039)
			(xy 195.01106 56.60858) (xy 195.01106 56.61678) (xy 195.01106 56.62497) (xy 195.01106 56.63317) (xy 195.01106 56.64136)
			(xy 195.01106 56.64955) (xy 195.01106 56.65775) (xy 195.01106 56.66594) (xy 195.01106 56.67414) (xy 195.01106 56.68233)
			(xy 195.01106 56.69053) (xy 195.01106 56.69872) (xy 195.01106 56.70692) (xy 195.01106 56.71511) (xy 195.01106 56.72331)
			(xy 195.01106 56.7315) (xy 195.01106 56.73969) (xy 195.01106 56.74789) (xy 195.01106 56.75608) (xy 195.01106 56.76428)
			(xy 195.01106 56.77247) (xy 195.01106 56.78067) (xy 195.01106 56.78886) (xy 195.01106 56.79706) (xy 195.01106 56.80525)
			(xy 195.01106 56.81345) (xy 195.01106 56.82164) (xy 195.01106 56.82983) (xy 195.01106 56.83803) (xy 195.01106 56.84622)
			(xy 195.01106 56.85442) (xy 195.01106 56.86261) (xy 195.01106 56.87081) (xy 195.01106 56.879) (xy 195.01106 56.88719)
			(xy 195.01106 56.89539) (xy 195.01106 56.90358) (xy 195.01106 56.91178) (xy 195.01106 56.91997) (xy 195.01106 56.92817)
			(xy 195.01106 56.93636) (xy 195.01106 56.94455) (xy 195.01106 56.95275) (xy 195.01106 56.96095) (xy 195.01106 56.96914)
			(xy 195.01106 56.97734) (xy 195.01106 56.98553) (xy 195.01106 56.99372) (xy 195.01106 57.00192) (xy 195.01106 57.01011)
			(xy 195.01106 57.01831) (xy 195.01106 57.0265) (xy 195.01106 57.0347) (xy 195.01106 57.04289) (xy 195.01106 57.05109)
			(xy 195.01106 57.05928) (xy 195.01106 57.06747) (xy 195.01106 57.07567) (xy 195.01106 57.08386) (xy 195.01106 57.09206)
			(xy 195.01106 57.10025) (xy 195.01925 57.10025) (xy 195.01925 57.10845) (xy 195.01106 57.10845) (xy 195.01106 57.11664)
			(xy 195.01925 57.11664) (xy 195.01925 57.12484) (xy 195.01925 57.13303) (xy 195.01925 57.14122) (xy 195.02745 57.14122)
			(xy 195.02745 57.14942) (xy 195.04384 57.14942) (xy 195.04384 57.15761) (xy 195.44537 57.15761) (xy 195.44537 57.14942)
			(xy 195.45356 57.14942) (xy 195.45356 57.14122) (xy 195.46176 57.14122) (xy 195.46176 57.13303) (xy 195.46176 57.12484)
			(xy 195.46176 57.11664) (xy 195.46995 57.11664) (xy 195.46995 57.10845) (xy 195.46995 57.10025) (xy 195.46995 57.09206)
			(xy 195.46995 57.08386) (xy 195.46995 57.07567) (xy 195.46995 57.06747) (xy 195.46995 57.05928) (xy 195.46995 57.05109)
			(xy 195.46995 57.04289) (xy 195.46995 57.0347) (xy 195.46995 57.0265) (xy 195.46995 57.01831) (xy 195.46995 57.01011)
			(xy 195.46995 57.00192) (xy 195.46995 56.99372) (xy 195.46995 56.98553) (xy 195.46995 56.97734) (xy 195.46995 56.96914)
			(xy 195.46995 56.96095) (xy 195.46995 56.95275) (xy 195.46995 56.94455) (xy 195.46995 56.93636) (xy 195.46995 56.92817)
			(xy 195.46995 56.91997) (xy 195.46995 56.91178) (xy 195.46995 56.90358) (xy 195.46995 56.89539) (xy 195.46995 56.88719)
			(xy 195.46995 56.879) (xy 195.46995 56.87081) (xy 195.46995 56.86261) (xy 195.46995 56.85442) (xy 195.46995 56.84622)
			(xy 195.46995 56.83803) (xy 195.46995 56.82983) (xy 195.46995 56.82164) (xy 195.46995 56.81345) (xy 195.46995 56.80525)
			(xy 195.46995 56.79706) (xy 195.46995 56.78886) (xy 195.46995 56.78067) (xy 195.46995 56.77247) (xy 195.46995 56.76428)
			(xy 195.46995 56.75608) (xy 195.46995 56.74789) (xy 195.46995 56.73969) (xy 195.46995 56.7315) (xy 195.46995 56.72331)
			(xy 195.46995 56.71511) (xy 195.46995 56.70692) (xy 195.46995 56.69872) (xy 195.46995 56.69053) (xy 195.46995 56.68233)
			(xy 195.46995 56.67414) (xy 195.46176 56.67414) (xy 195.46176 56.66594) (xy 195.46995 56.66594) (xy 195.46995 56.65775)
			(xy 195.46995 56.64955) (xy 195.46995 56.64136) (xy 195.46995 56.63317) (xy 195.46995 56.62497) (xy 195.78134 56.62497)
			(xy 195.78134 56.63317) (xy 195.78134 56.64136) (xy 195.78954 56.64136) (xy 195.78954 56.64955) (xy 195.78954 56.65775)
			(xy 195.79773 56.65775) (xy 195.79773 56.66594) (xy 195.80592 56.66594) (xy 195.80592 56.67414) (xy 195.80592 56.68233)
			(xy 195.81412 56.68233) (xy 195.81412 56.69053) (xy 195.81412 56.69872) (xy 195.82231 56.69872) (xy 195.82231 56.70692)
			(xy 195.83051 56.70692) (xy 195.83051 56.71511) (xy 195.83051 56.72331) (xy 195.8387 56.72331) (xy 195.8387 56.7315)
			(xy 195.8387 56.73969) (xy 195.8469 56.73969) (xy 195.8469 56.74789) (xy 195.8469 56.75608) (xy 195.85509 56.75608)
			(xy 195.85509 56.76428) (xy 195.86329 56.76428) (xy 195.86329 56.77247) (xy 195.86329 56.78067) (xy 195.87148 56.78067)
			(xy 195.87148 56.78886) (xy 195.87148 56.79706) (xy 195.87968 56.79706) (xy 195.87968 56.80525) (xy 195.88787 56.80525)
			(xy 195.88787 56.81345) (xy 195.88787 56.82164) (xy 195.89607 56.82164) (xy 195.89607 56.82983) (xy 195.89607 56.83803)
			(xy 195.90426 56.83803) (xy 195.90426 56.84622) (xy 195.91245 56.84622) (xy 195.91245 56.85442) (xy 195.91245 56.86261)
			(xy 195.92065 56.86261) (xy 195.92065 56.87081) (xy 195.92065 56.879) (xy 195.92884 56.879) (xy 195.92884 56.88719)
			(xy 195.92884 56.89539) (xy 195.93704 56.89539) (xy 195.93704 56.90358) (xy 195.94523 56.90358) (xy 195.94523 56.91178)
			(xy 195.94523 56.91997) (xy 195.95343 56.91997) (xy 195.95343 56.92817) (xy 195.95343 56.93636) (xy 195.96162 56.93636)
			(xy 195.96162 56.94455) (xy 195.96981 56.94455) (xy 195.96981 56.95275) (xy 195.96981 56.96095) (xy 195.97801 56.96095)
			(xy 195.97801 56.96914) (xy 195.97801 56.97734) (xy 195.98621 56.97734) (xy 195.98621 56.98553) (xy 195.9944 56.98553)
			(xy 195.9944 56.99372) (xy 195.9944 57.00192) (xy 196.00259 57.00192) (xy 196.00259 57.01011) (xy 196.00259 57.01831)
			(xy 196.01079 57.01831) (xy 196.01079 57.0265) (xy 196.01898 57.0265) (xy 196.01898 57.0347) (xy 196.01898 57.04289)
			(xy 196.02718 57.04289) (xy 196.02718 57.05109) (xy 196.02718 57.05928) (xy 196.03537 57.05928) (xy 196.03537 57.06747)
			(xy 196.03537 57.07567) (xy 196.04356 57.07567) (xy 196.04356 57.08386) (xy 196.05176 57.08386) (xy 196.05176 57.09206)
			(xy 196.05176 57.10025) (xy 196.05995 57.10025) (xy 196.05995 57.10845) (xy 196.05995 57.11664) (xy 196.06815 57.11664)
			(xy 196.06815 57.12484) (xy 196.07634 57.12484) (xy 196.07634 57.13303) (xy 196.08454 57.13303) (xy 196.08454 57.14122)
			(xy 196.09273 57.14122) (xy 196.09273 57.14942) (xy 196.10912 57.14942) (xy 196.10912 57.15761) (xy 196.56801 57.15761)
			(xy 196.56801 57.14942) (xy 196.57621 57.14942) (xy 196.57621 57.14122) (xy 196.57621 57.13303) (xy 196.57621 57.12484)
			(xy 196.57621 57.11664) (xy 196.56801 57.11664) (xy 196.56801 57.10845) (xy 196.55982 57.10845) (xy 196.55982 57.10025)
			(xy 196.55982 57.09206) (xy 196.55162 57.09206) (xy 196.55162 57.08386) (xy 196.55162 57.07567) (xy 196.54343 57.07567)
			(xy 196.54343 57.06747) (xy 196.53523 57.06747) (xy 196.53523 57.05928) (xy 196.53523 57.05109) (xy 196.52704 57.05109)
			(xy 196.52704 57.04289) (xy 196.52704 57.0347) (xy 196.51885 57.0347) (xy 196.51885 57.0265) (xy 196.51065 57.0265)
			(xy 196.51065 57.01831) (xy 196.51065 57.01011) (xy 196.50246 57.01011) (xy 196.50246 57.00192) (xy 196.50246 56.99372)
			(xy 196.49426 56.99372) (xy 196.49426 56.98553) (xy 196.48607 56.98553) (xy 196.48607 56.97734) (xy 196.48607 56.96914)
			(xy 196.47787 56.96914) (xy 196.47787 56.96095) (xy 196.47787 56.95275) (xy 196.46968 56.95275) (xy 196.46968 56.94455)
			(xy 196.46148 56.94455) (xy 196.46148 56.93636) (xy 196.46148 56.92817) (xy 196.45329 56.92817) (xy 196.45329 56.91997)
			(xy 196.45329 56.91178) (xy 196.4451 56.91178) (xy 196.4451 56.90358) (xy 196.4369 56.90358) (xy 196.4369 56.89539)
			(xy 196.4369 56.88719) (xy 196.42871 56.88719) (xy 196.42871 56.879) (xy 196.42871 56.87081) (xy 196.42051 56.87081)
			(xy 196.42051 56.86261) (xy 196.41232 56.86261) (xy 196.41232 56.85442) (xy 196.41232 56.84622) (xy 196.40412 56.84622)
			(xy 196.40412 56.83803) (xy 196.40412 56.82983) (xy 196.39593 56.82983) (xy 196.39593 56.82164) (xy 196.38773 56.82164)
			(xy 196.38773 56.81345) (xy 196.38773 56.80525) (xy 196.37954 56.80525) (xy 196.37954 56.79706) (xy 196.37954 56.78886)
			(xy 196.37135 56.78886) (xy 196.37135 56.78067) (xy 196.36315 56.78067) (xy 196.36315 56.77247) (xy 196.36315 56.76428)
			(xy 196.35496 56.76428) (xy 196.35496 56.75608) (xy 196.35496 56.74789) (xy 196.34676 56.74789) (xy 196.34676 56.73969)
			(xy 196.33857 56.73969) (xy 196.33857 56.7315) (xy 196.33857 56.72331) (xy 196.33037 56.72331) (xy 196.33037 56.71511)
			(xy 196.33037 56.70692) (xy 196.32218 56.70692) (xy 196.32218 56.69872) (xy 196.31398 56.69872) (xy 196.31398 56.69053)
			(xy 196.31398 56.68233) (xy 196.30579 56.68233) (xy 196.30579 56.67414) (xy 196.30579 56.66594) (xy 196.29759 56.66594)
			(xy 196.29759 56.65775) (xy 196.29759 56.64955) (xy 196.2894 56.64955) (xy 196.2894 56.64136) (xy 196.28121 56.64136)
			(xy 196.28121 56.63317) (xy 196.28121 56.62497) (xy 196.27301 56.62497) (xy 196.27301 56.61678) (xy 196.27301 56.60858)
			(xy 196.26482 56.60858) (xy 196.26482 56.60039) (xy 196.25662 56.60039) (xy 196.25662 56.59219) (xy 196.25662 56.584)
			(xy 196.26482 56.584) (xy 196.26482 56.5758) (xy 196.27301 56.5758) (xy 196.27301 56.56761) (xy 196.28121 56.56761)
			(xy 196.28121 56.55942) (xy 196.2894 56.55942) (xy 196.2894 56.55122) (xy 196.29759 56.55122) (xy 196.29759 56.54303)
			(xy 196.30579 56.54303) (xy 196.30579 56.53483) (xy 196.31398 56.53483) (xy 196.31398 56.52664) (xy 196.32218 56.52664)
			(xy 196.32218 56.51844) (xy 196.33037 56.51844) (xy 196.33037 56.51025) (xy 196.33857 56.51025) (xy 196.33857 56.50205)
			(xy 196.34676 56.50205) (xy 196.34676 56.49386) (xy 196.35496 56.49386) (xy 196.35496 56.48567) (xy 196.36315 56.48567)
			(xy 196.36315 56.47747) (xy 196.37135 56.47747) (xy 196.37135 56.46928) (xy 196.37954 56.46928) (xy 196.37954 56.46108)
			(xy 196.38773 56.46108) (xy 196.38773 56.45289) (xy 196.39593 56.45289) (xy 196.39593 56.44469) (xy 196.40412 56.44469)
			(xy 196.40412 56.4365) (xy 196.41232 56.4365) (xy 196.41232 56.42831) (xy 196.42051 56.42831) (xy 196.42051 56.42011)
			(xy 196.42871 56.42011) (xy 196.42871 56.41191) (xy 196.4369 56.41191) (xy 196.4369 56.40372) (xy 196.4451 56.40372)
			(xy 196.4451 56.39553) (xy 196.4451 56.38733) (xy 196.45329 56.38733) (xy 196.45329 56.37914) (xy 196.46148 56.37914)
			(xy 196.46148 56.37094) (xy 196.46968 56.37094) (xy 196.46968 56.36275) (xy 196.47787 56.36275) (xy 196.47787 56.35455)
			(xy 196.48607 56.35455) (xy 196.48607 56.34636) (xy 196.49426 56.34636) (xy 196.49426 56.33816) (xy 196.49426 56.32997)
			(xy 196.50246 56.32997) (xy 196.50246 56.32177) (xy 196.50246 56.31358) (xy 196.51065 56.31358) (xy 196.51065 56.30539)
			(xy 196.51065 56.29719) (xy 196.51065 56.289) (xy 196.51065 56.2808) (xy 196.51065 56.27261) (xy 196.51065 56.26441)
			(xy 196.51065 56.25622) (xy 196.51065 56.24803) (xy 196.51065 56.23983) (xy 196.51065 56.23164) (xy 196.51065 56.22344)
			(xy 196.51065 56.21524) (xy 196.51065 56.20705) (xy 196.51065 56.19886) (xy 196.51065 56.19066) (xy 196.51065 56.18247)
			(xy 196.51065 56.17427) (xy 196.51065 56.16608) (xy 196.51065 56.15788) (xy 196.51065 56.14969) (xy 196.51065 56.1415)
			(xy 196.51065 56.1333) (xy 196.51065 56.12511) (xy 196.51065 56.11691) (xy 196.51065 56.10872) (xy 196.51065 56.10053)
			(xy 196.51065 56.09233) (xy 196.51065 56.08413) (xy 196.51065 56.07594) (xy 196.51065 56.06775) (xy 196.51065 56.05955)
			(xy 196.51065 56.05136) (xy 196.51065 56.04316) (xy 196.51065 56.03497) (xy 196.51065 56.02677) (xy 196.51065 56.01858)
			(xy 196.51065 56.01039) (xy 196.51065 56.00219) (xy 196.51065 55.994) (xy 196.51065 55.9858) (xy 196.51065 55.97761)
			(xy 196.51065 55.96941) (xy 196.51065 55.96122) (xy 196.51065 55.95302) (xy 196.51065 55.94483) (xy 196.51065 55.93663)
			(xy 196.51065 55.92844) (xy 196.51065 55.92024) (xy 196.51065 55.91205) (xy 196.51065 55.90386) (xy 196.51065 55.89566)
			(xy 196.51065 55.88747) (xy 196.51065 55.87927) (xy 196.51065 55.87108) (xy 196.51065 55.86288) (xy 196.51065 55.85469)
			(xy 196.51065 55.84649) (xy 196.51065 55.8383) (xy 196.51065 55.83011) (xy 196.51065 55.82191) (xy 196.51065 55.81372)
			(xy 196.51065 55.80552) (xy 196.51065 55.79733) (xy 196.51065 55.78913) (xy 196.51065 55.78094) (xy 196.51065 55.77274)
			(xy 196.51065 55.76455) (xy 196.51065 55.75636) (xy 196.51065 55.74816) (xy 196.51065 55.73997) (xy 196.51065 55.73177)
			(xy 196.51065 55.72358) (xy 196.51065 55.71538) (xy 196.51065 55.70719) (xy 196.51065 55.69899) (xy 196.51065 55.6908)
			(xy 196.51065 55.6826) (xy 196.51065 55.67441) (xy 196.51065 55.66622) (xy 196.50246 55.66622) (xy 196.50246 55.65802)
			(xy 196.50246 55.64983) (xy 196.50246 55.64163) (xy 196.49426 55.64163) (xy 196.49426 55.63344) (xy 196.49426 55.62524)
			(xy 196.48607 55.62524) (xy 196.48607 55.61705) (xy 196.47787 55.61705) (xy 196.47787 55.60885) (xy 196.46968 55.60885)
			(xy 196.46968 55.60066) (xy 196.46148 55.60066) (xy 196.46148 55.59247) (xy 196.45329 55.59247) (xy 196.45329 55.58427)
			(xy 196.4451 55.58427) (xy 196.4451 55.57608) (xy 196.4369 55.57608) (xy 196.4369 55.56788) (xy 196.42871 55.56788)
			(xy 196.42871 55.55969) (xy 196.42051 55.55969) (xy 196.42051 55.55149) (xy 196.41232 55.55149) (xy 196.41232 55.5433)
			(xy 196.40412 55.5433) (xy 196.40412 55.5351) (xy 196.39593 55.5351) (xy 196.39593 55.52691) (xy 196.38773 55.52691)
			(xy 196.38773 55.51872) (xy 196.37954 55.51872) (xy 196.37954 55.51052) (xy 196.37135 55.51052) (xy 196.37135 55.50233)
			(xy 196.36315 55.50233) (xy 196.36315 55.49413) (xy 196.35496 55.49413) (xy 196.35496 55.48594) (xy 196.34676 55.48594)
			(xy 196.34676 55.47774) (xy 196.33857 55.47774) (xy 196.33857 55.46955) (xy 196.33037 55.46955) (xy 196.33037 55.46136)
			(xy 196.32218 55.46136) (xy 196.32218 55.45316) (xy 196.31398 55.45316) (xy 196.31398 55.44496) (xy 196.30579 55.44496)
			(xy 196.30579 55.43677) (xy 196.29759 55.43677) (xy 196.29759 55.42857) (xy 196.2894 55.42857) (xy 196.2894 55.42038)
			(xy 196.28121 55.42038) (xy 196.28121 55.41219) (xy 196.27301 55.41219) (xy 196.27301 55.40399) (xy 196.75649 55.40399)
			(xy 196.75649 55.41219) (xy 196.75649 55.42038) (xy 196.75649 55.42857) (xy 196.75649 55.43677) (xy 196.75649 55.44496)
			(xy 196.75649 55.45316) (xy 196.75649 55.46136) (xy 196.75649 55.46955) (xy 196.75649 55.47774) (xy 196.75649 55.48594)
			(xy 196.75649 55.49413) (xy 196.75649 55.50233) (xy 196.75649 55.51052) (xy 196.75649 55.51872) (xy 196.75649 55.52691)
			(xy 196.75649 55.5351) (xy 196.75649 55.5433) (xy 196.75649 55.55149) (xy 196.75649 55.55969) (xy 196.75649 55.56788)
			(xy 196.75649 55.57608) (xy 196.75649 55.58427) (xy 196.75649 55.59247) (xy 196.75649 55.60066) (xy 196.75649 55.60885)
			(xy 196.75649 55.61705) (xy 196.75649 55.62524) (xy 196.75649 55.63344) (xy 196.75649 55.64163) (xy 196.75649 55.64983)
			(xy 196.75649 55.65802) (xy 196.75649 55.66622) (xy 196.75649 55.67441) (xy 196.75649 55.6826) (xy 196.75649 55.6908)
			(xy 196.75649 55.69899) (xy 196.75649 55.70719) (xy 196.75649 55.71538) (xy 196.75649 55.72358) (xy 196.75649 55.73177)
			(xy 196.75649 55.73997) (xy 196.75649 55.74816) (xy 196.75649 55.75636) (xy 196.75649 55.76455) (xy 196.75649 55.77274)
			(xy 196.75649 55.78094) (xy 196.75649 55.78913) (xy 196.75649 55.79733) (xy 196.75649 55.80552) (xy 196.75649 55.81372)
			(xy 196.75649 55.82191) (xy 196.75649 55.83011) (xy 196.75649 55.8383) (xy 196.75649 55.84649) (xy 196.75649 55.85469)
			(xy 196.75649 55.86288) (xy 196.75649 55.87108) (xy 196.75649 55.87927) (xy 196.75649 55.88747) (xy 196.75649 55.89566)
			(xy 196.75649 55.90386) (xy 196.75649 55.91205) (xy 196.75649 55.92024) (xy 196.75649 55.92844) (xy 196.75649 55.93663)
			(xy 196.75649 55.94483) (xy 196.75649 55.95302) (xy 196.75649 55.96122) (xy 196.75649 55.96941) (xy 196.75649 55.97761)
			(xy 196.75649 55.9858) (xy 196.75649 55.994) (xy 196.75649 56.00219) (xy 196.75649 56.01039) (xy 196.75649 56.01858)
			(xy 196.75649 56.02677) (xy 196.75649 56.03497) (xy 196.75649 56.04316) (xy 196.75649 56.05136) (xy 196.75649 56.05955)
			(xy 196.75649 56.06775) (xy 196.75649 56.07594) (xy 196.75649 56.08413) (xy 196.75649 56.09233) (xy 196.75649 56.10053)
			(xy 196.75649 56.10872) (xy 196.75649 56.11691) (xy 196.75649 56.12511) (xy 196.75649 56.1333) (xy 196.75649 56.1415)
			(xy 196.75649 56.14969) (xy 196.75649 56.15788) (xy 196.75649 56.16608) (xy 196.75649 56.17427) (xy 196.75649 56.18247)
			(xy 196.75649 56.19066) (xy 196.75649 56.19886) (xy 196.75649 56.20705) (xy 196.75649 56.21524) (xy 196.75649 56.22344)
			(xy 196.75649 56.23164) (xy 196.75649 56.23983) (xy 196.75649 56.24803) (xy 196.75649 56.25622) (xy 196.75649 56.26441)
			(xy 196.75649 56.27261) (xy 196.75649 56.2808) (xy 196.75649 56.289) (xy 196.75649 56.29719) (xy 196.75649 56.30539)
			(xy 196.75649 56.31358) (xy 196.75649 56.32177) (xy 196.75649 56.32997) (xy 196.75649 56.33816) (xy 196.75649 56.34636)
			(xy 196.75649 56.35455) (xy 196.75649 56.36275) (xy 196.75649 56.37094) (xy 196.75649 56.37914) (xy 196.75649 56.38733)
			(xy 196.75649 56.39553) (xy 196.75649 56.40372) (xy 196.75649 56.41191) (xy 196.75649 56.42011) (xy 196.75649 56.42831)
			(xy 196.75649 56.4365) (xy 196.75649 56.44469) (xy 196.75649 56.45289) (xy 196.75649 56.46108) (xy 196.75649 56.46928)
			(xy 196.75649 56.47747) (xy 196.75649 56.48567) (xy 196.75649 56.49386) (xy 196.75649 56.50205) (xy 196.75649 56.51025)
			(xy 196.75649 56.51844) (xy 196.75649 56.52664) (xy 196.75649 56.53483) (xy 196.75649 56.54303) (xy 196.75649 56.55122)
			(xy 196.75649 56.55942) (xy 196.75649 56.56761) (xy 196.75649 56.5758) (xy 196.75649 56.584) (xy 196.75649 56.59219)
			(xy 196.75649 56.60039) (xy 196.75649 56.60858) (xy 196.75649 56.61678) (xy 196.75649 56.62497) (xy 196.75649 56.63317)
			(xy 196.75649 56.64136) (xy 196.75649 56.64955) (xy 196.75649 56.65775) (xy 196.75649 56.66594) (xy 196.75649 56.67414)
			(xy 196.75649 56.68233) (xy 196.75649 56.69053) (xy 196.75649 56.69872) (xy 196.75649 56.70692) (xy 196.75649 56.71511)
			(xy 196.75649 56.72331) (xy 196.75649 56.7315) (xy 196.75649 56.73969) (xy 196.75649 56.74789) (xy 196.75649 56.75608)
			(xy 196.75649 56.76428) (xy 196.75649 56.77247) (xy 196.75649 56.78067) (xy 196.75649 56.78886) (xy 196.75649 56.79706)
			(xy 196.75649 56.80525) (xy 196.75649 56.81345) (xy 196.75649 56.82164) (xy 196.75649 56.82983) (xy 196.75649 56.83803)
			(xy 196.75649 56.84622) (xy 196.75649 56.85442) (xy 196.75649 56.86261) (xy 196.75649 56.87081) (xy 196.75649 56.879)
			(xy 196.75649 56.88719) (xy 196.75649 56.89539) (xy 196.75649 56.90358) (xy 196.75649 56.91178) (xy 196.75649 56.91997)
			(xy 196.75649 56.92817) (xy 196.75649 56.93636) (xy 196.75649 56.94455) (xy 196.75649 56.95275) (xy 196.75649 56.96095)
			(xy 196.75649 56.96914) (xy 196.75649 56.97734) (xy 196.75649 56.98553) (xy 196.75649 56.99372) (xy 196.75649 57.00192)
			(xy 196.75649 57.01011) (xy 196.75649 57.01831) (xy 196.75649 57.0265) (xy 196.75649 57.0347) (xy 196.75649 57.04289)
			(xy 196.75649 57.05109) (xy 196.75649 57.05928) (xy 196.75649 57.06747) (xy 196.75649 57.07567) (xy 196.75649 57.08386)
			(xy 196.75649 57.09206) (xy 196.75649 57.10025) (xy 196.75649 57.10845) (xy 196.75649 57.11664) (xy 196.75649 57.12484)
			(xy 196.75649 57.13303) (xy 196.76468 57.13303) (xy 196.76468 57.14122) (xy 196.77287 57.14122) (xy 196.77287 57.14942)
			(xy 196.78107 57.14942) (xy 196.78107 57.15761) (xy 197.95288 57.15761) (xy 197.95288 57.14942) (xy 197.98566 57.14942)
			(xy 197.98566 57.14122) (xy 198.00205 57.14122) (xy 198.00205 57.13303) (xy 198.01025 57.13303) (xy 198.01025 57.12484)
			(xy 198.01844 57.12484) (xy 198.01844 57.11664) (xy 198.02663 57.11664) (xy 198.02663 57.10845) (xy 198.03483 57.10845)
			(xy 198.03483 57.10025) (xy 198.04302 57.10025) (xy 198.04302 57.09206) (xy 198.05122 57.09206) (xy 198.05122 57.08386)
			(xy 198.05941 57.08386) (xy 198.05941 57.07567) (xy 198.06761 57.07567) (xy 198.06761 57.06747) (xy 198.0758 57.06747)
			(xy 198.0758 57.05928) (xy 198.08399 57.05928) (xy 198.08399 57.05109) (xy 198.09219 57.05109) (xy 198.09219 57.04289)
			(xy 198.10038 57.04289) (xy 198.10038 57.0347) (xy 198.10858 57.0347) (xy 198.10858 57.0265) (xy 198.11677 57.0265)
			(xy 198.11677 57.01831) (xy 198.12497 57.01831) (xy 198.12497 57.01011) (xy 198.13316 57.01011) (xy 198.13316 57.00192)
			(xy 198.14136 57.00192) (xy 198.14136 56.99372) (xy 198.14955 56.99372) (xy 198.14955 56.98553) (xy 198.15775 56.98553)
			(xy 198.15775 56.97734) (xy 198.16594 56.97734) (xy 198.16594 56.96914) (xy 198.17413 56.96914) (xy 198.17413 56.96095)
			(xy 198.18233 56.96095) (xy 198.18233 56.95275) (xy 198.19052 56.95275) (xy 198.19052 56.94455) (xy 198.19872 56.94455)
			(xy 198.19872 56.93636) (xy 198.20691 56.93636) (xy 198.20691 56.92817) (xy 198.2151 56.92817) (xy 198.2151 56.91997)
			(xy 198.2233 56.91997) (xy 198.2233 56.91178) (xy 198.2315 56.91178) (xy 198.2315 56.90358) (xy 198.23969 56.90358)
			(xy 198.23969 56.89539) (xy 198.23969 56.88719) (xy 198.23969 56.879) (xy 198.24788 56.879) (xy 198.24788 56.87081)
			(xy 198.24788 56.86261) (xy 198.24788 56.85442) (xy 198.24788 56.84622) (xy 198.25608 56.84622) (xy 198.25608 56.83803)
			(xy 198.25608 56.82983) (xy 198.25608 56.82164) (xy 198.25608 56.81345) (xy 198.25608 56.80525) (xy 198.25608 56.79706)
			(xy 198.25608 56.78886) (xy 198.25608 56.78067) (xy 198.25608 56.77247) (xy 198.25608 56.76428) (xy 198.25608 56.75608)
			(xy 198.25608 56.74789) (xy 198.25608 56.73969) (xy 198.25608 56.7315) (xy 198.25608 56.72331) (xy 198.25608 56.71511)
			(xy 198.25608 56.70692) (xy 198.25608 56.69872) (xy 198.25608 56.69053) (xy 198.25608 56.68233) (xy 198.25608 56.67414)
			(xy 198.25608 56.66594) (xy 198.25608 56.65775) (xy 198.25608 56.64955) (xy 198.25608 56.64136) (xy 198.25608 56.63317)
			(xy 198.25608 56.62497) (xy 198.25608 56.61678) (xy 198.25608 56.60858) (xy 198.25608 56.60039) (xy 198.25608 56.59219)
			(xy 198.25608 56.584) (xy 198.25608 56.5758) (xy 198.25608 56.56761) (xy 198.25608 56.55942) (xy 198.25608 56.55122)
			(xy 198.25608 56.54303) (xy 198.25608 56.53483) (xy 198.25608 56.52664) (xy 198.25608 56.51844) (xy 198.25608 56.51025)
			(xy 198.25608 56.50205) (xy 198.25608 56.49386) (xy 198.25608 56.48567) (xy 198.25608 56.47747) (xy 198.25608 56.46928)
			(xy 198.25608 56.46108) (xy 198.25608 56.45289) (xy 198.25608 56.44469) (xy 198.25608 56.4365) (xy 198.25608 56.42831)
			(xy 198.25608 56.42011) (xy 198.25608 56.41191) (xy 198.25608 56.40372) (xy 198.25608 56.39553) (xy 198.25608 56.38733)
			(xy 198.25608 56.37914) (xy 198.25608 56.37094) (xy 198.25608 56.36275) (xy 198.25608 56.35455) (xy 198.25608 56.34636)
			(xy 198.25608 56.33816) (xy 198.25608 56.32997) (xy 198.25608 56.32177) (xy 198.25608 56.31358) (xy 198.25608 56.30539)
			(xy 198.25608 56.29719) (xy 198.25608 56.289) (xy 198.25608 56.2808) (xy 198.25608 56.27261) (xy 198.25608 56.26441)
			(xy 198.25608 56.25622) (xy 198.25608 56.24803) (xy 198.25608 56.23983) (xy 198.25608 56.23164) (xy 198.25608 56.22344)
			(xy 198.25608 56.21524) (xy 198.25608 56.20705) (xy 198.25608 56.19886) (xy 198.25608 56.19066) (xy 198.25608 56.18247)
			(xy 198.25608 56.17427) (xy 198.25608 56.16608) (xy 198.25608 56.15788) (xy 198.25608 56.14969) (xy 198.25608 56.1415)
			(xy 198.25608 56.1333) (xy 198.25608 56.12511) (xy 198.25608 56.11691) (xy 198.25608 56.10872) (xy 198.25608 56.10053)
			(xy 198.25608 56.09233) (xy 198.25608 56.08413) (xy 198.25608 56.07594) (xy 198.25608 56.06775) (xy 198.25608 56.05955)
			(xy 198.25608 56.05136) (xy 198.25608 56.04316) (xy 198.25608 56.03497) (xy 198.25608 56.02677) (xy 198.25608 56.01858)
			(xy 198.25608 56.01039) (xy 198.25608 56.00219) (xy 198.25608 55.994) (xy 198.25608 55.9858) (xy 198.25608 55.97761)
			(xy 198.25608 55.96941) (xy 198.25608 55.96122) (xy 198.25608 55.95302) (xy 198.25608 55.94483) (xy 198.25608 55.93663)
			(xy 198.25608 55.92844) (xy 198.25608 55.92024) (xy 198.25608 55.91205) (xy 198.25608 55.90386) (xy 198.25608 55.89566)
			(xy 198.25608 55.88747) (xy 198.25608 55.87927) (xy 198.25608 55.87108) (xy 198.25608 55.86288) (xy 198.25608 55.85469)
			(xy 198.25608 55.84649) (xy 198.25608 55.8383) (xy 198.25608 55.83011) (xy 198.25608 55.82191) (xy 198.25608 55.81372)
			(xy 198.25608 55.80552) (xy 198.25608 55.79733) (xy 198.25608 55.78913) (xy 198.25608 55.78094) (xy 198.25608 55.77274)
			(xy 198.25608 55.76455) (xy 198.25608 55.75636) (xy 198.25608 55.74816) (xy 198.25608 55.73997) (xy 198.25608 55.73177)
			(xy 198.25608 55.72358) (xy 198.25608 55.71538) (xy 198.25608 55.70719) (xy 198.25608 55.69899) (xy 198.25608 55.6908)
			(xy 198.25608 55.6826) (xy 198.24788 55.6826) (xy 198.24788 55.67441) (xy 198.24788 55.66622) (xy 198.24788 55.65802)
			(xy 198.24788 55.64983) (xy 198.23969 55.64983) (xy 198.23969 55.64163) (xy 198.23969 55.63344) (xy 198.2315 55.63344)
			(xy 198.2315 55.62524) (xy 198.2233 55.62524) (xy 198.2233 55.61705) (xy 198.2151 55.61705) (xy 198.2151 55.60885)
			(xy 198.20691 55.60885) (xy 198.20691 55.60066) (xy 198.19872 55.60066) (xy 198.19872 55.59247) (xy 198.19052 55.59247)
			(xy 198.19052 55.58427) (xy 198.18233 55.58427) (xy 198.18233 55.57608) (xy 198.17413 55.57608) (xy 198.17413 55.56788)
			(xy 198.16594 55.56788) (xy 198.16594 55.55969) (xy 198.15775 55.55969) (xy 198.15775 55.55149) (xy 198.14955 55.55149)
			(xy 198.14955 55.5433) (xy 198.14136 55.5433) (xy 198.14136 55.5351) (xy 198.13316 55.5351) (xy 198.13316 55.52691)
			(xy 198.12497 55.52691) (xy 198.12497 55.51872) (xy 198.11677 55.51872) (xy 198.11677 55.51052) (xy 198.10858 55.51052)
			(xy 198.10858 55.50233) (xy 198.10038 55.50233) (xy 198.10038 55.49413) (xy 198.09219 55.49413) (xy 198.09219 55.48594)
			(xy 198.08399 55.48594) (xy 198.08399 55.47774) (xy 198.0758 55.47774) (xy 198.0758 55.46955) (xy 198.06761 55.46955)
			(xy 198.06761 55.46136) (xy 198.05941 55.46136) (xy 198.05941 55.45316) (xy 198.05122 55.45316) (xy 198.05122 55.44496)
			(xy 198.04302 55.44496) (xy 198.04302 55.43677) (xy 198.03483 55.43677) (xy 198.03483 55.42857) (xy 198.02663 55.42857)
			(xy 198.02663 55.42038) (xy 198.01844 55.42038) (xy 198.01844 55.41219) (xy 198.01025 55.41219) (xy 198.01025 55.40399)
			(xy 198.00205 55.40399) (xy 198.00205 55.3958) (xy 197.99385 55.3958) (xy 197.99385 55.3876) (xy 197.96927 55.3876)
			(xy 197.96927 55.37941) (xy 197.9283 55.37941) (xy 197.9283 55.37122) (xy 196.79746 55.37122) (xy 196.79746 55.37941)
			(xy 196.78107 55.37941) (xy 196.78107 55.3876) (xy 196.77287 55.3876) (xy 196.77287 55.3958) (xy 196.76468 55.3958)
			(xy 196.76468 55.40399) (xy 196.75649 55.40399) (xy 196.27301 55.40399) (xy 196.26482 55.40399) (xy 196.26482 55.3958)
			(xy 196.24843 55.3958) (xy 196.24843 55.3876) (xy 196.22385 55.3876) (xy 196.22385 55.37941) (xy 196.18287 55.37941)
			(xy 196.18287 55.37122) (xy 195.05203 55.37122) (xy 195.05203 55.37941) (xy 195.03564 55.37941) (xy 195.03564 55.3876)
			(xy 195.02745 55.3876) (xy 195.02745 55.3958) (xy 195.01925 55.3958) (xy 195.01925 55.40399) (xy 195.01925 55.41219)
			(xy 195.01925 55.42038) (xy 195.01106 55.42038) (xy 194.61772 55.42038) (xy 194.60953 55.42038) (xy 194.60953 55.41219)
			(xy 194.60133 55.41219) (xy 194.60133 55.40399) (xy 194.59314 55.40399) (xy 194.59314 55.3958) (xy 194.57675 55.3958)
			(xy 194.57675 55.3876) (xy 194.56036 55.3876) (xy 194.56036 55.37941) (xy 194.52759 55.37941) (xy 194.52759 55.37122)
			(xy 194.41286 55.37122) (xy 194.41286 55.37941) (xy 194.40467 55.37941) (xy 194.40467 55.3876) (xy 194.39647 55.3876)
			(xy 194.39647 55.3958) (xy 194.38828 55.3958) (xy 194.38828 55.40399) (xy 194.38008 55.40399) (xy 194.38008 55.41219)
			(xy 194.37189 55.41219) (xy 194.37189 55.42038) (xy 194.36369 55.42038) (xy 194.36369 55.42857) (xy 194.3555 55.42857)
			(xy 194.3555 55.43677) (xy 194.3473 55.43677) (xy 194.3473 55.44496) (xy 194.33911 55.44496) (xy 194.33911 55.45316)
			(xy 194.33092 55.45316) (xy 194.33092 55.46136) (xy 194.32272 55.46136) (xy 194.32272 55.46955) (xy 194.31453 55.46955)
			(xy 194.31453 55.47774) (xy 194.30633 55.47774) (xy 194.30633 55.48594) (xy 194.29814 55.48594) (xy 194.29814 55.49413)
			(xy 194.28994 55.49413) (xy 194.28994 55.50233) (xy 194.28175 55.50233) (xy 194.28175 55.51052) (xy 194.27356 55.51052)
			(xy 194.27356 55.51872) (xy 194.26536 55.51872) (xy 194.26536 55.52691) (xy 194.25717 55.52691) (xy 194.25717 55.5351)
			(xy 194.24897 55.5351) (xy 194.24897 55.5433) (xy 194.24078 55.5433) (xy 194.24078 55.55149) (xy 194.23258 55.55149)
			(xy 194.23258 55.55969) (xy 194.22439 55.55969) (xy 194.22439 55.56788) (xy 194.21619 55.56788) (xy 194.21619 55.57608)
			(xy 194.208 55.57608) (xy 194.208 55.58427) (xy 194.19981 55.58427) (xy 194.19981 55.59247) (xy 194.19161 55.59247)
			(xy 194.19161 55.60066) (xy 194.18342 55.60066) (xy 194.18342 55.60885) (xy 194.17522 55.60885) (xy 194.17522 55.61705)
			(xy 194.16703 55.61705) (xy 194.16703 55.62524) (xy 194.15883 55.62524) (xy 194.15883 55.63344) (xy 194.15064 55.63344)
			(xy 194.15064 55.64163) (xy 194.14244 55.64163) (xy 194.14244 55.64983) (xy 194.13425 55.64983) (xy 194.13425 55.65802)
			(xy 194.12605 55.65802) (xy 194.12605 55.66622) (xy 194.11786 55.66622) (xy 194.11786 55.67441) (xy 194.10967 55.67441)
			(xy 194.10967 55.6826) (xy 194.10147 55.6826) (xy 194.10147 55.6908) (xy 194.09328 55.6908) (xy 194.09328 55.69899)
			(xy 194.08508 55.69899) (xy 194.08508 55.70719) (xy 194.07689 55.70719) (xy 194.07689 55.71538) (xy 194.06869 55.71538)
			(xy 194.06869 55.72358) (xy 194.0605 55.72358) (xy 194.0605 55.73177) (xy 194.0523 55.73177) (xy 194.0523 55.73997)
			(xy 194.04411 55.73997) (xy 194.04411 55.74816) (xy 194.03591 55.74816) (xy 194.03591 55.75636) (xy 194.02772 55.75636)
			(xy 194.02772 55.76455) (xy 194.01953 55.76455) (xy 194.01953 55.77274) (xy 194.38828 55.77274) (xy 194.38828 55.78094)
			(xy 194.38828 55.78913) (xy 194.38828 55.79733) (xy 194.38828 55.80552) (xy 194.38828 55.81372) (xy 194.38828 55.82191)
			(xy 194.38828 55.83011) (xy 194.38828 55.8383) (xy 194.38828 55.84649) (xy 194.38828 55.85469) (xy 194.38828 55.86288)
			(xy 194.38828 55.87108) (xy 194.38828 55.87927) (xy 194.38828 55.88747) (xy 194.38828 55.89566) (xy 194.38828 55.90386)
			(xy 194.38828 55.91205) (xy 194.38828 55.92024) (xy 194.38828 55.92844) (xy 194.38828 55.93663) (xy 194.38828 55.94483)
			(xy 194.38828 55.95302) (xy 194.38828 55.96122) (xy 194.38828 55.96941) (xy 194.38828 55.97761) (xy 194.38828 55.9858)
			(xy 194.38828 55.994) (xy 194.38828 56.00219) (xy 194.38828 56.01039) (xy 194.38828 56.01858) (xy 194.38828 56.02677)
			(xy 194.38828 56.03497) (xy 194.38828 56.04316) (xy 194.38828 56.05136) (xy 194.38828 56.05955) (xy 194.38828 56.06775)
			(xy 194.38828 56.07594) (xy 194.38828 56.08413) (xy 194.38828 56.09233) (xy 194.38828 56.10053) (xy 194.38828 56.10872)
			(xy 194.38828 56.11691) (xy 194.38828 56.12511) (xy 194.38828 56.1333) (xy 194.38828 56.1415) (xy 194.38828 56.14969)
			(xy 194.38828 56.15788) (xy 194.38828 56.16608) (xy 194.38828 56.17427) (xy 194.38828 56.18247) (xy 194.38828 56.19066)
			(xy 194.38828 56.19886) (xy 194.38828 56.20705) (xy 194.38828 56.21524) (xy 194.38828 56.22344) (xy 193.79008 56.22344)
			(xy 193.79008 56.21524) (xy 193.79008 56.20705) (xy 193.79008 56.19886) (xy 193.79008 56.19066) (xy 193.79008 56.18247)
			(xy 193.79008 56.17427) (xy 193.79008 56.16608) (xy 193.79008 56.15788) (xy 193.79008 56.14969) (xy 193.79008 56.1415)
			(xy 193.79008 56.1333) (xy 193.79008 56.12511) (xy 193.79008 56.11691) (xy 193.79008 56.10872) (xy 193.79008 56.10053)
			(xy 193.79008 56.09233) (xy 193.79008 56.08413) (xy 193.79008 56.07594) (xy 193.79008 56.06775) (xy 193.79008 56.05955)
			(xy 193.79008 56.05136) (xy 193.79008 56.04316) (xy 193.78189 56.04316) (xy 193.78189 56.05136) (xy 193.77369 56.05136)
			(xy 193.77369 56.05955) (xy 193.7655 56.05955) (xy 193.7655 56.06775) (xy 193.7573 56.06775) (xy 193.7573 56.07594)
			(xy 193.74911 56.07594) (xy 193.74911 56.08413) (xy 193.74091 56.08413) (xy 193.74091 56.09233) (xy 193.73272 56.09233)
			(xy 193.73272 56.10053) (xy 193.72453 56.10053) (xy 193.72453 56.10872) (xy 193.71633 56.10872) (xy 193.71633 56.11691)
			(xy 193.70814 56.11691) (xy 193.70814 56.12511) (xy 193.69994 56.12511) (xy 193.69994 56.1333) (xy 193.69174 56.1333)
			(xy 193.69174 56.1415) (xy 193.68355 56.1415) (xy 193.68355 56.14969) (xy 193.67536 56.14969) (xy 193.67536 56.15788)
			(xy 193.66716 56.15788) (xy 193.66716 56.16608) (xy 193.65897 56.16608) (xy 193.65897 56.17427) (xy 193.65077 56.17427)
			(xy 193.65077 56.18247) (xy 193.64258 56.18247) (xy 193.64258 56.19066) (xy 193.63438 56.19066) (xy 193.63438 56.19886)
			(xy 193.62619 56.19886) (xy 193.62619 56.20705) (xy 193.618 56.20705) (xy 193.618 56.21524) (xy 193.6098 56.21524)
			(xy 193.6098 56.22344) (xy 193.60161 56.22344) (xy 193.60161 56.23164) (xy 193.59341 56.23164) (xy 193.59341 56.23983)
			(xy 193.58522 56.23983) (xy 193.58522 56.24803) (xy 193.57702 56.24803) (xy 193.57702 56.25622) (xy 193.56883 56.25622)
			(xy 193.56883 56.26441) (xy 193.56063 56.26441) (xy 193.56063 56.27261) (xy 193.55244 56.27261) (xy 193.55244 56.2808)
			(xy 193.54425 56.2808) (xy 193.54425 56.289) (xy 193.53605 56.289) (xy 193.53605 56.29719) (xy 193.52786 56.29719)
			(xy 193.52786 56.30539) (xy 193.51966 56.30539) (xy 193.51966 56.31358) (xy 193.51147 56.31358) (xy 193.51147 56.32177)
			(xy 193.50327 56.32177) (xy 193.50327 56.32997) (xy 193.49508 56.32997) (xy 193.49508 56.33816) (xy 193.48688 56.33816)
			(xy 193.48688 56.34636) (xy 193.47869 56.34636) (xy 193.47869 56.35455) (xy 193.4705 56.35455) (xy 193.4705 56.36275)
			(xy 193.4623 56.36275) (xy 193.4623 56.37094) (xy 193.4541 56.37094) (xy 193.4541 56.37914) (xy 193.44591 56.37914)
			(xy 193.44591 56.38733) (xy 193.43772 56.38733) (xy 193.43772 56.39553) (xy 193.42952 56.39553) (xy 193.42952 56.40372)
			(xy 193.42133 56.40372) (xy 193.42133 56.41191) (xy 193.41313 56.41191) (xy 193.41313 56.42011) (xy 193.40494 56.42011)
			(xy 193.40494 56.42831) (xy 193.38855 56.42831) (xy 193.38855 56.4365) (xy 193.38036 56.4365) (xy 193.38036 56.44469)
			(xy 193.37216 56.44469) (xy 193.37216 56.45289) (xy 193.36397 56.45289) (xy 193.36397 56.46108) (xy 193.35577 56.46108)
			(xy 193.35577 56.46928) (xy 193.34758 56.46928) (xy 193.34758 56.47747) (xy 193.33938 56.47747) (xy 193.12633 56.47747)
			(xy 193.12633 56.46928) (xy 193.13452 56.46928) (xy 193.13452 56.46108) (xy 193.14271 56.46108) (xy 193.14271 56.45289)
			(xy 193.15091 56.45289) (xy 193.15091 56.44469) (xy 193.1591 56.44469) (xy 193.1591 56.4365) (xy 193.1673 56.4365)
			(xy 193.1673 56.42831) (xy 193.17549 56.42831) (xy 193.17549 56.42011) (xy 193.18369 56.42011) (xy 193.18369 56.41191)
			(xy 193.19188 56.41191) (xy 193.19188 56.40372) (xy 193.20008 56.40372) (xy 193.20008 56.39553) (xy 193.20827 56.39553)
			(xy 193.20827 56.38733) (xy 193.21646 56.38733) (xy 193.21646 56.37914) (xy 193.22466 56.37914) (xy 193.22466 56.37094)
			(xy 193.23286 56.37094) (xy 193.23286 56.36275) (xy 193.24105 56.36275) (xy 193.24105 56.35455) (xy 193.24924 56.35455)
			(xy 193.24924 56.34636) (xy 193.26563 56.34636) (xy 193.26563 56.33816) (xy 193.27383 56.33816) (xy 193.27383 56.32997)
			(xy 193.28202 56.32997) (xy 193.28202 56.32177) (xy 193.29021 56.32177) (xy 193.29021 56.31358) (xy 193.29841 56.31358)
			(xy 193.29841 56.30539) (xy 193.30661 56.30539) (xy 193.30661 56.29719) (xy 193.3148 56.29719) (xy 193.3148 56.289)
			(xy 193.32299 56.289) (xy 193.32299 56.2808) (xy 193.33119 56.2808) (xy 193.33119 56.27261) (xy 193.33938 56.27261)
			(xy 193.33938 56.26441) (xy 193.34758 56.26441) (xy 193.34758 56.25622) (xy 193.35577 56.25622) (xy 193.35577 56.24803)
			(xy 193.36397 56.24803) (xy 193.36397 56.23983) (xy 193.37216 56.23983) (xy 193.37216 56.23164) (xy 193.38036 56.23164)
			(xy 193.38036 56.22344) (xy 193.38855 56.22344) (xy 193.38855 56.21524) (xy 193.39674 56.21524) (xy 193.39674 56.20705)
			(xy 193.40494 56.20705) (xy 193.40494 56.19886) (xy 193.41313 56.19886) (xy 193.41313 56.19066) (xy 193.42133 56.19066)
			(xy 193.42133 56.18247) (xy 193.42952 56.18247) (xy 193.42952 56.17427) (xy 193.43772 56.17427) (xy 193.43772 56.16608)
			(xy 193.44591 56.16608) (xy 193.44591 56.15788) (xy 193.4541 56.15788) (xy 193.4541 56.14969) (xy 193.4623 56.14969)
			(xy 193.4623 56.1415) (xy 193.4705 56.1415) (xy 193.4705 56.1333) (xy 193.47869 56.1333) (xy 193.47869 56.12511)
			(xy 193.48688 56.12511) (xy 193.48688 56.11691) (xy 193.49508 56.11691) (xy 193.49508 56.10872) (xy 193.50327 56.10872)
			(xy 193.50327 56.10053) (xy 193.51147 56.10053) (xy 193.51147 56.09233) (xy 193.51966 56.09233) (xy 193.51966 56.08413)
			(xy 193.52786 56.08413) (xy 193.52786 56.07594) (xy 193.53605 56.07594) (xy 193.53605 56.06775) (xy 193.54425 56.06775)
			(xy 193.54425 56.05955) (xy 193.55244 56.05955) (xy 193.55244 56.05136) (xy 193.56063 56.05136) (xy 193.56063 56.04316)
			(xy 193.56883 56.04316) (xy 193.56883 56.03497) (xy 193.57702 56.03497) (xy 193.57702 56.02677) (xy 193.58522 56.02677)
			(xy 193.58522 56.01858) (xy 193.59341 56.01858) (xy 193.59341 56.01039) (xy 193.60161 56.01039) (xy 193.60161 56.00219)
			(xy 193.6098 56.00219) (xy 193.6098 55.994) (xy 193.618 55.994) (xy 193.618 55.9858) (xy 193.62619 55.9858)
			(xy 193.62619 55.97761) (xy 193.63438 55.97761) (xy 193.63438 55.96941) (xy 193.64258 55.96941) (xy 193.64258 55.96122)
			(xy 193.65077 55.96122) (xy 193.65077 55.95302) (xy 193.65897 55.95302) (xy 193.65897 55.94483) (xy 193.66716 55.94483)
			(xy 193.66716 55.93663) (xy 193.67536 55.93663) (xy 193.67536 55.92844) (xy 193.68355 55.92844) (xy 193.68355 55.92024)
			(xy 193.69174 55.92024) (xy 193.69174 55.91205) (xy 193.69994 55.91205) (xy 193.69994 55.90386) (xy 193.70814 55.90386)
			(xy 193.70814 55.89566) (xy 193.71633 55.89566) (xy 193.71633 55.88747) (xy 193.72453 55.88747) (xy 193.72453 55.87927)
			(xy 193.73272 55.87927) (xy 193.73272 55.87108) (xy 193.74091 55.87108) (xy 193.74091 55.86288) (xy 193.74911 55.86288)
			(xy 193.74911 55.85469) (xy 193.7573 55.85469) (xy 193.7573 55.84649) (xy 193.7655 55.84649) (xy 193.7655 55.8383)
			(xy 193.77369 55.8383) (xy 193.77369 55.83011) (xy 193.78189 55.83011) (xy 193.78189 55.82191) (xy 193.79008 55.82191)
			(xy 193.79008 55.81372) (xy 193.79827 55.81372) (xy 193.79827 55.80552) (xy 193.80647 55.80552) (xy 193.80647 55.79733)
			(xy 193.81466 55.79733) (xy 193.81466 55.78913) (xy 193.82286 55.78913) (xy 193.82286 55.78094) (xy 193.83105 55.78094)
			(xy 193.83105 55.77274) (xy 193.83925 55.77274) (xy 193.83925 55.76455) (xy 193.84744 55.76455) (xy 193.84744 55.75636)
			(xy 193.85564 55.75636) (xy 193.85564 55.74816) (xy 193.86383 55.74816) (xy 193.86383 55.73997) (xy 193.87202 55.73997)
			(xy 193.87202 55.73177) (xy 193.88022 55.73177) (xy 193.88022 55.72358) (xy 193.88841 55.72358) (xy 193.88841 55.71538)
			(xy 193.89661 55.71538) (xy 193.89661 55.70719) (xy 193.9048 55.70719) (xy 193.9048 55.69899) (xy 193.913 55.69899)
			(xy 193.913 55.6908) (xy 193.92119 55.6908) (xy 193.92119 55.6826) (xy 193.92938 55.6826) (xy 193.92938 55.67441)
			(xy 193.93758 55.67441) (xy 193.93758 55.66622) (xy 193.94578 55.66622) (xy 193.94578 55.65802) (xy 193.96217 55.65802)
			(xy 193.96217 55.64983) (xy 193.97036 55.64983) (xy 193.97036 55.64163) (xy 193.97855 55.64163) (xy 193.97855 55.63344)
			(xy 193.98675 55.63344) (xy 193.98675 55.62524) (xy 193.99494 55.62524) (xy 193.99494 55.61705) (xy 194.00314 55.61705)
			(xy 194.00314 55.60885) (xy 194.01133 55.60885) (xy 194.01133 55.60066) (xy 194.01953 55.60066) (xy 194.01953 55.59247)
			(xy 194.02772 55.59247) (xy 194.02772 55.58427) (xy 194.03591 55.58427) (xy 194.03591 55.57608) (xy 194.04411 55.57608)
			(xy 194.04411 55.56788) (xy 194.0523 55.56788) (xy 194.0523 55.55969) (xy 194.0605 55.55969) (xy 194.0605 55.55149)
			(xy 194.06869 55.55149) (xy 194.06869 55.5433) (xy 194.07689 55.5433) (xy 194.07689 55.5351) (xy 194.08508 55.5351)
			(xy 194.08508 55.52691) (xy 194.09328 55.52691) (xy 194.09328 55.51872) (xy 194.10147 55.51872) (xy 194.10147 55.51052)
			(xy 194.10967 55.51052) (xy 194.10967 55.50233) (xy 194.11786 55.50233) (xy 194.11786 55.49413) (xy 194.12605 55.49413)
			(xy 194.12605 55.48594) (xy 194.13425 55.48594) (xy 194.13425 55.47774) (xy 194.14244 55.47774) (xy 194.14244 55.46955)
			(xy 194.15064 55.46955) (xy 194.15064 55.46136) (xy 194.15883 55.46136) (xy 194.15883 55.45316) (xy 194.16703 55.45316)
			(xy 194.16703 55.44496) (xy 194.17522 55.44496) (xy 194.17522 55.43677) (xy 194.18342 55.43677) (xy 194.18342 55.42857)
			(xy 194.19161 55.42857) (xy 194.19161 55.42038) (xy 194.19981 55.42038) (xy 194.19981 55.41219) (xy 194.208 55.41219)
			(xy 194.208 55.40399) (xy 194.208 55.3958) (xy 194.21619 55.3958) (xy 194.21619 55.3876) (xy 194.22439 55.3876)
			(xy 194.22439 55.37941) (xy 194.22439 55.37122) (xy 194.23258 55.37122) (xy 194.23258 55.36302) (xy 194.23258 55.35482)
			(xy 194.24078 55.35482) (xy 194.24078 55.34663) (xy 194.24078 55.33844) (xy 194.24897 55.33844) (xy 194.24897 55.33024)
			(xy 194.24897 55.32205) (xy 194.24897 55.31385) (xy 194.24897 55.30566) (xy 194.25717 55.30566) (xy 194.25717 55.29746)
			(xy 194.25717 55.28927) (xy 194.25717 55.28108) (xy 194.25717 55.27288) (xy 194.25717 55.26469) (xy 194.25717 55.25649)
			(xy 194.25717 55.2483) (xy 194.25717 55.2401) (xy 194.25717 55.23191) (xy 194.25717 55.22371) (xy 194.25717 55.21552)
			(xy 194.25717 55.20732) (xy 194.25717 55.19913) (xy 194.25717 55.19093) (xy 194.25717 55.18274) (xy 194.25717 55.17455)
			(xy 194.25717 55.16635) (xy 194.25717 55.15816) (xy 194.25717 55.14996) (xy 194.25717 55.14177) (xy 194.25717 55.13357)
			(xy 194.25717 55.12538) (xy 194.25717 55.11718) (xy 194.25717 55.10899) (xy 194.25717 55.1008) (xy 194.25717 55.0926)
			(xy 194.25717 55.08441) (xy 194.25717 55.07621) (xy 194.25717 55.06802) (xy 194.25717 55.05982) (xy 194.25717 55.05163)
			(xy 194.25717 55.04344) (xy 194.25717 55.03524) (xy 194.25717 55.02705) (xy 194.25717 55.01885) (xy 194.25717 55.01065)
			(xy 194.25717 55.00246) (xy 194.25717 54.99427) (xy 194.25717 54.98607) (xy 194.25717 54.97788) (xy 194.25717 54.96968)
			(xy 194.25717 54.96149) (xy 194.25717 54.95329) (xy 194.25717 54.9451) (xy 194.25717 54.93691) (xy 194.25717 54.92871)
			(xy 194.25717 54.92052) (xy 194.25717 54.91232) (xy 194.25717 54.90413) (xy 194.25717 54.89593) (xy 194.25717 54.88774)
			(xy 194.25717 54.87955) (xy 194.25717 54.87135) (xy 194.25717 54.86316) (xy 194.25717 54.85496) (xy 194.25717 54.84677)
			(xy 194.25717 54.83857) (xy 194.25717 54.83038) (xy 194.25717 54.82218) (xy 194.25717 54.81399) (xy 194.25717 54.80579)
			(xy 194.25717 54.7976) (xy 194.25717 54.78941) (xy 194.25717 54.78121) (xy 194.25717 54.77302) (xy 194.25717 54.76482)
			(xy 194.25717 54.75663) (xy 194.25717 54.74843) (xy 194.25717 54.74024) (xy 194.25717 54.73204) (xy 194.25717 54.72385)
			(xy 194.25717 54.71565) (xy 194.25717 54.70746) (xy 194.25717 54.69926) (xy 194.25717 54.69107) (xy 194.25717 54.68288)
			(xy 194.25717 54.67468) (xy 194.25717 54.66649) (xy 194.25717 54.65829) (xy 194.25717 54.6501) (xy 194.25717 54.6419)
			(xy 194.25717 54.63371) (xy 194.25717 54.62551) (xy 194.25717 54.61732) (xy 194.25717 54.60913) (xy 194.25717 54.60093)
			(xy 194.25717 54.59274) (xy 194.25717 54.58454) (xy 194.25717 54.57635) (xy 194.25717 54.56815) (xy 194.25717 54.55996)
			(xy 194.25717 54.55176) (xy 194.25717 54.54357) (xy 194.25717 54.53538) (xy 194.25717 54.52718) (xy 194.25717 54.51899)
			(xy 194.25717 54.51079) (xy 194.25717 54.5026) (xy 194.25717 54.4944) (xy 194.25717 54.48621) (xy 194.25717 54.47801)
			(xy 194.25717 54.46982) (xy 194.25717 54.46162) (xy 194.25717 54.45343) (xy 194.25717 54.44524) (xy 194.25717 54.43704)
			(xy 194.25717 54.42885) (xy 194.25717 54.42065) (xy 194.25717 54.41246) (xy 194.25717 54.40426) (xy 194.25717 54.39607)
			(xy 194.25717 54.38787) (xy 194.25717 54.37968) (xy 194.25717 54.37149) (xy 194.25717 54.36329) (xy 194.25717 54.3551)
			(xy 194.25717 54.3469) (xy 194.25717 54.33871) (xy 194.25717 54.33051) (xy 194.25717 54.32232) (xy 194.25717 54.31413)
			(xy 194.25717 54.30593) (xy 194.25717 54.29774) (xy 194.25717 54.28954) (xy 194.25717 54.28134) (xy 194.25717 54.27315)
			(xy 194.25717 54.26496) (xy 194.25717 54.25676) (xy 194.25717 54.24857) (xy 194.25717 54.24037) (xy 194.25717 54.23218)
			(xy 194.25717 54.22398) (xy 194.25717 54.21579) (xy 194.25717 54.2076) (xy 194.25717 54.1994) (xy 194.25717 54.19121)
			(xy 194.25717 54.18301) (xy 194.25717 54.17482) (xy 194.25717 54.16662) (xy 194.25717 54.15843) (xy 194.25717 54.15023)
			(xy 194.25717 54.14204) (xy 194.25717 54.13385) (xy 194.25717 54.12565) (xy 194.25717 54.11746) (xy 194.25717 54.10926)
			(xy 194.25717 54.10107) (xy 194.25717 54.09287) (xy 194.25717 54.08468) (xy 194.25717 54.07649) (xy 194.25717 54.06829)
			(xy 194.25717 54.0601) (xy 194.25717 54.0519) (xy 194.25717 54.0437) (xy 194.25717 54.03551) (xy 194.25717 54.02732)
			(xy 194.25717 54.01912) (xy 194.25717 54.01093) (xy 194.25717 54.00273) (xy 194.25717 53.99454) (xy 194.25717 53.98634)
			(xy 194.25717 53.97815) (xy 194.25717 53.96996) (xy 194.25717 53.96176) (xy 194.25717 53.95357) (xy 194.25717 53.94537)
			(xy 194.25717 53.93718) (xy 194.25717 53.92898) (xy 194.25717 53.92079) (xy 194.25717 53.91259) (xy 194.25717 53.9044)
			(xy 194.25717 53.8962) (xy 194.25717 53.88801) (xy 194.25717 53.87982) (xy 194.25717 53.87162) (xy 194.25717 53.86343)
			(xy 194.25717 53.85523) (xy 194.25717 53.84704) (xy 194.25717 53.83884) (xy 194.25717 53.83065) (xy 194.25717 53.82246)
			(xy 194.25717 53.81426) (xy 194.25717 53.80606) (xy 194.25717 53.79787) (xy 194.25717 53.78968) (xy 194.25717 53.78148)
			(xy 194.25717 53.77329) (xy 194.25717 53.76509) (xy 194.45383 53.76509) (xy 194.45383 53.77329) (xy 194.45383 53.78148)
			(xy 194.45383 53.78968) (xy 194.45383 53.79787) (xy 194.45383 53.80606) (xy 194.45383 53.81426) (xy 194.45383 53.82246)
			(xy 194.45383 53.83065) (xy 194.45383 53.83884) (xy 194.45383 53.84704) (xy 194.45383 53.85523) (xy 194.45383 53.86343)
			(xy 194.45383 53.87162) (xy 194.45383 53.87982) (xy 194.45383 53.88801) (xy 194.45383 53.8962) (xy 194.45383 53.9044)
			(xy 194.45383 53.91259) (xy 194.45383 53.92079) (xy 194.45383 53.92898) (xy 194.45383 53.93718) (xy 194.45383 53.94537)
			(xy 194.45383 53.95357) (xy 194.45383 53.96176) (xy 194.45383 53.96996) (xy 194.45383 53.97815) (xy 194.45383 53.98634)
			(xy 194.45383 53.99454) (xy 194.45383 54.00273) (xy 194.45383 54.01093) (xy 194.45383 54.01912) (xy 194.45383 54.02732)
			(xy 194.45383 54.03551) (xy 194.45383 54.0437) (xy 194.45383 54.0519) (xy 194.45383 54.0601) (xy 194.45383 54.06829)
			(xy 194.45383 54.07649) (xy 194.45383 54.08468) (xy 194.45383 54.09287) (xy 194.45383 54.10107) (xy 194.45383 54.10926)
			(xy 194.45383 54.11746) (xy 194.45383 54.12565) (xy 194.45383 54.13385) (xy 194.45383 54.14204) (xy 194.45383 54.15023)
			(xy 194.45383 54.15843) (xy 194.45383 54.16662) (xy 194.45383 54.17482) (xy 194.45383 54.18301) (xy 194.45383 54.19121)
			(xy 194.45383 54.1994) (xy 194.45383 54.2076) (xy 194.45383 54.21579) (xy 194.45383 54.22398) (xy 194.45383 54.23218)
			(xy 194.45383 54.24037) (xy 194.45383 54.24857) (xy 194.45383 54.25676) (xy 194.45383 54.26496) (xy 194.45383 54.27315)
			(xy 194.45383 54.28134) (xy 194.45383 54.28954) (xy 194.45383 54.29774) (xy 194.45383 54.30593) (xy 194.45383 54.31413)
			(xy 194.45383 54.32232) (xy 194.45383 54.33051) (xy 194.45383 54.33871) (xy 194.45383 54.3469) (xy 194.45383 54.3551)
			(xy 194.45383 54.36329) (xy 194.45383 54.37149) (xy 194.45383 54.37968) (xy 194.45383 54.38787) (xy 194.45383 54.39607)
			(xy 194.45383 54.40426) (xy 194.45383 54.41246) (xy 194.45383 54.42065) (xy 194.45383 54.42885) (xy 194.45383 54.43704)
			(xy 194.45383 54.44524) (xy 194.45383 54.45343) (xy 194.45383 54.46162) (xy 194.45383 54.46982) (xy 194.45383 54.47801)
			(xy 194.45383 54.48621) (xy 194.45383 54.4944) (xy 194.45383 54.5026) (xy 194.45383 54.51079) (xy 194.45383 54.51899)
			(xy 194.45383 54.52718) (xy 194.45383 54.53538) (xy 194.45383 54.54357) (xy 194.45383 54.55176) (xy 194.45383 54.55996)
			(xy 194.45383 54.56815) (xy 194.45383 54.57635) (xy 194.45383 54.58454) (xy 194.45383 54.59274) (xy 194.45383 54.60093)
			(xy 194.45383 54.60913) (xy 194.45383 54.61732) (xy 194.45383 54.62551) (xy 194.45383 54.63371) (xy 194.45383 54.6419)
			(xy 194.45383 54.6501) (xy 194.45383 54.65829) (xy 194.45383 54.66649) (xy 194.45383 54.67468) (xy 194.45383 54.68288)
			(xy 194.45383 54.69107) (xy 194.45383 54.69926) (xy 194.45383 54.70746) (xy 194.45383 54.71565) (xy 194.45383 54.72385)
			(xy 194.45383 54.73204) (xy 194.45383 54.74024) (xy 194.45383 54.74843) (xy 194.45383 54.75663) (xy 194.45383 54.76482)
			(xy 194.45383 54.77302) (xy 194.45383 54.78121) (xy 194.45383 54.78941) (xy 194.45383 54.7976) (xy 194.45383 54.80579)
			(xy 194.45383 54.81399) (xy 194.45383 54.82218) (xy 194.45383 54.83038) (xy 194.45383 54.83857) (xy 194.45383 54.84677)
			(xy 194.45383 54.85496) (xy 194.45383 54.86316) (xy 194.45383 54.87135) (xy 194.45383 54.87955) (xy 194.45383 54.88774)
			(xy 194.45383 54.89593) (xy 194.45383 54.90413) (xy 194.46203 54.90413) (xy 194.46203 54.91232) (xy 194.46203 54.92052)
			(xy 194.46203 54.92871) (xy 194.46203 54.93691) (xy 194.46203 54.9451) (xy 194.47022 54.9451) (xy 194.47022 54.95329)
			(xy 194.47022 54.96149) (xy 194.47842 54.96149) (xy 194.47842 54.96968) (xy 194.47842 54.97788) (xy 194.48661 54.97788)
			(xy 194.48661 54.98607) (xy 194.49481 54.98607) (xy 194.49481 54.99427) (xy 194.503 54.99427) (xy 194.503 55.00246)
			(xy 194.51119 55.00246) (xy 194.51119 55.01065) (xy 194.51939 55.01065) (xy 194.51939 55.01885) (xy 194.52759 55.01885)
			(xy 194.52759 55.02705) (xy 194.53578 55.02705) (xy 194.53578 55.03524) (xy 194.54397 55.03524) (xy 194.54397 55.04344)
			(xy 194.55217 55.04344) (xy 194.55217 55.05163) (xy 194.56036 55.05163) (xy 194.56036 55.05982) (xy 194.56856 55.05982)
			(xy 194.56856 55.06802) (xy 194.57675 55.06802) (xy 194.57675 55.07621) (xy 194.58495 55.07621) (xy 194.58495 55.08441)
			(xy 194.59314 55.08441) (xy 194.59314 55.0926) (xy 194.60133 55.0926) (xy 194.60133 55.1008) (xy 194.60953 55.1008)
			(xy 194.60953 55.10899) (xy 194.61772 55.10899) (xy 194.61772 55.11718) (xy 194.62592 55.11718) (xy 194.62592 55.12538)
			(xy 194.63411 55.12538) (xy 194.63411 55.13357) (xy 194.64231 55.13357) (xy 194.64231 55.14177) (xy 194.6505 55.14177)
			(xy 194.6505 55.14996) (xy 194.65869 55.14996) (xy 194.65869 55.15816) (xy 194.66689 55.15816) (xy 194.66689 55.16635)
			(xy 194.67509 55.16635) (xy 194.67509 55.17455) (xy 194.68328 55.17455) (xy 194.68328 55.18274) (xy 194.69148 55.18274)
			(xy 194.69148 55.19093) (xy 194.69967 55.19093) (xy 194.69967 55.19913) (xy 194.70786 55.19913) (xy 194.70786 55.20732)
			(xy 194.72425 55.20732) (xy 194.72425 55.21552) (xy 194.75703 55.21552) (xy 194.75703 55.22371) (xy 195.79773 55.22371)
			(xy 195.79773 55.21552) (xy 195.80592 55.21552) (xy 195.80592 55.20732) (xy 195.81412 55.20732) (xy 195.81412 55.19913)
			(xy 195.81412 55.19093) (xy 195.82231 55.19093) (xy 195.82231 55.18274) (xy 195.82231 55.17455) (xy 195.82231 55.16635)
			(xy 195.82231 55.15816) (xy 195.82231 55.14996) (xy 195.82231 55.14177) (xy 195.82231 55.13357) (xy 195.82231 55.12538)
			(xy 195.82231 55.11718) (xy 195.82231 55.10899) (xy 195.82231 55.1008) (xy 195.82231 55.0926) (xy 195.82231 55.08441)
			(xy 195.82231 55.07621) (xy 195.82231 55.06802) (xy 195.82231 55.05982) (xy 195.82231 55.05163) (xy 195.82231 55.04344)
			(xy 195.82231 55.03524) (xy 195.82231 55.02705) (xy 195.82231 55.01885) (xy 195.82231 55.01065) (xy 195.82231 55.00246)
			(xy 195.82231 54.99427) (xy 195.82231 54.98607) (xy 195.82231 54.97788) (xy 195.82231 54.96968) (xy 195.82231 54.96149)
			(xy 195.82231 54.95329) (xy 195.82231 54.9451) (xy 195.82231 54.93691) (xy 195.82231 54.92871) (xy 195.82231 54.92052)
			(xy 195.82231 54.91232) (xy 195.82231 54.90413) (xy 195.82231 54.89593) (xy 195.82231 54.88774) (xy 195.82231 54.87955)
			(xy 195.82231 54.87135) (xy 195.82231 54.86316) (xy 195.82231 54.85496) (xy 195.82231 54.84677) (xy 195.82231 54.83857)
			(xy 195.81412 54.83857) (xy 195.81412 54.83038) (xy 195.81412 54.82218) (xy 195.80592 54.82218) (xy 195.80592 54.81399)
			(xy 195.78954 54.81399) (xy 195.78954 54.80579) (xy 194.91273 54.80579) (xy 194.91273 54.7976) (xy 194.90453 54.7976)
			(xy 194.90453 54.78941) (xy 194.90453 54.78121) (xy 194.90453 54.77302) (xy 194.90453 54.76482) (xy 194.90453 54.75663)
			(xy 194.90453 54.74843) (xy 194.90453 54.74024) (xy 194.90453 54.73204) (xy 194.90453 54.72385) (xy 194.90453 54.71565)
			(xy 194.90453 54.70746) (xy 194.90453 54.69926) (xy 194.90453 54.69107) (xy 194.90453 54.68288) (xy 194.90453 54.67468)
			(xy 194.90453 54.66649) (xy 194.90453 54.65829) (xy 194.90453 54.6501) (xy 194.90453 54.6419) (xy 194.90453 54.63371)
			(xy 194.90453 54.62551) (xy 194.90453 54.61732) (xy 194.90453 54.60913) (xy 194.90453 54.60093) (xy 194.90453 54.59274)
			(xy 194.90453 54.58454) (xy 194.90453 54.57635) (xy 194.90453 54.56815) (xy 194.90453 54.55996) (xy 194.90453 54.55176)
			(xy 194.90453 54.54357) (xy 194.90453 54.53538) (xy 194.90453 54.52718) (xy 194.90453 54.51899) (xy 194.91273 54.51899)
			(xy 194.91273 54.51079) (xy 195.66662 54.51079) (xy 195.66662 54.5026) (xy 195.68301 54.5026) (xy 195.68301 54.4944)
			(xy 195.68301 54.48621) (xy 195.6912 54.48621) (xy 195.6912 54.47801) (xy 195.6912 54.46982) (xy 195.6912 54.46162)
			(xy 195.6912 54.45343) (xy 195.6912 54.44524) (xy 195.6912 54.43704) (xy 195.6912 54.42885) (xy 195.6912 54.42065)
			(xy 195.6912 54.41246) (xy 195.6912 54.40426) (xy 195.6912 54.39607) (xy 195.6912 54.38787) (xy 195.6912 54.37968)
			(xy 195.6912 54.37149) (xy 195.6912 54.36329) (xy 195.6912 54.3551) (xy 195.6912 54.3469) (xy 195.6912 54.33871)
			(xy 195.6912 54.33051) (xy 195.6912 54.32232) (xy 195.6912 54.31413) (xy 195.6912 54.30593) (xy 195.6912 54.29774)
			(xy 195.6912 54.28954) (xy 195.6912 54.28134) (xy 195.6912 54.27315) (xy 195.6912 54.26496) (xy 195.6912 54.25676)
			(xy 195.6912 54.24857) (xy 195.6912 54.24037) (xy 195.6912 54.23218) (xy 195.6912 54.22398) (xy 195.6912 54.21579)
			(xy 195.6912 54.2076) (xy 195.6912 54.1994) (xy 195.6912 54.19121) (xy 195.6912 54.18301) (xy 195.68301 54.18301)
			(xy 195.68301 54.17482) (xy 195.68301 54.16662) (xy 195.66662 54.16662) (xy 195.66662 54.15843) (xy 194.91273 54.15843)
			(xy 194.91273 54.15023) (xy 194.90453 54.15023) (xy 194.90453 54.14204) (xy 194.90453 54.13385) (xy 194.90453 54.12565)
			(xy 194.90453 54.11746) (xy 194.90453 54.10926) (xy 194.90453 54.10107) (xy 194.90453 54.09287) (xy 194.90453 54.08468)
			(xy 194.90453 54.07649) (xy 194.90453 54.06829) (xy 194.90453 54.0601) (xy 194.90453 54.0519) (xy 194.90453 54.0437)
			(xy 194.90453 54.03551) (xy 194.90453 54.02732) (xy 194.90453 54.01912) (xy 194.90453 54.01093) (xy 194.90453 54.00273)
			(xy 194.90453 53.99454) (xy 194.90453 53.98634) (xy 194.90453 53.97815) (xy 194.90453 53.96996) (xy 194.90453 53.96176)
			(xy 194.90453 53.95357) (xy 194.90453 53.94537) (xy 194.90453 53.93718) (xy 194.90453 53.92898) (xy 194.90453 53.92079)
			(xy 194.90453 53.91259) (xy 194.90453 53.9044) (xy 194.90453 53.8962) (xy 194.90453 53.88801) (xy 194.90453 53.87982)
			(xy 194.90453 53.87162) (xy 194.90453 53.86343) (xy 194.91273 53.86343) (xy 194.91273 53.85523) (xy 195.79773 53.85523)
			(xy 195.79773 53.84704) (xy 195.80592 53.84704) (xy 195.80592 53.83884) (xy 195.81412 53.83884) (xy 195.81412 53.83065)
			(xy 195.82231 53.83065) (xy 195.82231 53.82246) (xy 195.82231 53.81426) (xy 195.82231 53.80606) (xy 195.82231 53.79787)
			(xy 195.82231 53.78968) (xy 195.82231 53.78148) (xy 195.82231 53.77329) (xy 195.82231 53.76509) (xy 195.82231 53.7569)
			(xy 195.82231 53.7487) (xy 195.82231 53.74051) (xy 195.82231 53.73231) (xy 195.82231 53.72412) (xy 195.82231 53.71593)
			(xy 195.82231 53.70773) (xy 195.82231 53.69954) (xy 195.82231 53.69134) (xy 195.82231 53.68315) (xy 195.82231 53.67495)
			(xy 195.82231 53.66676) (xy 195.82231 53.65857) (xy 195.82231 53.65037) (xy 195.82231 53.64218) (xy 195.82231 53.63398)
			(xy 195.82231 53.62579) (xy 195.82231 53.61759) (xy 195.82231 53.6094) (xy 195.82231 53.6012) (xy 195.82231 53.59301)
			(xy 195.82231 53.58482) (xy 195.82231 53.57662) (xy 195.82231 53.56843) (xy 195.82231 53.56023) (xy 195.82231 53.55204)
			(xy 195.82231 53.54384) (xy 195.82231 53.53565) (xy 195.82231 53.52745) (xy 195.82231 53.51926) (xy 195.82231 53.51106)
			(xy 195.82231 53.50287) (xy 195.82231 53.49467) (xy 195.82231 53.48648) (xy 195.82231 53.47829) (xy 195.81412 53.47829)
			(xy 195.81412 53.47009) (xy 195.81412 53.4619) (xy 195.80592 53.4619) (xy 195.80592 53.4537) (xy 195.79773 53.4537)
			(xy 195.79773 53.44551) (xy 195.78134 53.44551) (xy 195.78134 53.43731) (xy 195.75676 53.43731) (xy 195.75676 53.44551)
			(xy 195.74856 53.44551) (xy 195.74856 53.43731) (xy 194.78981 53.43731) (xy 194.78981 53.44551) (xy 194.74884 53.44551)
			(xy 194.74884 53.4537) (xy 194.72425 53.4537) (xy 194.72425 53.4619) (xy 194.70786 53.4619) (xy 194.70786 53.47009)
			(xy 194.69967 53.47009) (xy 194.69967 53.47829) (xy 194.69148 53.47829) (xy 194.69148 53.48648) (xy 194.68328 53.48648)
			(xy 194.68328 53.49467) (xy 194.67509 53.49467) (xy 194.67509 53.50287) (xy 194.66689 53.50287) (xy 194.66689 53.51106)
			(xy 194.65869 53.51106) (xy 194.65869 53.51926) (xy 194.6505 53.51926) (xy 194.6505 53.52745) (xy 194.64231 53.52745)
			(xy 194.64231 53.53565) (xy 194.63411 53.53565) (xy 194.63411 53.54384) (xy 194.62592 53.54384) (xy 194.62592 53.55204)
			(xy 194.61772 53.55204) (xy 194.61772 53.56023) (xy 194.60953 53.56023) (xy 194.60953 53.56843) (xy 194.60133 53.56843)
			(xy 194.60133 53.57662) (xy 194.59314 53.57662) (xy 194.59314 53.58482) (xy 194.58495 53.58482) (xy 194.58495 53.59301)
			(xy 194.57675 53.59301) (xy 194.57675 53.6012) (xy 194.56856 53.6012) (xy 194.56856 53.6094) (xy 194.56036 53.6094)
			(xy 194.56036 53.61759) (xy 194.55217 53.61759) (xy 194.55217 53.62579) (xy 194.54397 53.62579) (xy 194.54397 53.63398)
			(xy 194.53578 53.63398) (xy 194.53578 53.64218) (xy 194.52759 53.64218) (xy 194.52759 53.65037) (xy 194.51939 53.65037)
			(xy 194.51939 53.65857) (xy 194.51119 53.65857) (xy 194.51119 53.66676) (xy 194.503 53.66676) (xy 194.503 53.67495)
			(xy 194.49481 53.67495) (xy 194.49481 53.68315) (xy 194.48661 53.68315) (xy 194.48661 53.69134) (xy 194.47842 53.69134)
			(xy 194.47842 53.69954) (xy 194.47022 53.69954) (xy 194.47022 53.70773) (xy 194.47022 53.71593) (xy 194.47022 53.72412)
			(xy 194.46203 53.72412) (xy 194.46203 53.73231) (xy 194.46203 53.74051) (xy 194.46203 53.7487) (xy 194.46203 53.7569)
			(xy 194.46203 53.76509) (xy 194.45383 53.76509) (xy 194.25717 53.76509) (xy 194.25717 53.7569) (xy 194.25717 53.7487)
			(xy 194.25717 53.74051) (xy 194.25717 53.73231) (xy 194.25717 53.72412) (xy 194.25717 53.71593) (xy 194.25717 53.70773)
			(xy 194.25717 53.69954) (xy 194.25717 53.69134) (xy 194.25717 53.68315) (xy 194.25717 53.67495) (xy 194.25717 53.66676)
			(xy 194.25717 53.65857) (xy 194.25717 53.65037) (xy 194.25717 53.64218) (xy 194.25717 53.63398) (xy 194.25717 53.62579)
			(xy 194.25717 53.61759) (xy 194.25717 53.6094) (xy 194.25717 53.6012) (xy 194.25717 53.59301) (xy 194.25717 53.58482)
			(xy 194.25717 53.57662) (xy 194.25717 53.56843) (xy 194.25717 53.56023) (xy 194.25717 53.55204) (xy 194.25717 53.54384)
			(xy 194.25717 53.53565) (xy 194.25717 53.52745) (xy 194.25717 53.51926) (xy 194.25717 53.51106) (xy 194.25717 53.50287)
			(xy 194.25717 53.49467) (xy 194.25717 53.48648) (xy 194.25717 53.47829) (xy 194.25717 53.47009) (xy 194.25717 53.4619)
			(xy 194.25717 53.4537) (xy 194.25717 53.44551) (xy 194.25717 53.43731) (xy 194.25717 53.42912) (xy 194.25717 53.42092)
			(xy 194.25717 53.41273) (xy 194.25717 53.40453) (xy 194.25717 53.39634) (xy 194.25717 53.38815) (xy 194.25717 53.37995)
			(xy 194.25717 53.37176) (xy 194.25717 53.36356) (xy 194.25717 53.35537) (xy 194.25717 53.34718) (xy 194.25717 53.33898)
			(xy 194.25717 53.33079) (xy 194.25717 53.32259) (xy 194.25717 53.31439) (xy 194.25717 53.3062) (xy 194.25717 53.29801)
			(xy 194.25717 53.28981) (xy 194.25717 53.28162) (xy 194.25717 53.27342) (xy 194.25717 53.26523) (xy 194.25717 53.25703)
			(xy 194.25717 53.24884) (xy 194.25717 53.24065) (xy 194.25717 53.23245) (xy 194.25717 53.22426) (xy 194.25717 53.21606)
			(xy 194.25717 53.20787) (xy 194.25717 53.19967) (xy 194.25717 53.19148) (xy 194.25717 53.18328) (xy 194.25717 53.17509)
			(xy 194.25717 53.16689) (xy 194.25717 53.1587) (xy 194.25717 53.15051) (xy 194.25717 53.14231) (xy 194.25717 53.13412)
			(xy 194.25717 53.12592) (xy 194.25717 53.11773) (xy 194.25717 53.10953) (xy 194.25717 53.10134) (xy 194.25717 53.09315)
			(xy 194.25717 53.08495) (xy 194.25717 53.07675) (xy 194.25717 53.06856) (xy 194.25717 53.06037) (xy 194.25717 53.05217)
			(xy 194.25717 53.04398) (xy 194.25717 53.03578) (xy 194.25717 53.02759) (xy 194.25717 53.01939) (xy 194.25717 53.0112)
			(xy 194.25717 53.00301) (xy 194.25717 52.99481) (xy 194.25717 52.98662) (xy 194.25717 52.97842) (xy 194.25717 52.97023)
			(xy 194.25717 52.96203) (xy 194.25717 52.95384) (xy 194.25717 52.94564) (xy 194.25717 52.93745) (xy 194.25717 52.92926)
			(xy 194.25717 52.92106) (xy 194.25717 52.91287) (xy 194.25717 52.90467) (xy 194.25717 52.89648) (xy 194.25717 52.88828)
			(xy 194.25717 52.88009) (xy 194.25717 52.87189) (xy 194.25717 52.8637) (xy 194.25717 52.85551) (xy 194.25717 52.84731)
			(xy 194.25717 52.83911) (xy 194.25717 52.83092) (xy 194.25717 52.82273) (xy 194.25717 52.81453) (xy 194.25717 52.80634)
			(xy 194.25717 52.79814) (xy 194.25717 52.78995) (xy 194.25717 52.78175) (xy 194.25717 52.77356) (xy 194.25717 52.76536)
			(xy 194.25717 52.75717) (xy 194.24897 52.75717) (xy 194.24897 52.74898) (xy 194.24897 52.74078) (xy 194.24897 52.73259)
			(xy 194.24897 52.72439) (xy 194.24078 52.72439) (xy 194.24078 52.7162) (xy 194.24078 52.708) (xy 194.23258 52.708)
			(xy 194.23258 52.69981) (xy 194.22439 52.69981) (xy 194.22439 52.69162) (xy 194.21619 52.69162) (xy 194.21619 52.68342)
			(xy 194.208 52.68342) (xy 194.208 52.67522) (xy 194.19981 52.67522) (xy 194.19981 52.66703) (xy 194.19161 52.66703)
			(xy 194.19161 52.65884) (xy 194.18342 52.65884) (xy 194.18342 52.65064) (xy 194.17522 52.65064) (xy 194.17522 52.64245)
			(xy 194.16703 52.64245) (xy 194.16703 52.63425) (xy 194.15883 52.63425) (xy 194.15883 52.62606) (xy 194.15064 52.62606)
			(xy 194.15064 52.61787) (xy 194.14244 52.61787) (xy 194.14244 52.60967) (xy 194.13425 52.60967) (xy 194.13425 52.60148)
			(xy 194.12605 52.60148) (xy 194.12605 52.59328) (xy 194.11786 52.59328) (xy 194.11786 52.58509) (xy 194.10967 52.58509)
			(xy 194.10967 52.57689) (xy 194.10147 52.57689) (xy 194.10147 52.5687) (xy 194.09328 52.5687) (xy 194.09328 52.5605)
			(xy 194.08508 52.5605) (xy 194.08508 52.55231) (xy 194.07689 52.55231) (xy 194.07689 52.54411) (xy 194.06869 52.54411)
			(xy 194.06869 52.53592) (xy 194.0605 52.53592) (xy 194.0605 52.52772) (xy 194.0523 52.52772) (xy 194.0523 52.51953)
			(xy 194.04411 52.51953) (xy 194.04411 52.51134) (xy 194.03591 52.51134) (xy 194.03591 52.50314) (xy 194.02772 52.50314)
			(xy 194.02772 52.49495) (xy 194.01953 52.49495) (xy 194.01953 52.48675) (xy 194.01133 52.48675) (xy 194.01133 52.47856)
			(xy 193.99494 52.47856) (xy 193.99494 52.47036) (xy 193.96217 52.47036) (xy 193.96217 52.46217) (xy 193.81466 52.46217)
			(xy 193.81466 52.47036) (xy 193.81466 52.47856) (xy 193.81466 52.48675) (xy 193.81466 52.49495) (xy 193.81466 52.50314)
			(xy 193.81466 52.51134) (xy 193.81466 52.51953) (xy 193.81466 52.52772) (xy 193.81466 52.53592) (xy 193.81466 52.54411)
			(xy 193.81466 52.55231) (xy 193.81466 52.5605) (xy 193.81466 52.5687) (xy 193.81466 52.57689) (xy 193.81466 52.58509)
			(xy 193.81466 52.59328) (xy 193.81466 52.60148) (xy 193.81466 52.60967) (xy 193.81466 52.61787) (xy 193.81466 52.62606)
			(xy 193.81466 52.63425) (xy 193.81466 52.64245) (xy 193.81466 52.65064) (xy 193.81466 52.65884) (xy 193.81466 52.66703)
			(xy 193.81466 52.67522) (xy 193.81466 52.68342) (xy 193.81466 52.69162) (xy 193.81466 52.69981) (xy 193.81466 52.708)
			(xy 193.81466 52.7162) (xy 193.81466 52.72439) (xy 193.81466 52.73259) (xy 193.81466 52.74078) (xy 193.81466 52.74898)
			(xy 193.81466 52.75717) (xy 193.81466 52.76536) (xy 193.81466 52.77356) (xy 193.81466 52.78175) (xy 193.81466 52.78995)
			(xy 193.81466 52.79814) (xy 193.81466 52.80634) (xy 193.81466 52.81453) (xy 193.81466 52.82273) (xy 193.81466 52.83092)
			(xy 193.81466 52.83911) (xy 193.81466 52.84731) (xy 193.81466 52.85551) (xy 193.81466 52.8637) (xy 193.81466 52.87189)
			(xy 193.81466 52.88009) (xy 193.81466 52.88828) (xy 193.81466 52.89648) (xy 193.81466 52.90467) (xy 193.81466 52.91287)
			(xy 193.81466 52.92106) (xy 193.81466 52.92926) (xy 193.81466 52.93745) (xy 193.81466 52.94564) (xy 193.81466 52.95384)
			(xy 193.81466 52.96203) (xy 193.81466 52.97023) (xy 193.81466 52.97842) (xy 193.81466 52.98662) (xy 193.81466 52.99481)
			(xy 193.81466 53.00301) (xy 193.81466 53.0112) (xy 193.81466 53.01939) (xy 193.81466 53.02759) (xy 193.81466 53.03578)
			(xy 193.81466 53.04398) (xy 193.81466 53.05217) (xy 193.81466 53.06037) (xy 193.81466 53.06856) (xy 193.81466 53.07675)
			(xy 193.81466 53.08495) (xy 193.81466 53.09315) (xy 193.81466 53.10134) (xy 193.81466 53.10953) (xy 193.81466 53.11773)
			(xy 193.81466 53.12592) (xy 193.81466 53.13412) (xy 193.81466 53.14231) (xy 193.81466 53.15051) (xy 193.81466 53.1587)
			(xy 193.81466 53.16689) (xy 193.81466 53.17509) (xy 193.81466 53.18328) (xy 193.81466 53.19148) (xy 193.81466 53.19967)
			(xy 193.81466 53.20787) (xy 193.81466 53.21606) (xy 193.81466 53.22426) (xy 193.81466 53.23245) (xy 193.81466 53.24065)
			(xy 193.81466 53.24884) (xy 193.81466 53.25703) (xy 193.81466 53.26523) (xy 193.81466 53.27342) (xy 193.81466 53.28162)
			(xy 193.81466 53.28981) (xy 193.81466 53.29801) (xy 193.81466 53.3062) (xy 193.81466 53.31439) (xy 193.81466 53.32259)
			(xy 193.81466 53.33079) (xy 193.81466 53.33898) (xy 193.81466 53.34718) (xy 193.81466 53.35537) (xy 193.81466 53.36356)
			(xy 193.81466 53.37176) (xy 193.81466 53.37995) (xy 193.81466 53.38815) (xy 193.81466 53.39634) (xy 193.81466 53.40453)
			(xy 193.81466 53.41273) (xy 193.81466 53.42092) (xy 193.81466 53.42912) (xy 193.81466 53.43731) (xy 193.81466 53.44551)
			(xy 193.81466 53.4537) (xy 193.81466 53.4619) (xy 193.81466 53.47009) (xy 193.81466 53.47829) (xy 193.81466 53.48648)
			(xy 193.81466 53.49467) (xy 193.81466 53.50287) (xy 193.81466 53.51106) (xy 193.81466 53.51926) (xy 193.81466 53.52745)
			(xy 193.81466 53.53565) (xy 193.81466 53.54384) (xy 193.81466 53.55204) (xy 193.81466 53.56023) (xy 193.81466 53.56843)
			(xy 193.81466 53.57662) (xy 193.81466 53.58482) (xy 193.81466 53.59301) (xy 193.81466 53.6012) (xy 193.81466 53.6094)
			(xy 193.81466 53.61759) (xy 193.81466 53.62579) (xy 193.81466 53.63398) (xy 193.81466 53.64218) (xy 193.81466 53.65037)
			(xy 193.81466 53.65857) (xy 193.81466 53.66676) (xy 193.81466 53.67495) (xy 193.81466 53.68315) (xy 193.81466 53.69134)
			(xy 193.81466 53.69954) (xy 193.81466 53.70773) (xy 193.81466 53.71593) (xy 193.81466 53.72412) (xy 193.81466 53.73231)
			(xy 193.81466 53.74051) (xy 193.81466 53.7487) (xy 193.81466 53.7569) (xy 193.81466 53.76509) (xy 193.81466 53.77329)
			(xy 193.81466 53.78148) (xy 193.81466 53.78968) (xy 193.81466 53.79787) (xy 193.81466 53.80606) (xy 193.81466 53.81426)
			(xy 193.81466 53.82246) (xy 193.81466 53.83065) (xy 193.81466 53.83884) (xy 193.81466 53.84704) (xy 193.81466 53.85523)
			(xy 193.81466 53.86343) (xy 193.81466 53.87162) (xy 193.81466 53.87982) (xy 193.81466 53.88801) (xy 193.81466 53.8962)
			(xy 193.81466 53.9044) (xy 193.81466 53.91259) (xy 193.81466 53.92079) (xy 193.81466 53.92898) (xy 193.81466 53.93718)
			(xy 193.81466 53.94537) (xy 193.81466 53.95357) (xy 193.81466 53.96176) (xy 193.81466 53.96996) (xy 193.81466 53.97815)
			(xy 193.81466 53.98634) (xy 193.81466 53.99454) (xy 193.81466 54.00273) (xy 193.81466 54.01093) (xy 193.81466 54.01912)
			(xy 193.81466 54.02732) (xy 193.81466 54.03551) (xy 193.81466 54.0437) (xy 193.81466 54.0519) (xy 193.81466 54.0601)
			(xy 193.81466 54.06829) (xy 193.81466 54.07649) (xy 193.81466 54.08468) (xy 193.81466 54.09287) (xy 193.81466 54.10107)
			(xy 193.81466 54.10926) (xy 193.81466 54.11746) (xy 193.81466 54.12565) (xy 193.81466 54.13385) (xy 193.81466 54.14204)
			(xy 193.81466 54.15023) (xy 193.81466 54.15843) (xy 193.81466 54.16662) (xy 193.81466 54.17482) (xy 193.81466 54.18301)
			(xy 193.81466 54.19121) (xy 193.81466 54.1994) (xy 193.81466 54.2076) (xy 193.81466 54.21579) (xy 193.81466 54.22398)
			(xy 193.81466 54.23218) (xy 193.81466 54.24037) (xy 193.81466 54.24857) (xy 193.81466 54.25676) (xy 193.81466 54.26496)
			(xy 193.81466 54.27315) (xy 193.81466 54.28134) (xy 193.81466 54.28954) (xy 193.81466 54.29774) (xy 193.81466 54.30593)
			(xy 193.81466 54.31413) (xy 193.81466 54.32232) (xy 193.81466 54.33051) (xy 193.81466 54.33871) (xy 193.81466 54.3469)
			(xy 193.81466 54.3551) (xy 193.81466 54.36329) (xy 193.81466 54.37149) (xy 193.81466 54.37968) (xy 193.81466 54.38787)
			(xy 193.81466 54.39607) (xy 193.81466 54.40426) (xy 193.81466 54.41246) (xy 193.81466 54.42065) (xy 193.81466 54.42885)
			(xy 193.81466 54.43704) (xy 193.81466 54.44524) (xy 193.81466 54.45343) (xy 193.81466 54.46162) (xy 193.81466 54.46982)
			(xy 193.81466 54.47801) (xy 193.81466 54.48621) (xy 193.81466 54.4944) (xy 193.81466 54.5026) (xy 193.81466 54.51079)
			(xy 193.81466 54.51899) (xy 193.81466 54.52718) (xy 193.81466 54.53538) (xy 193.81466 54.54357) (xy 193.81466 54.55176)
			(xy 193.81466 54.55996) (xy 193.81466 54.56815) (xy 193.81466 54.57635) (xy 193.81466 54.58454) (xy 193.81466 54.59274)
			(xy 193.81466 54.60093) (xy 193.81466 54.60913) (xy 193.81466 54.61732) (xy 193.81466 54.62551) (xy 193.81466 54.63371)
			(xy 193.81466 54.6419) (xy 193.81466 54.6501) (xy 193.81466 54.65829) (xy 193.81466 54.66649) (xy 193.81466 54.67468)
			(xy 193.81466 54.68288) (xy 193.81466 54.69107) (xy 193.81466 54.69926) (xy 193.81466 54.70746) (xy 193.81466 54.71565)
			(xy 193.81466 54.72385) (xy 193.81466 54.73204) (xy 193.81466 54.74024) (xy 193.81466 54.74843) (xy 193.81466 54.75663)
			(xy 193.81466 54.76482) (xy 193.81466 54.77302) (xy 193.81466 54.78121) (xy 193.81466 54.78941) (xy 193.81466 54.7976)
			(xy 193.81466 54.80579) (xy 193.81466 54.81399) (xy 193.81466 54.82218) (xy 193.81466 54.83038) (xy 193.81466 54.83857)
			(xy 193.81466 54.84677) (xy 193.81466 54.85496) (xy 193.81466 54.86316) (xy 193.81466 54.87135) (xy 193.81466 54.87955)
			(xy 193.81466 54.88774) (xy 193.81466 54.89593) (xy 193.81466 54.90413) (xy 193.81466 54.91232) (xy 193.81466 54.92052)
			(xy 193.81466 54.92871) (xy 193.81466 54.93691) (xy 193.81466 54.9451) (xy 193.81466 54.95329) (xy 193.81466 54.96149)
			(xy 193.81466 54.96968) (xy 193.81466 54.97788) (xy 193.81466 54.98607) (xy 193.81466 54.99427) (xy 193.81466 55.00246)
			(xy 193.81466 55.01065) (xy 193.81466 55.01885) (xy 193.81466 55.02705) (xy 193.81466 55.03524) (xy 193.81466 55.04344)
			(xy 193.81466 55.05163) (xy 193.81466 55.05982) (xy 193.81466 55.06802) (xy 193.81466 55.07621) (xy 193.81466 55.08441)
			(xy 193.81466 55.0926) (xy 193.81466 55.1008) (xy 193.81466 55.10899) (xy 193.81466 55.11718) (xy 193.81466 55.12538)
			(xy 193.81466 55.13357) (xy 193.81466 55.14177) (xy 193.81466 55.14996) (xy 193.81466 55.15816) (xy 193.81466 55.16635)
			(xy 193.81466 55.17455) (xy 193.80647 55.17455) (xy 193.80647 55.18274) (xy 193.79827 55.18274) (xy 193.79827 55.19093)
			(xy 193.79008 55.19093) (xy 193.79008 55.19913) (xy 193.78189 55.19913) (xy 193.78189 55.20732) (xy 193.77369 55.20732)
			(xy 193.77369 55.21552) (xy 193.7655 55.21552) (xy 193.7655 55.22371) (xy 193.7573 55.22371) (xy 193.7573 55.23191)
			(xy 193.74911 55.23191) (xy 193.74911 55.2401) (xy 193.74091 55.2401) (xy 193.74091 55.2483) (xy 193.73272 55.2483)
			(xy 193.73272 55.25649) (xy 193.72453 55.25649) (xy 193.72453 55.26469) (xy 193.71633 55.26469) (xy 193.71633 55.27288)
			(xy 193.70814 55.27288) (xy 193.70814 55.28108) (xy 193.69994 55.28108) (xy 193.69994 55.28927) (xy 193.69174 55.28927)
			(xy 193.69174 55.29746) (xy 193.68355 55.29746) (xy 193.68355 55.30566) (xy 193.67536 55.30566) (xy 193.67536 55.31385)
			(xy 193.65897 55.31385) (xy 193.65897 55.32205) (xy 193.65077 55.32205) (xy 193.65077 55.33024) (xy 193.64258 55.33024)
			(xy 193.64258 55.33844) (xy 193.63438 55.33844) (xy 193.63438 55.34663) (xy 193.62619 55.34663) (xy 193.62619 55.35482)
			(xy 193.618 55.35482) (xy 193.618 55.36302) (xy 193.6098 55.36302) (xy 193.6098 55.37122) (xy 193.60161 55.37122)
			(xy 193.60161 55.37941) (xy 193.59341 55.37941) (xy 193.59341 55.3876) (xy 193.58522 55.3876) (xy 193.58522 55.3958)
			(xy 193.57702 55.3958) (xy 193.57702 55.40399) (xy 193.56883 55.40399) (xy 193.56883 55.41219) (xy 193.56063 55.41219)
			(xy 193.56063 55.42038) (xy 193.55244 55.42038) (xy 193.55244 55.42857) (xy 193.54425 55.42857) (xy 193.54425 55.43677)
			(xy 193.53605 55.43677) (xy 193.53605 55.44496) (xy 193.52786 55.44496) (xy 193.52786 55.45316) (xy 193.51966 55.45316)
			(xy 193.51966 55.46136) (xy 193.51147 55.46136) (xy 193.51147 55.46955) (xy 193.50327 55.46955) (xy 193.50327 55.47774)
			(xy 193.49508 55.47774) (xy 193.49508 55.48594) (xy 193.48688 55.48594) (xy 193.48688 55.49413) (xy 193.47869 55.49413)
			(xy 193.47869 55.50233) (xy 193.4705 55.50233) (xy 193.4705 55.51052) (xy 193.4623 55.51052) (xy 193.4623 55.51872)
			(xy 193.4541 55.51872) (xy 193.4541 55.52691) (xy 193.44591 55.52691) (xy 193.44591 55.5351) (xy 193.43772 55.5351)
			(xy 193.43772 55.5433) (xy 193.42952 55.5433) (xy 193.42952 55.55149) (xy 193.42133 55.55149) (xy 193.42133 55.55969)
			(xy 193.41313 55.55969) (xy 193.41313 55.56788) (xy 193.40494 55.56788) (xy 193.40494 55.57608) (xy 193.39674 55.57608)
			(xy 193.39674 55.58427) (xy 193.38855 55.58427) (xy 193.38855 55.59247) (xy 193.38036 55.59247) (xy 193.38036 55.60066)
			(xy 193.37216 55.60066) (xy 193.37216 55.60885) (xy 193.36397 55.60885) (xy 193.36397 55.61705) (xy 193.35577 55.61705)
			(xy 193.35577 55.62524) (xy 193.34758 55.62524) (xy 193.34758 55.63344) (xy 193.33938 55.63344) (xy 193.33938 55.64163)
			(xy 193.33119 55.64163) (xy 193.33119 55.64983) (xy 193.32299 55.64983) (xy 193.32299 55.65802) (xy 193.3148 55.65802)
			(xy 193.3148 55.66622) (xy 193.30661 55.66622) (xy 193.30661 55.67441) (xy 193.29841 55.67441) (xy 193.29841 55.6826)
			(xy 193.29021 55.6826) (xy 193.29021 55.6908) (xy 193.28202 55.6908) (xy 193.28202 55.69899) (xy 193.27383 55.69899)
			(xy 193.27383 55.70719) (xy 193.26563 55.70719) (xy 193.26563 55.71538) (xy 193.25744 55.71538) (xy 193.25744 55.72358)
			(xy 193.24924 55.72358) (xy 193.24924 55.73177) (xy 193.24105 55.73177) (xy 193.24105 55.73997) (xy 193.23286 55.73997)
			(xy 193.23286 55.74816) (xy 193.22466 55.74816) (xy 193.22466 55.75636) (xy 193.21646 55.75636) (xy 193.21646 55.76455)
			(xy 193.20827 55.76455) (xy 193.20827 55.77274) (xy 193.20008 55.77274) (xy 193.20008 55.78094) (xy 193.19188 55.78094)
			(xy 193.19188 55.78913) (xy 193.18369 55.78913) (xy 193.18369 55.79733) (xy 193.17549 55.79733) (xy 193.17549 55.80552)
			(xy 193.1673 55.80552) (xy 193.1673 55.81372) (xy 193.1591 55.81372) (xy 193.1591 55.82191) (xy 193.15091 55.82191)
			(xy 193.15091 55.83011) (xy 193.14271 55.83011) (xy 193.14271 55.8383) (xy 193.13452 55.8383) (xy 193.13452 55.84649)
			(xy 193.12633 55.84649) (xy 193.12633 55.85469) (xy 193.11813 55.85469) (xy 193.11813 55.86288) (xy 193.10174 55.86288)
			(xy 193.10174 55.87108) (xy 193.09355 55.87108) (xy 193.09355 55.87927) (xy 193.08535 55.87927) (xy 193.08535 55.88747)
			(xy 193.07716 55.88747) (xy 193.07716 55.89566) (xy 193.06896 55.89566) (xy 193.06896 55.90386) (xy 193.06077 55.90386)
			(xy 193.06077 55.91205) (xy 193.05258 55.91205) (xy 193.05258 55.92024) (xy 193.04438 55.92024) (xy 193.04438 55.92844)
			(xy 193.03619 55.92844) (xy 193.03619 55.93663) (xy 193.02799 55.93663) (xy 193.02799 55.94483) (xy 193.0198 55.94483)
			(xy 193.0198 55.95302) (xy 193.0116 55.95302) (xy 193.0116 55.96122) (xy 193.00341 55.96122) (xy 193.00341 55.96941)
			(xy 192.99521 55.96941) (xy 192.99521 55.97761) (xy 192.98702 55.97761) (xy 192.98702 55.9858) (xy 192.97883 55.9858)
			(xy 192.97883 55.994) (xy 192.97063 55.994) (xy 192.97063 56.00219) (xy 192.97063 56.01039) (xy 192.96243 56.01039)
			(xy 192.96243 56.01858) (xy 192.95424 56.01858) (xy 192.95424 56.02677) (xy 192.95424 56.03497) (xy 192.94605 56.03497)
			(xy 192.94605 56.04316) (xy 192.94605 56.05136) (xy 192.93785 56.05136) (xy 192.22493 56.05136) (xy 192.22493 56.04316)
			(xy 192.22493 56.03497) (xy 192.22493 56.02677) (xy 192.22493 56.01858) (xy 192.22493 56.01039) (xy 192.22493 56.00219)
			(xy 192.22493 55.994) (xy 192.22493 55.9858) (xy 192.22493 55.97761) (xy 192.22493 55.96941) (xy 192.22493 55.96122)
			(xy 192.22493 55.95302) (xy 192.22493 55.94483) (xy 192.22493 55.93663) (xy 192.22493 55.92844) (xy 192.22493 55.92024)
			(xy 192.22493 55.91205) (xy 192.22493 55.90386) (xy 192.22493 55.89566) (xy 192.22493 55.88747) (xy 192.22493 55.87927)
			(xy 192.22493 55.87108) (xy 192.22493 55.86288) (xy 192.22493 55.85469) (xy 192.22493 55.84649) (xy 192.22493 55.8383)
			(xy 192.22493 55.83011) (xy 192.23313 55.83011) (xy 192.23313 55.82191) (xy 192.24132 55.82191) (xy 192.24132 55.81372)
			(xy 193.05258 55.81372) (xy 193.05258 55.80552) (xy 193.06077 55.80552) (xy 193.06077 55.81372) (xy 193.09355 55.81372)
			(xy 193.09355 55.80552) (xy 193.11813 55.80552) (xy 193.11813 55.79733) (xy 193.12633 55.79733) (xy 193.12633 55.78913)
			(xy 193.13452 55.78913) (xy 193.13452 55.78094) (xy 193.13452 55.77274) (xy 193.13452 55.76455) (xy 193.13452 55.75636)
			(xy 193.13452 55.74816) (xy 193.13452 55.73997) (xy 193.13452 55.73177) (xy 193.13452 55.72358) (xy 193.13452 55.71538)
			(xy 193.13452 55.70719) (xy 193.13452 55.69899) (xy 193.13452 55.6908) (xy 193.13452 55.6826) (xy 193.13452 55.67441)
			(xy 193.13452 55.66622) (xy 193.13452 55.65802) (xy 193.13452 55.64983) (xy 193.13452 55.64163) (xy 193.13452 55.63344)
			(xy 193.13452 55.62524) (xy 193.13452 55.61705) (xy 193.13452 55.60885) (xy 193.13452 55.60066) (xy 193.13452 55.59247)
			(xy 193.13452 55.58427) (xy 193.13452 55.57608) (xy 193.13452 55.56788) (xy 193.13452 55.55969) (xy 193.13452 55.55149)
			(xy 193.13452 55.5433) (xy 193.13452 55.5351) (xy 193.13452 55.52691) (xy 193.13452 55.51872) (xy 193.13452 55.51052)
			(xy 193.13452 55.50233) (xy 193.13452 55.49413) (xy 193.13452 55.48594) (xy 193.13452 55.47774) (xy 193.13452 55.46955)
			(xy 193.13452 55.46136) (xy 193.13452 55.45316) (xy 193.13452 55.44496) (xy 193.13452 55.43677) (xy 193.13452 55.42857)
			(xy 193.13452 55.42038) (xy 193.13452 55.41219) (xy 193.13452 55.40399) (xy 193.13452 55.3958) (xy 193.12633 55.3958)
			(xy 193.12633 55.3876) (xy 193.11813 55.3876) (xy 193.11813 55.37941) (xy 193.09355 55.37941) (xy 193.09355 55.37122)
			(xy 193.07716 55.37122) (xy 193.07716 55.37941) (xy 193.06896 55.37941) (xy 193.06896 55.37122) (xy 192.08563 55.37122)
			(xy 192.08563 55.37941) (xy 192.06104 55.37941) (xy 192.06104 55.3876) (xy 192.03646 55.3876) (xy 192.03646 55.3958)
			(xy 192.02007 55.3958) (xy 192.02007 55.40399) (xy 192.01188 55.40399) (xy 192.01188 55.41219) (xy 192.00368 55.41219)
			(xy 192.00368 55.42038) (xy 191.99548 55.42038) (xy 191.99548 55.42857) (xy 191.98729 55.42857) (xy 191.98729 55.43677)
			(xy 191.9791 55.43677) (xy 191.9791 55.44496) (xy 191.9709 55.44496) (xy 191.9709 55.45316) (xy 191.96271 55.45316)
			(xy 191.96271 55.46136) (xy 191.95451 55.46136) (xy 191.95451 55.46955) (xy 191.94632 55.46955) (xy 191.94632 55.47774)
			(xy 191.93812 55.47774) (xy 191.93812 55.48594) (xy 191.92993 55.48594) (xy 191.92993 55.49413) (xy 191.92174 55.49413)
			(xy 191.92174 55.50233) (xy 191.91354 55.50233) (xy 191.91354 55.51052) (xy 191.90534 55.51052) (xy 191.90534 55.51872)
			(xy 191.89715 55.51872) (xy 191.89715 55.52691) (xy 191.88896 55.52691) (xy 191.88896 55.5351) (xy 191.88076 55.5351)
			(xy 191.88076 55.5433) (xy 191.87257 55.5433) (xy 191.87257 55.55149) (xy 191.86437 55.55149) (xy 191.86437 55.55969)
			(xy 191.85618 55.55969) (xy 191.85618 55.56788) (xy 191.84798 55.56788) (xy 191.84798 55.57608) (xy 191.83979 55.57608)
			(xy 191.83979 55.58427) (xy 191.8316 55.58427) (xy 191.8316 55.59247) (xy 191.8234 55.59247) (xy 191.8234 55.60066)
			(xy 191.81521 55.60066) (xy 191.81521 55.60885) (xy 191.80701 55.60885) (xy 191.80701 55.61705) (xy 191.79882 55.61705)
			(xy 191.79882 55.62524) (xy 191.79063 55.62524) (xy 191.79063 55.63344) (xy 191.79063 55.64163) (xy 191.78243 55.64163)
			(xy 191.78243 55.64983) (xy 191.78243 55.65802) (xy 191.78243 55.66622) (xy 191.78243 55.67441) (xy 191.77424 55.67441)
			(xy 191.04492 55.67441) (xy 191.04492 55.66622) (xy 191.04492 55.65802) (xy 191.04492 55.64983) (xy 191.04492 55.64163)
			(xy 191.03673 55.64163) (xy 191.03673 55.63344) (xy 191.03673 55.62524) (xy 191.03673 55.61705) (xy 191.03673 55.60885)
			(xy 191.03673 55.60066) (xy 191.03673 55.59247) (xy 191.03673 55.58427) (xy 191.03673 55.57608) (xy 191.03673 55.56788)
			(xy 191.03673 55.55969) (xy 191.02853 55.55969) (xy 191.02853 55.55149) (xy 191.02853 55.5433) (xy 191.02853 55.5351)
			(xy 191.02853 55.52691) (xy 191.02853 55.51872) (xy 191.02853 55.51052) (xy 191.02853 55.50233) (xy 191.02853 55.49413)
			(xy 191.02853 55.48594) (xy 191.02853 55.47774) (xy 191.02853 55.46955) (xy 191.02853 55.46136) (xy 191.02853 55.45316)
			(xy 191.02853 55.44496) (xy 191.02853 55.43677) (xy 191.02853 55.42857) (xy 191.02034 55.42857) (xy 191.02034 55.42038)
			(xy 191.02034 55.41219) (xy 191.02034 55.40399) (xy 191.02034 55.3958) (xy 191.02034 55.3876) (xy 191.02034 55.37941)
			(xy 190.92201 55.37941) (xy 190.92201 55.3876) (xy 189.82394 55.3876) (xy 189.82394 55.37941) (xy 189.82394 55.37122)
			(xy 189.82394 55.36302) (xy 189.82394 55.35482) (xy 189.82394 55.34663) (xy 189.82394 55.33844) (xy 189.82394 55.33024)
			(xy 189.82394 55.32205) (xy 189.82394 55.31385) (xy 189.82394 55.30566) (xy 189.82394 55.29746) (xy 189.82394 55.28927)
			(xy 189.82394 55.28108) (xy 189.82394 55.27288) (xy 189.82394 55.26469) (xy 189.82394 55.25649) (xy 189.82394 55.2483)
			(xy 189.82394 55.2401) (xy 189.82394 55.23191) (xy 189.82394 55.22371) (xy 189.82394 55.21552) (xy 189.82394 55.20732)
			(xy 189.82394 55.19913) (xy 189.82394 55.19093) (xy 189.82394 55.18274) (xy 189.82394 55.17455) (xy 189.82394 55.16635)
			(xy 189.82394 55.15816) (xy 189.82394 55.14996) (xy 189.82394 55.14177) (xy 189.82394 55.13357) (xy 189.82394 55.12538)
			(xy 189.82394 55.11718) (xy 189.82394 55.10899) (xy 189.82394 55.1008) (xy 189.82394 55.0926) (xy 189.82394 55.08441)
			(xy 189.82394 55.07621) (xy 189.82394 55.06802) (xy 189.82394 55.05982) (xy 189.82394 55.05163) (xy 189.82394 55.04344)
			(xy 189.82394 55.03524) (xy 189.82394 55.02705) (xy 189.82394 55.01885) (xy 189.82394 55.01065) (xy 189.82394 55.00246)
			(xy 189.82394 54.99427) (xy 189.82394 54.98607) (xy 189.82394 54.97788) (xy 189.82394 54.96968) (xy 189.82394 54.96149)
			(xy 189.82394 54.95329) (xy 189.82394 54.9451) (xy 189.82394 54.93691) (xy 189.82394 54.92871) (xy 189.82394 54.92052)
			(xy 189.82394 54.91232) (xy 189.82394 54.90413) (xy 189.82394 54.89593) (xy 189.82394 54.88774) (xy 189.82394 54.87955)
			(xy 189.82394 54.87135) (xy 189.82394 54.86316) (xy 189.82394 54.85496) (xy 189.82394 54.84677) (xy 189.82394 54.83857)
			(xy 189.82394 54.83038) (xy 189.82394 54.82218) (xy 189.82394 54.81399) (xy 189.82394 54.80579) (xy 189.82394 54.7976)
			(xy 189.82394 54.78941) (xy 189.82394 54.78121) (xy 189.82394 54.77302) (xy 189.82394 54.76482) (xy 189.82394 54.75663)
			(xy 189.82394 54.74843) (xy 189.82394 54.74024) (xy 189.82394 54.73204) (xy 189.82394 54.72385) (xy 189.82394 54.71565)
			(xy 189.02908 54.71565) (xy 189.02908 54.70746) (xy 189.02908 54.69926) (xy 189.02908 54.69107) (xy 189.02908 54.68288)
			(xy 189.02908 54.67468) (xy 189.02908 54.66649) (xy 189.02908 54.65829) (xy 189.02908 54.6501) (xy 189.02908 54.6419)
			(xy 189.02908 54.63371) (xy 189.02908 54.62551) (xy 189.02908 54.61732) (xy 189.02908 54.60913) (xy 189.02908 54.60093)
			(xy 189.02908 54.59274) (xy 189.02908 54.58454) (xy 189.02908 54.57635) (xy 189.02908 54.56815) (xy 189.02908 54.55996)
			(xy 189.02908 54.55176) (xy 189.02908 54.54357) (xy 189.02908 54.53538) (xy 189.02908 54.52718) (xy 189.02908 54.51899)
			(xy 189.02908 54.51079) (xy 189.02908 54.5026) (xy 189.02908 54.4944) (xy 189.02908 54.48621) (xy 189.02908 54.47801)
			(xy 189.02908 54.46982) (xy 189.02908 54.46162) (xy 189.02908 54.45343) (xy 189.02908 54.44524) (xy 189.02908 54.43704)
			(xy 189.02908 54.42885) (xy 189.02908 54.42065) (xy 189.02908 54.41246) (xy 189.02908 54.40426) (xy 189.02908 54.39607)
			(xy 189.02908 54.38787) (xy 189.02908 54.37968) (xy 189.02908 54.37149) (xy 189.02908 54.36329) (xy 189.02908 54.3551)
			(xy 189.02908 54.3469) (xy 189.02908 54.33871) (xy 189.02908 54.33051) (xy 189.02908 54.32232) (xy 189.02908 54.31413)
			(xy 189.02908 54.30593) (xy 189.02908 54.29774) (xy 189.02908 54.28954) (xy 189.02908 54.28134) (xy 189.02908 54.27315)
			(xy 189.02908 54.26496) (xy 189.02908 54.25676) (xy 189.02908 54.24857) (xy 189.02908 54.24037) (xy 189.02908 54.23218)
			(xy 189.02908 54.22398) (xy 189.02908 54.21579) (xy 189.02908 54.2076) (xy 189.02908 54.1994) (xy 189.02908 54.19121)
			(xy 189.02908 54.18301) (xy 189.02908 54.17482) (xy 189.02908 54.16662) (xy 189.02908 54.15843) (xy 189.02908 54.15023)
			(xy 189.02908 54.14204) (xy 189.02908 54.13385) (xy 189.02908 54.12565) (xy 189.02908 54.11746) (xy 189.02908 54.10926)
			(xy 189.02908 54.10107) (xy 189.02908 54.09287) (xy 189.02908 54.08468) (xy 189.02908 54.07649) (xy 189.02908 54.06829)
			(xy 189.02908 54.0601) (xy 189.02908 54.0519) (xy 189.02908 54.0437) (xy 189.02908 54.03551) (xy 189.02908 54.02732)
			(xy 189.02908 54.01912) (xy 189.02908 54.01093) (xy 189.02908 54.00273) (xy 189.02908 53.99454) (xy 189.02908 53.98634)
			(xy 189.02908 53.97815) (xy 189.02908 53.96996) (xy 189.02908 53.96176) (xy 189.02908 53.95357) (xy 189.02908 53.94537)
			(xy 189.02908 53.93718) (xy 189.02908 53.92898) (xy 189.02908 53.92079) (xy 189.02908 53.91259) (xy 189.02908 53.9044)
			(xy 189.02908 53.8962) (xy 189.02908 53.88801) (xy 189.02908 53.87982) (xy 189.02908 53.87162) (xy 189.02908 53.86343)
			(xy 189.02908 53.85523) (xy 189.02908 53.84704) (xy 189.02908 53.83884) (xy 189.02908 53.83065) (xy 189.02908 53.82246)
			(xy 189.02908 53.81426) (xy 189.02908 53.80606) (xy 189.02908 53.79787) (xy 189.02908 53.78968) (xy 189.02908 53.78148)
			(xy 189.02908 53.77329) (xy 189.02908 53.76509) (xy 189.02908 53.7569) (xy 189.02908 53.7487) (xy 189.02908 53.74051)
			(xy 189.02908 53.73231) (xy 189.02908 53.72412) (xy 189.02908 53.71593) (xy 189.02908 53.70773) (xy 189.02908 53.69954)
			(xy 189.02908 53.69134) (xy 189.02908 53.68315) (xy 189.02908 53.67495) (xy 189.02908 53.66676) (xy 189.02908 53.65857)
			(xy 189.02908 53.65037) (xy 189.02908 53.64218) (xy 189.02908 53.63398) (xy 189.02908 53.62579) (xy 189.02908 53.61759)
			(xy 189.02908 53.6094) (xy 189.02908 53.6012) (xy 189.02908 53.59301) (xy 189.02908 53.58482) (xy 189.02908 53.57662)
			(xy 189.02908 53.56843) (xy 189.02908 53.56023) (xy 189.02908 53.55204) (xy 189.02908 53.54384) (xy 189.02908 53.53565)
			(xy 189.02908 53.52745) (xy 189.02908 53.51926) (xy 189.02908 53.51106) (xy 189.02908 53.50287) (xy 189.02908 53.49467)
			(xy 189.02908 53.48648) (xy 189.02908 53.47829) (xy 189.02908 53.47009) (xy 190.25825 53.47009) (xy 190.25825 53.47829)
			(xy 190.25825 53.48648) (xy 190.25825 53.49467) (xy 190.25825 53.50287) (xy 190.25825 53.51106) (xy 190.25825 53.51926)
			(xy 190.25825 53.52745) (xy 190.25825 53.53565) (xy 190.25825 53.54384) (xy 190.25825 53.55204) (xy 190.25825 53.56023)
			(xy 190.25825 53.56843) (xy 190.25825 53.57662) (xy 190.25825 53.58482) (xy 190.25825 53.59301) (xy 190.25825 53.6012)
			(xy 190.25825 53.6094) (xy 190.25825 53.61759) (xy 190.25825 53.62579) (xy 190.25825 53.63398) (xy 190.25825 53.64218)
			(xy 190.25825 53.65037) (xy 190.25825 53.65857) (xy 190.25825 53.66676) (xy 190.25825 53.67495) (xy 190.25825 53.68315)
			(xy 190.25825 53.69134) (xy 190.25825 53.69954) (xy 190.25825 53.70773) (xy 190.25825 53.71593) (xy 190.25825 53.72412)
			(xy 190.25825 53.73231) (xy 190.25825 53.74051) (xy 190.25825 53.7487) (xy 190.25825 53.7569) (xy 190.25825 53.76509)
			(xy 190.25825 53.77329) (xy 190.25825 53.78148) (xy 190.25825 53.78968) (xy 190.25825 53.79787) (xy 190.25825 53.80606)
			(xy 190.25825 53.81426) (xy 190.25825 53.82246) (xy 190.25825 53.83065) (xy 190.25825 53.83884) (xy 190.25825 53.84704)
			(xy 190.26645 53.84704) (xy 190.26645 53.85523) (xy 190.27464 53.85523) (xy 190.27464 53.86343) (xy 190.28284 53.86343)
			(xy 190.28284 53.87162) (xy 190.29923 53.87162) (xy 190.29923 53.87982) (xy 190.69256 53.87982) (xy 190.69256 53.88801)
			(xy 190.70075 53.88801) (xy 190.70075 53.8962) (xy 190.70895 53.8962) (xy 190.70895 53.9044) (xy 190.70895 53.91259)
			(xy 190.71715 53.91259) (xy 190.71715 53.92079) (xy 190.71715 53.92898) (xy 190.71715 53.93718) (xy 190.71715 53.94537)
			(xy 190.71715 53.95357) (xy 190.71715 53.96176) (xy 190.71715 53.96996) (xy 190.71715 53.97815) (xy 190.71715 53.98634)
			(xy 190.71715 53.99454) (xy 190.71715 54.00273) (xy 190.71715 54.01093) (xy 190.71715 54.01912) (xy 190.71715 54.02732)
			(xy 190.71715 54.03551) (xy 190.71715 54.0437) (xy 190.71715 54.0519) (xy 190.71715 54.0601) (xy 190.71715 54.06829)
			(xy 190.71715 54.07649) (xy 190.71715 54.08468) (xy 190.71715 54.09287) (xy 190.71715 54.10107) (xy 190.71715 54.10926)
			(xy 190.71715 54.11746) (xy 190.71715 54.12565) (xy 190.71715 54.13385) (xy 190.71715 54.14204) (xy 190.71715 54.15023)
			(xy 190.71715 54.15843) (xy 190.71715 54.16662) (xy 190.71715 54.17482) (xy 190.71715 54.18301) (xy 190.71715 54.19121)
			(xy 190.71715 54.1994) (xy 190.71715 54.2076) (xy 190.71715 54.21579) (xy 190.71715 54.22398) (xy 190.71715 54.23218)
			(xy 190.71715 54.24037) (xy 190.71715 54.24857) (xy 190.71715 54.25676) (xy 190.71715 54.26496) (xy 190.71715 54.27315)
			(xy 190.71715 54.28134) (xy 190.71715 54.28954) (xy 190.71715 54.29774) (xy 190.71715 54.30593) (xy 190.71715 54.31413)
			(xy 190.71715 54.32232) (xy 190.71715 54.33051) (xy 190.71715 54.33871) (xy 190.71715 54.3469) (xy 190.71715 54.3551)
			(xy 190.71715 54.36329) (xy 190.71715 54.37149) (xy 190.71715 54.37968) (xy 190.71715 54.38787) (xy 190.71715 54.39607)
			(xy 190.71715 54.40426) (xy 190.71715 54.41246) (xy 190.71715 54.42065) (xy 190.71715 54.42885) (xy 190.71715 54.43704)
			(xy 190.71715 54.44524) (xy 190.71715 54.45343) (xy 190.71715 54.46162) (xy 190.71715 54.46982) (xy 190.71715 54.47801)
			(xy 190.71715 54.48621) (xy 190.71715 54.4944) (xy 190.71715 54.5026) (xy 190.71715 54.51079) (xy 190.71715 54.51899)
			(xy 190.71715 54.52718) (xy 190.71715 54.53538) (xy 190.71715 54.54357) (xy 190.71715 54.55176) (xy 190.71715 54.55996)
			(xy 190.71715 54.56815) (xy 190.71715 54.57635) (xy 190.71715 54.58454) (xy 190.71715 54.59274) (xy 190.71715 54.60093)
			(xy 190.71715 54.60913) (xy 190.71715 54.61732) (xy 190.71715 54.62551) (xy 190.71715 54.63371) (xy 190.71715 54.6419)
			(xy 190.71715 54.6501) (xy 190.71715 54.65829) (xy 190.71715 54.66649) (xy 190.71715 54.67468) (xy 190.71715 54.68288)
			(xy 190.71715 54.69107) (xy 190.71715 54.69926) (xy 190.71715 54.70746) (xy 190.71715 54.71565) (xy 190.71715 54.72385)
			(xy 190.71715 54.73204) (xy 190.71715 54.74024) (xy 190.71715 54.74843) (xy 190.71715 54.75663) (xy 190.71715 54.76482)
			(xy 190.71715 54.77302) (xy 190.71715 54.78121) (xy 190.71715 54.78941) (xy 190.71715 54.7976) (xy 190.71715 54.80579)
			(xy 190.71715 54.81399) (xy 190.71715 54.82218) (xy 190.71715 54.83038) (xy 190.71715 54.83857) (xy 190.71715 54.84677)
			(xy 190.71715 54.85496) (xy 190.71715 54.86316) (xy 190.71715 54.87135) (xy 190.71715 54.87955) (xy 190.71715 54.88774)
			(xy 190.71715 54.89593) (xy 190.71715 54.90413) (xy 190.71715 54.91232) (xy 190.71715 54.92052) (xy 190.71715 54.92871)
			(xy 190.71715 54.93691) (xy 190.71715 54.9451) (xy 190.71715 54.95329) (xy 190.71715 54.96149) (xy 190.71715 54.96968)
			(xy 190.71715 54.97788) (xy 190.71715 54.98607) (xy 190.71715 54.99427) (xy 190.71715 55.00246) (xy 190.71715 55.01065)
			(xy 190.71715 55.01885) (xy 190.71715 55.02705) (xy 190.71715 55.03524) (xy 190.71715 55.04344) (xy 190.71715 55.05163)
			(xy 190.71715 55.05982) (xy 190.71715 55.06802) (xy 190.71715 55.07621) (xy 190.71715 55.08441) (xy 190.71715 55.0926)
			(xy 190.71715 55.1008) (xy 190.71715 55.10899) (xy 190.71715 55.11718) (xy 190.71715 55.12538) (xy 190.71715 55.13357)
			(xy 190.71715 55.14177) (xy 190.71715 55.14996) (xy 190.71715 55.15816) (xy 190.71715 55.16635) (xy 190.71715 55.17455)
			(xy 190.71715 55.18274) (xy 190.71715 55.19093) (xy 190.71715 55.19913) (xy 190.72534 55.19913) (xy 190.72534 55.20732)
			(xy 190.73353 55.20732) (xy 190.73353 55.21552) (xy 190.74173 55.21552) (xy 190.74173 55.22371) (xy 191.14326 55.22371)
			(xy 191.14326 55.21552) (xy 191.15145 55.21552) (xy 191.15145 55.20732) (xy 191.15965 55.20732) (xy 191.15965 55.19913)
			(xy 191.15965 55.19093) (xy 191.15965 55.18274) (xy 191.16784 55.18274) (xy 191.16784 55.17455) (xy 191.16784 55.16635)
			(xy 191.16784 55.15816) (xy 191.16784 55.14996) (xy 191.16784 55.14177) (xy 191.16784 55.13357) (xy 191.16784 55.12538)
			(xy 191.16784 55.11718) (xy 191.16784 55.10899) (xy 191.16784 55.1008) (xy 191.16784 55.0926) (xy 191.16784 55.08441)
			(xy 191.16784 55.07621) (xy 191.16784 55.06802) (xy 191.16784 55.05982) (xy 191.16784 55.05163) (xy 191.16784 55.04344)
			(xy 191.16784 55.03524) (xy 191.16784 55.02705) (xy 191.16784 55.01885) (xy 191.16784 55.01065) (xy 191.16784 55.00246)
			(xy 191.16784 54.99427) (xy 191.16784 54.98607) (xy 191.16784 54.97788) (xy 191.16784 54.96968) (xy 191.16784 54.96149)
			(xy 191.16784 54.95329) (xy 191.16784 54.9451) (xy 191.16784 54.93691) (xy 191.16784 54.92871) (xy 191.16784 54.92052)
			(xy 191.16784 54.91232) (xy 191.16784 54.90413) (xy 191.16784 54.89593) (xy 191.16784 54.88774) (xy 191.16784 54.87955)
			(xy 191.16784 54.87135) (xy 191.16784 54.86316) (xy 191.16784 54.85496) (xy 191.16784 54.84677) (xy 191.16784 54.83857)
			(xy 191.16784 54.83038) (xy 191.16784 54.82218) (xy 191.16784 54.81399) (xy 191.16784 54.80579) (xy 191.16784 54.7976)
			(xy 191.16784 54.78941) (xy 191.16784 54.78121) (xy 191.16784 54.77302) (xy 191.16784 54.76482) (xy 191.16784 54.75663)
			(xy 191.16784 54.74843) (xy 191.16784 54.74024) (xy 191.16784 54.73204) (xy 191.16784 54.72385) (xy 191.16784 54.71565)
			(xy 191.16784 54.70746) (xy 191.16784 54.69926) (xy 191.16784 54.69107) (xy 191.16784 54.68288) (xy 191.16784 54.67468)
			(xy 191.16784 54.66649) (xy 191.16784 54.65829) (xy 191.16784 54.6501) (xy 191.16784 54.6419) (xy 191.16784 54.63371)
			(xy 191.16784 54.62551) (xy 191.16784 54.61732) (xy 191.16784 54.60913) (xy 191.16784 54.60093) (xy 191.16784 54.59274)
			(xy 191.16784 54.58454) (xy 191.16784 54.57635) (xy 191.16784 54.56815) (xy 191.16784 54.55996) (xy 191.16784 54.55176)
			(xy 191.16784 54.54357) (xy 191.16784 54.53538) (xy 191.16784 54.52718) (xy 191.16784 54.51899) (xy 191.16784 54.51079)
			(xy 191.16784 54.5026) (xy 191.16784 54.4944) (xy 191.16784 54.48621) (xy 191.16784 54.47801) (xy 191.16784 54.46982)
			(xy 191.16784 54.46162) (xy 191.16784 54.45343) (xy 191.16784 54.44524) (xy 191.16784 54.43704) (xy 191.16784 54.42885)
			(xy 191.16784 54.42065) (xy 191.16784 54.41246) (xy 191.16784 54.40426) (xy 191.16784 54.39607) (xy 191.16784 54.38787)
			(xy 191.16784 54.37968) (xy 191.16784 54.37149) (xy 191.16784 54.36329) (xy 191.16784 54.3551) (xy 191.16784 54.3469)
			(xy 191.16784 54.33871) (xy 191.16784 54.33051) (xy 191.16784 54.32232) (xy 191.16784 54.31413) (xy 191.16784 54.30593)
			(xy 191.16784 54.29774) (xy 191.16784 54.28954) (xy 191.16784 54.28134) (xy 191.16784 54.27315) (xy 191.16784 54.26496)
			(xy 191.16784 54.25676) (xy 191.16784 54.24857) (xy 191.16784 54.24037) (xy 191.16784 54.23218) (xy 191.16784 54.22398)
			(xy 191.16784 54.21579) (xy 191.16784 54.2076) (xy 191.16784 54.1994) (xy 191.16784 54.19121) (xy 191.16784 54.18301)
			(xy 191.16784 54.17482) (xy 191.16784 54.16662) (xy 191.16784 54.15843) (xy 191.16784 54.15023) (xy 191.16784 54.14204)
			(xy 191.16784 54.13385) (xy 191.16784 54.12565) (xy 191.16784 54.11746) (xy 191.16784 54.10926) (xy 191.16784 54.10107)
			(xy 191.16784 54.09287) (xy 191.16784 54.08468) (xy 191.16784 54.07649) (xy 191.16784 54.06829) (xy 191.16784 54.0601)
			(xy 191.16784 54.0519) (xy 191.16784 54.0437) (xy 191.16784 54.03551) (xy 191.16784 54.02732) (xy 191.16784 54.01912)
			(xy 191.16784 54.01093) (xy 191.16784 54.00273) (xy 191.16784 53.99454) (xy 191.16784 53.98634) (xy 191.16784 53.97815)
			(xy 191.16784 53.96996) (xy 191.16784 53.96176) (xy 191.16784 53.95357) (xy 191.16784 53.94537) (xy 191.16784 53.93718)
			(xy 191.16784 53.92898) (xy 191.16784 53.92079) (xy 191.16784 53.91259) (xy 191.16784 53.9044) (xy 191.16784 53.8962)
			(xy 191.17604 53.8962) (xy 191.17604 53.88801) (xy 191.18423 53.88801) (xy 191.18423 53.87982) (xy 191.57757 53.87982)
			(xy 191.57757 53.87162) (xy 191.60215 53.87162) (xy 191.60215 53.86343) (xy 191.61034 53.86343) (xy 191.61034 53.85523)
			(xy 191.61854 53.85523) (xy 191.61854 53.84704) (xy 191.61854 53.83884) (xy 191.61854 53.83065) (xy 191.62673 53.83065)
			(xy 191.62673 53.82246) (xy 191.62673 53.81426) (xy 191.62673 53.80606) (xy 191.62673 53.79787) (xy 191.62673 53.78968)
			(xy 191.62673 53.78148) (xy 191.62673 53.77329) (xy 191.62673 53.76509) (xy 191.62673 53.7569) (xy 191.62673 53.7487)
			(xy 191.62673 53.74051) (xy 191.62673 53.73231) (xy 191.62673 53.72412) (xy 191.62673 53.71593) (xy 191.62673 53.70773)
			(xy 191.62673 53.69954) (xy 191.62673 53.69134) (xy 191.62673 53.68315) (xy 191.62673 53.67495) (xy 191.62673 53.66676)
			(xy 191.62673 53.65857) (xy 191.62673 53.65037) (xy 191.62673 53.64218) (xy 191.62673 53.63398) (xy 191.62673 53.62579)
			(xy 191.62673 53.61759) (xy 191.62673 53.6094) (xy 191.62673 53.6012) (xy 191.62673 53.59301) (xy 191.62673 53.58482)
			(xy 191.62673 53.57662) (xy 191.62673 53.56843) (xy 191.62673 53.56023) (xy 191.62673 53.55204) (xy 191.62673 53.54384)
			(xy 191.62673 53.53565) (xy 191.62673 53.52745) (xy 191.62673 53.51926) (xy 191.62673 53.51106) (xy 191.62673 53.50287)
			(xy 191.62673 53.49467) (xy 191.62673 53.48648) (xy 191.61854 53.48648) (xy 191.61854 53.47829) (xy 191.72507 53.47829)
			(xy 191.72507 53.48648) (xy 191.72507 53.49467) (xy 191.72507 53.50287) (xy 191.72507 53.51106) (xy 191.72507 53.51926)
			(xy 191.72507 53.52745) (xy 191.72507 53.53565) (xy 191.72507 53.54384) (xy 191.72507 53.55204) (xy 191.72507 53.56023)
			(xy 191.72507 53.56843) (xy 191.72507 53.57662) (xy 191.72507 53.58482) (xy 191.72507 53.59301) (xy 191.72507 53.6012)
			(xy 191.72507 53.6094) (xy 191.72507 53.61759) (xy 191.72507 53.62579) (xy 191.72507 53.63398) (xy 191.72507 53.64218)
			(xy 191.72507 53.65037) (xy 191.72507 53.65857) (xy 191.72507 53.66676) (xy 191.72507 53.67495) (xy 191.72507 53.68315)
			(xy 191.72507 53.69134) (xy 191.72507 53.69954) (xy 191.72507 53.70773) (xy 191.72507 53.71593) (xy 191.72507 53.72412)
			(xy 191.72507 53.73231) (xy 191.72507 53.74051) (xy 191.72507 53.7487) (xy 191.72507 53.7569) (xy 191.72507 53.76509)
			(xy 191.72507 53.77329) (xy 191.72507 53.78148) (xy 191.72507 53.78968) (xy 191.72507 53.79787) (xy 191.72507 53.80606)
			(xy 191.72507 53.81426) (xy 191.72507 53.82246) (xy 191.72507 53.83065) (xy 191.72507 53.83884) (xy 191.72507 53.84704)
			(xy 191.72507 53.85523) (xy 191.72507 53.86343) (xy 191.72507 53.87162) (xy 191.72507 53.87982) (xy 191.72507 53.88801)
			(xy 191.72507 53.8962) (xy 191.72507 53.9044) (xy 191.72507 53.91259) (xy 191.72507 53.92079) (xy 191.72507 53.92898)
			(xy 191.72507 53.93718) (xy 191.72507 53.94537) (xy 191.72507 53.95357) (xy 191.72507 53.96176) (xy 191.72507 53.96996)
			(xy 191.72507 53.97815) (xy 191.72507 53.98634) (xy 191.72507 53.99454) (xy 191.72507 54.00273) (xy 191.72507 54.01093)
			(xy 191.72507 54.01912) (xy 191.72507 54.02732) (xy 191.72507 54.03551) (xy 191.72507 54.0437) (xy 191.72507 54.0519)
			(xy 191.72507 54.0601) (xy 191.72507 54.06829) (xy 191.72507 54.07649) (xy 191.72507 54.08468) (xy 191.72507 54.09287)
			(xy 191.72507 54.10107) (xy 191.72507 54.10926) (xy 191.72507 54.11746) (xy 191.72507 54.12565) (xy 191.72507 54.13385)
			(xy 191.72507 54.14204) (xy 191.72507 54.15023) (xy 191.72507 54.15843) (xy 191.72507 54.16662) (xy 191.72507 54.17482)
			(xy 191.72507 54.18301) (xy 191.72507 54.19121) (xy 191.72507 54.1994) (xy 191.72507 54.2076) (xy 191.72507 54.21579)
			(xy 191.72507 54.22398) (xy 191.72507 54.23218) (xy 191.72507 54.24037) (xy 191.72507 54.24857) (xy 191.72507 54.25676)
			(xy 191.72507 54.26496) (xy 191.72507 54.27315) (xy 191.72507 54.28134) (xy 191.72507 54.28954) (xy 191.72507 54.29774)
			(xy 191.72507 54.30593) (xy 191.72507 54.31413) (xy 191.72507 54.32232) (xy 191.72507 54.33051) (xy 191.72507 54.33871)
			(xy 191.72507 54.3469) (xy 191.72507 54.3551) (xy 191.72507 54.36329) (xy 191.72507 54.37149) (xy 191.72507 54.37968)
			(xy 191.72507 54.38787) (xy 191.72507 54.39607) (xy 191.72507 54.40426) (xy 191.72507 54.41246) (xy 191.72507 54.42065)
			(xy 191.72507 54.42885) (xy 191.72507 54.43704) (xy 191.72507 54.44524) (xy 191.72507 54.45343) (xy 191.72507 54.46162)
			(xy 191.72507 54.46982) (xy 191.72507 54.47801) (xy 191.72507 54.48621) (xy 191.72507 54.4944) (xy 191.72507 54.5026)
			(xy 191.72507 54.51079) (xy 191.72507 54.51899) (xy 191.72507 54.52718) (xy 191.72507 54.53538) (xy 191.72507 54.54357)
			(xy 191.72507 54.55176) (xy 191.72507 54.55996) (xy 191.72507 54.56815) (xy 191.72507 54.57635) (xy 191.72507 54.58454)
			(xy 191.72507 54.59274) (xy 191.72507 54.60093) (xy 191.72507 54.60913) (xy 191.72507 54.61732) (xy 191.72507 54.62551)
			(xy 191.72507 54.63371) (xy 191.72507 54.6419) (xy 191.72507 54.6501) (xy 191.72507 54.65829) (xy 191.72507 54.66649)
			(xy 191.72507 54.67468) (xy 191.72507 54.68288) (xy 191.72507 54.69107) (xy 191.72507 54.69926) (xy 191.72507 54.70746)
			(xy 191.72507 54.71565) (xy 191.72507 54.72385) (xy 191.72507 54.73204) (xy 191.72507 54.74024) (xy 191.72507 54.74843)
			(xy 191.72507 54.75663) (xy 191.72507 54.76482) (xy 191.72507 54.77302) (xy 191.72507 54.78121) (xy 191.72507 54.78941)
			(xy 191.72507 54.7976) (xy 191.72507 54.80579) (xy 191.72507 54.81399) (xy 191.72507 54.82218) (xy 191.72507 54.83038)
			(xy 191.72507 54.83857) (xy 191.72507 54.84677) (xy 191.72507 54.85496) (xy 191.72507 54.86316) (xy 191.72507 54.87135)
			(xy 191.72507 54.87955) (xy 191.72507 54.88774) (xy 191.72507 54.89593) (xy 191.72507 54.90413) (xy 191.72507 54.91232)
			(xy 191.72507 54.92052) (xy 191.72507 54.92871) (xy 191.72507 54.93691) (xy 191.72507 54.9451) (xy 191.72507 54.95329)
			(xy 191.72507 54.96149) (xy 191.72507 54.96968) (xy 191.72507 54.97788) (xy 191.72507 54.98607) (xy 191.72507 54.99427)
			(xy 191.72507 55.00246) (xy 191.72507 55.01065) (xy 191.72507 55.01885) (xy 191.72507 55.02705) (xy 191.72507 55.03524)
			(xy 191.72507 55.04344) (xy 191.72507 55.05163) (xy 191.72507 55.05982) (xy 191.72507 55.06802) (xy 191.72507 55.07621)
			(xy 191.72507 55.08441) (xy 191.72507 55.0926) (xy 191.72507 55.1008) (xy 191.72507 55.10899) (xy 191.72507 55.11718)
			(xy 191.72507 55.12538) (xy 191.72507 55.13357) (xy 191.72507 55.14177) (xy 191.72507 55.14996) (xy 191.72507 55.15816)
			(xy 191.72507 55.16635) (xy 191.72507 55.17455) (xy 191.72507 55.18274) (xy 191.72507 55.19093) (xy 191.73326 55.19093)
			(xy 191.73326 55.19913) (xy 191.73326 55.20732) (xy 191.74146 55.20732) (xy 191.74146 55.21552) (xy 191.74965 55.21552)
			(xy 191.74965 55.22371) (xy 192.15938 55.22371) (xy 192.15938 55.21552) (xy 192.16757 55.21552) (xy 192.16757 55.20732)
			(xy 192.17576 55.20732) (xy 192.17576 55.19913) (xy 192.17576 55.19093) (xy 192.17576 55.18274) (xy 192.17576 55.17455)
			(xy 192.17576 55.16635) (xy 192.17576 55.15816) (xy 192.17576 55.14996) (xy 192.17576 55.14177) (xy 192.17576 55.13357)
			(xy 192.17576 55.12538) (xy 192.17576 55.11718) (xy 192.17576 55.10899) (xy 192.17576 55.1008) (xy 192.17576 55.0926)
			(xy 192.17576 55.08441) (xy 192.17576 55.07621) (xy 192.17576 55.06802) (xy 192.17576 55.05982) (xy 192.17576 55.05163)
			(xy 192.17576 55.04344) (xy 192.17576 55.03524) (xy 192.17576 55.02705) (xy 192.17576 55.01885) (xy 192.17576 55.01065)
			(xy 192.17576 55.00246) (xy 192.17576 54.99427) (xy 192.17576 54.98607) (xy 192.17576 54.97788) (xy 192.17576 54.96968)
			(xy 192.17576 54.96149) (xy 192.17576 54.95329) (xy 192.17576 54.9451) (xy 192.17576 54.93691) (xy 192.17576 54.92871)
			(xy 192.17576 54.92052) (xy 192.17576 54.91232) (xy 192.17576 54.90413) (xy 192.17576 54.89593) (xy 192.17576 54.88774)
			(xy 192.17576 54.87955) (xy 192.17576 54.87135) (xy 192.17576 54.86316) (xy 192.17576 54.85496) (xy 192.17576 54.84677)
			(xy 192.17576 54.83857) (xy 192.17576 54.83038) (xy 192.17576 54.82218) (xy 192.17576 54.81399) (xy 192.17576 54.80579)
			(xy 192.17576 54.7976) (xy 192.17576 54.78941) (xy 192.17576 54.78121) (xy 192.17576 54.77302) (xy 192.17576 54.76482)
			(xy 192.17576 54.75663) (xy 192.17576 54.74843) (xy 192.17576 54.74024) (xy 192.17576 54.73204) (xy 192.17576 54.72385)
			(xy 192.17576 54.71565) (xy 192.17576 54.70746) (xy 192.17576 54.69926) (xy 192.17576 54.69107) (xy 192.17576 54.68288)
			(xy 192.17576 54.67468) (xy 192.17576 54.66649) (xy 192.17576 54.65829) (xy 192.17576 54.6501) (xy 192.17576 54.6419)
			(xy 192.17576 54.63371) (xy 192.17576 54.62551) (xy 192.17576 54.61732) (xy 192.17576 54.60913) (xy 192.17576 54.60093)
			(xy 192.17576 54.59274) (xy 192.17576 54.58454) (xy 192.17576 54.57635) (xy 192.17576 54.56815) (xy 192.17576 54.55996)
			(xy 192.17576 54.55176) (xy 192.17576 54.54357) (xy 192.17576 54.53538) (xy 192.17576 54.52718) (xy 192.17576 54.51899)
			(xy 192.17576 54.51079) (xy 192.17576 54.5026) (xy 192.17576 54.4944) (xy 192.17576 54.48621) (xy 192.17576 54.47801)
			(xy 192.17576 54.46982) (xy 192.17576 54.46162) (xy 192.17576 54.45343) (xy 192.17576 54.44524) (xy 192.17576 54.43704)
			(xy 192.17576 54.42885) (xy 192.17576 54.42065) (xy 192.17576 54.41246) (xy 192.17576 54.40426) (xy 192.17576 54.39607)
			(xy 192.17576 54.38787) (xy 192.17576 54.37968) (xy 192.17576 54.37149) (xy 192.17576 54.36329) (xy 192.17576 54.3551)
			(xy 192.17576 54.3469) (xy 192.17576 54.33871) (xy 192.17576 54.33051) (xy 192.17576 54.32232) (xy 192.17576 54.31413)
			(xy 192.17576 54.30593) (xy 192.17576 54.29774) (xy 192.17576 54.28954) (xy 192.17576 54.28134) (xy 192.17576 54.27315)
			(xy 192.17576 54.26496) (xy 192.17576 54.25676) (xy 192.17576 54.24857) (xy 192.17576 54.24037) (xy 192.17576 54.23218)
			(xy 192.17576 54.22398) (xy 192.17576 54.21579) (xy 192.17576 54.2076) (xy 192.17576 54.1994) (xy 192.17576 54.19121)
			(xy 192.17576 54.18301) (xy 192.17576 54.17482) (xy 192.17576 54.16662) (xy 192.17576 54.15843) (xy 192.17576 54.15023)
			(xy 192.17576 54.14204) (xy 192.17576 54.13385) (xy 192.17576 54.12565) (xy 192.17576 54.11746) (xy 192.17576 54.10926)
			(xy 192.17576 54.10107) (xy 192.17576 54.09287) (xy 192.17576 54.08468) (xy 192.17576 54.07649) (xy 192.17576 54.06829)
			(xy 192.17576 54.0601) (xy 192.17576 54.0519) (xy 192.17576 54.0437) (xy 192.17576 54.03551) (xy 192.17576 54.02732)
			(xy 192.17576 54.01912) (xy 192.17576 54.01093) (xy 192.17576 54.00273) (xy 192.17576 53.99454) (xy 192.17576 53.98634)
			(xy 192.17576 53.97815) (xy 192.17576 53.96996) (xy 192.17576 53.96176) (xy 192.17576 53.95357) (xy 192.17576 53.94537)
			(xy 192.17576 53.93718) (xy 192.17576 53.92898) (xy 192.17576 53.92079) (xy 192.17576 53.91259) (xy 192.17576 53.9044)
			(xy 192.17576 53.8962) (xy 192.17576 53.88801) (xy 192.17576 53.87982) (xy 192.17576 53.87162) (xy 192.17576 53.86343)
			(xy 192.17576 53.85523) (xy 192.17576 53.84704) (xy 192.17576 53.83884) (xy 192.17576 53.83065) (xy 192.17576 53.82246)
			(xy 192.17576 53.81426) (xy 192.17576 53.80606) (xy 192.17576 53.79787) (xy 192.17576 53.78968) (xy 192.17576 53.78148)
			(xy 192.17576 53.77329) (xy 192.17576 53.76509) (xy 192.17576 53.7569) (xy 192.17576 53.7487) (xy 192.17576 53.74051)
			(xy 192.17576 53.73231) (xy 192.17576 53.72412) (xy 192.17576 53.71593) (xy 192.17576 53.70773) (xy 192.17576 53.69954)
			(xy 192.17576 53.69134) (xy 192.17576 53.68315) (xy 192.17576 53.67495) (xy 192.17576 53.66676) (xy 192.17576 53.65857)
			(xy 192.17576 53.65037) (xy 192.17576 53.64218) (xy 192.17576 53.63398) (xy 192.17576 53.62579) (xy 192.17576 53.61759)
			(xy 192.17576 53.6094) (xy 192.17576 53.6012) (xy 192.17576 53.59301) (xy 192.17576 53.58482) (xy 192.17576 53.57662)
			(xy 192.17576 53.56843) (xy 192.17576 53.56023) (xy 192.17576 53.55204) (xy 192.17576 53.54384) (xy 192.17576 53.53565)
			(xy 192.17576 53.52745) (xy 192.17576 53.51926) (xy 192.17576 53.51106) (xy 192.17576 53.50287) (xy 192.17576 53.49467)
			(xy 192.17576 53.48648) (xy 192.17576 53.47829) (xy 192.17576 53.47009) (xy 192.38063 53.47009) (xy 192.38063 53.47829)
			(xy 192.38063 53.48648) (xy 192.38063 53.49467) (xy 192.38063 53.50287) (xy 192.38063 53.51106) (xy 192.38063 53.51926)
			(xy 192.38063 53.52745) (xy 192.38063 53.53565) (xy 192.38063 53.54384) (xy 192.38063 53.55204) (xy 192.38063 53.56023)
			(xy 192.38063 53.56843) (xy 192.38063 53.57662) (xy 192.38063 53.58482) (xy 192.38063 53.59301) (xy 192.38063 53.6012)
			(xy 192.38063 53.6094) (xy 192.38063 53.61759) (xy 192.38063 53.62579) (xy 192.38063 53.63398) (xy 192.38063 53.64218)
			(xy 192.38063 53.65037) (xy 192.38063 53.65857) (xy 192.38063 53.66676) (xy 192.38063 53.67495) (xy 192.38063 53.68315)
			(xy 192.38063 53.69134) (xy 192.38063 53.69954) (xy 192.38063 53.70773) (xy 192.38063 53.71593) (xy 192.38063 53.72412)
			(xy 192.38063 53.73231) (xy 192.38063 53.74051) (xy 192.38063 53.7487) (xy 192.38063 53.7569) (xy 192.38063 53.76509)
			(xy 192.38063 53.77329) (xy 192.38063 53.78148) (xy 192.38063 53.78968) (xy 192.38063 53.79787) (xy 192.38063 53.80606)
			(xy 192.38063 53.81426) (xy 192.38063 53.82246) (xy 192.38063 53.83065) (xy 192.38063 53.83884) (xy 192.38063 53.84704)
			(xy 192.38063 53.85523) (xy 192.38063 53.86343) (xy 192.38063 53.87162) (xy 192.38063 53.87982) (xy 192.38063 53.88801)
			(xy 192.38063 53.8962) (xy 192.38063 53.9044) (xy 192.38063 53.91259) (xy 192.38063 53.92079) (xy 192.38063 53.92898)
			(xy 192.38063 53.93718) (xy 192.38063 53.94537) (xy 192.38063 53.95357) (xy 192.38063 53.96176) (xy 192.38063 53.96996)
			(xy 192.38063 53.97815) (xy 192.38063 53.98634) (xy 192.38063 53.99454) (xy 192.38063 54.00273) (xy 192.38063 54.01093)
			(xy 192.38063 54.01912) (xy 192.38063 54.02732) (xy 192.38063 54.03551) (xy 192.38063 54.0437) (xy 192.38063 54.0519)
			(xy 192.38063 54.0601) (xy 192.38063 54.06829) (xy 192.38063 54.07649) (xy 192.38063 54.08468) (xy 192.38063 54.09287)
			(xy 192.38063 54.10107) (xy 192.38063 54.10926) (xy 192.38063 54.11746) (xy 192.38063 54.12565) (xy 192.38063 54.13385)
			(xy 192.38063 54.14204) (xy 192.38063 54.15023) (xy 192.38063 54.15843) (xy 192.38063 54.16662) (xy 192.38063 54.17482)
			(xy 192.38063 54.18301) (xy 192.38063 54.19121) (xy 192.38063 54.1994) (xy 192.38063 54.2076) (xy 192.38063 54.21579)
			(xy 192.38063 54.22398) (xy 192.38063 54.23218) (xy 192.38063 54.24037) (xy 192.38063 54.24857) (xy 192.38063 54.25676)
			(xy 192.38063 54.26496) (xy 192.38063 54.27315) (xy 192.38063 54.28134) (xy 192.38063 54.28954) (xy 192.38063 54.29774)
			(xy 192.38063 54.30593) (xy 192.38063 54.31413) (xy 192.38063 54.32232) (xy 192.38063 54.33051) (xy 192.38063 54.33871)
			(xy 192.38063 54.3469) (xy 192.38063 54.3551) (xy 192.38063 54.36329) (xy 192.38063 54.37149) (xy 192.38063 54.37968)
			(xy 192.38063 54.38787) (xy 192.38063 54.39607) (xy 192.38063 54.40426) (xy 192.38063 54.41246) (xy 192.38063 54.42065)
			(xy 192.38063 54.42885) (xy 192.38063 54.43704) (xy 192.38063 54.44524) (xy 192.38063 54.45343) (xy 192.38063 54.46162)
			(xy 192.38063 54.46982) (xy 192.38063 54.47801) (xy 192.38063 54.48621) (xy 192.38063 54.4944) (xy 192.38063 54.5026)
			(xy 192.38063 54.51079) (xy 192.38063 54.51899) (xy 192.38063 54.52718) (xy 192.38063 54.53538) (xy 192.38063 54.54357)
			(xy 192.38063 54.55176) (xy 192.38063 54.55996) (xy 192.38063 54.56815) (xy 192.38063 54.57635) (xy 192.38063 54.58454)
			(xy 192.38063 54.59274) (xy 192.38063 54.60093) (xy 192.38063 54.60913) (xy 192.38063 54.61732) (xy 192.38063 54.62551)
			(xy 192.38063 54.63371) (xy 192.38063 54.6419) (xy 192.38063 54.6501) (xy 192.38063 54.65829) (xy 192.38063 54.66649)
			(xy 192.38063 54.67468) (xy 192.38063 54.68288) (xy 192.38063 54.69107) (xy 192.38063 54.69926) (xy 192.38063 54.70746)
			(xy 192.38063 54.71565) (xy 192.38063 54.72385) (xy 192.38063 54.73204) (xy 192.38063 54.74024) (xy 192.38063 54.74843)
			(xy 192.38063 54.75663) (xy 192.38063 54.76482) (xy 192.38063 54.77302) (xy 192.38063 54.78121) (xy 192.38063 54.78941)
			(xy 192.38063 54.7976) (xy 192.38063 54.80579) (xy 192.38063 54.81399) (xy 192.38063 54.82218) (xy 192.38063 54.83038)
			(xy 192.38063 54.83857) (xy 192.38063 54.84677) (xy 192.38063 54.85496) (xy 192.38063 54.86316) (xy 192.38063 54.87135)
			(xy 192.38063 54.87955) (xy 192.38063 54.88774) (xy 192.38063 54.89593) (xy 192.38063 54.90413) (xy 192.38063 54.91232)
			(xy 192.38063 54.92052) (xy 192.38063 54.92871) (xy 192.38063 54.93691) (xy 192.38063 54.9451) (xy 192.38063 54.95329)
			(xy 192.38063 54.96149) (xy 192.38063 54.96968) (xy 192.38063 54.97788) (xy 192.38063 54.98607) (xy 192.38063 54.99427)
			(xy 192.38063 55.00246) (xy 192.38063 55.01065) (xy 192.38063 55.01885) (xy 192.38063 55.02705) (xy 192.38063 55.03524)
			(xy 192.38063 55.04344) (xy 192.38063 55.05163) (xy 192.38063 55.05982) (xy 192.38063 55.06802) (xy 192.38063 55.07621)
			(xy 192.38063 55.08441) (xy 192.38063 55.0926) (xy 192.38063 55.1008) (xy 192.38063 55.10899) (xy 192.38063 55.11718)
			(xy 192.38063 55.12538) (xy 192.38063 55.13357) (xy 192.38063 55.14177) (xy 192.38063 55.14996) (xy 192.38063 55.15816)
			(xy 192.38063 55.16635) (xy 192.38063 55.17455) (xy 192.38063 55.18274) (xy 192.38063 55.19093) (xy 192.38063 55.19913)
			(xy 192.38882 55.19913) (xy 192.38882 55.20732) (xy 192.38882 55.21552) (xy 192.40521 55.21552) (xy 192.40521 55.22371)
			(xy 192.80674 55.22371) (xy 192.80674 55.21552) (xy 192.81494 55.21552) (xy 192.81494 55.20732) (xy 192.82313 55.20732)
			(xy 192.82313 55.19913) (xy 192.82313 55.19093) (xy 192.83132 55.19093) (xy 192.83132 55.18274) (xy 192.83132 55.17455)
			(xy 192.83132 55.16635) (xy 192.83132 55.15816) (xy 192.83132 55.14996) (xy 192.83132 55.14177) (xy 192.83132 55.13357)
			(xy 192.83132 55.12538) (xy 192.83132 55.11718) (xy 192.83132 55.10899) (xy 192.83132 55.1008) (xy 192.83132 55.0926)
			(xy 192.83132 55.08441) (xy 192.83132 55.07621) (xy 192.83132 55.06802) (xy 192.83132 55.05982) (xy 192.83132 55.05163)
			(xy 192.83132 55.04344) (xy 192.83132 55.03524) (xy 192.83132 55.02705) (xy 192.83132 55.01885) (xy 192.83132 55.01065)
			(xy 192.83132 55.00246) (xy 192.83132 54.99427) (xy 192.83132 54.98607) (xy 192.83132 54.97788) (xy 192.83132 54.96968)
			(xy 192.83132 54.96149) (xy 192.83132 54.95329) (xy 192.83132 54.9451) (xy 192.83132 54.93691) (xy 192.83132 54.92871)
			(xy 192.83132 54.92052) (xy 192.83132 54.91232) (xy 192.83132 54.90413) (xy 192.83132 54.89593) (xy 192.83132 54.88774)
			(xy 192.83132 54.87955) (xy 192.83132 54.87135) (xy 192.83132 54.86316) (xy 192.83132 54.85496) (xy 192.83132 54.84677)
			(xy 192.83132 54.83857) (xy 192.83132 54.83038) (xy 192.83132 54.82218) (xy 192.83132 54.81399) (xy 192.83132 54.80579)
			(xy 192.83132 54.7976) (xy 192.83132 54.78941) (xy 192.83132 54.78121) (xy 192.83132 54.77302) (xy 192.83132 54.76482)
			(xy 192.83132 54.75663) (xy 192.83132 54.74843) (xy 192.83132 54.74024) (xy 192.83132 54.73204) (xy 192.83132 54.72385)
			(xy 192.83132 54.71565) (xy 192.83132 54.70746) (xy 192.83132 54.69926) (xy 192.83132 54.69107) (xy 192.83132 54.68288)
			(xy 192.83132 54.67468) (xy 192.83132 54.66649) (xy 192.83132 54.65829) (xy 192.83132 54.6501) (xy 192.83132 54.6419)
			(xy 192.83132 54.63371) (xy 192.83132 54.62551) (xy 192.83132 54.61732) (xy 192.83132 54.60913) (xy 192.83132 54.60093)
			(xy 192.83132 54.59274) (xy 192.83132 54.58454) (xy 192.83132 54.57635) (xy 192.83132 54.56815) (xy 192.83132 54.55996)
			(xy 192.83132 54.55176) (xy 192.83132 54.54357) (xy 192.83132 54.53538) (xy 192.83132 54.52718) (xy 192.83132 54.51899)
			(xy 192.83132 54.51079) (xy 192.83132 54.5026) (xy 192.83132 54.4944) (xy 192.83132 54.48621) (xy 192.83132 54.47801)
			(xy 192.83132 54.46982) (xy 192.83132 54.46162) (xy 192.83132 54.45343) (xy 192.83132 54.44524) (xy 192.83132 54.43704)
			(xy 192.83132 54.42885) (xy 192.83132 54.42065) (xy 192.83132 54.41246) (xy 192.83132 54.40426) (xy 192.83132 54.39607)
			(xy 192.83132 54.38787) (xy 192.83132 54.37968) (xy 192.83132 54.37149) (xy 192.83132 54.36329) (xy 192.83132 54.3551)
			(xy 192.83132 54.3469) (xy 192.83132 54.33871) (xy 192.83132 54.33051) (xy 192.83132 54.32232) (xy 192.83132 54.31413)
			(xy 192.83132 54.30593) (xy 192.83132 54.29774) (xy 192.83132 54.28954) (xy 192.83132 54.28134) (xy 192.83132 54.27315)
			(xy 192.83132 54.26496) (xy 192.83132 54.25676) (xy 192.83132 54.24857) (xy 192.83132 54.24037) (xy 192.83132 54.23218)
			(xy 192.83132 54.22398) (xy 192.83132 54.21579) (xy 192.83132 54.2076) (xy 192.83132 54.1994) (xy 192.83132 54.19121)
			(xy 192.83132 54.18301) (xy 192.83132 54.17482) (xy 192.83132 54.16662) (xy 192.83132 54.15843) (xy 192.83132 54.15023)
			(xy 192.83132 54.14204) (xy 192.83132 54.13385) (xy 192.83132 54.12565) (xy 192.83132 54.11746) (xy 192.83132 54.10926)
			(xy 192.83132 54.10107) (xy 192.83132 54.09287) (xy 192.83132 54.08468) (xy 192.83132 54.07649) (xy 192.83132 54.06829)
			(xy 192.83132 54.0601) (xy 192.83132 54.0519) (xy 192.83132 54.0437) (xy 192.83132 54.03551) (xy 192.83132 54.02732)
			(xy 192.83132 54.01912) (xy 192.83132 54.01093) (xy 192.83132 54.00273) (xy 192.83132 53.99454) (xy 192.83132 53.98634)
			(xy 192.83132 53.97815) (xy 192.83132 53.96996) (xy 192.83132 53.96176) (xy 192.83132 53.95357) (xy 192.83132 53.94537)
			(xy 192.83132 53.93718) (xy 192.83132 53.92898) (xy 192.83132 53.92079) (xy 192.83132 53.91259) (xy 192.83132 53.9044)
			(xy 192.83132 53.8962) (xy 192.83132 53.88801) (xy 192.83132 53.87982) (xy 193.10994 53.87982) (xy 193.10994 53.88801)
			(xy 193.10994 53.8962) (xy 193.10994 53.9044) (xy 193.10994 53.91259) (xy 193.10994 53.92079) (xy 193.10994 53.92898)
			(xy 193.10994 53.93718) (xy 193.10994 53.94537) (xy 193.10994 53.95357) (xy 193.10994 53.96176) (xy 193.10994 53.96996)
			(xy 193.10994 53.97815) (xy 193.10994 53.98634) (xy 193.10994 53.99454) (xy 193.10994 54.00273) (xy 193.10994 54.01093)
			(xy 193.10994 54.01912) (xy 193.10994 54.02732) (xy 193.10994 54.03551) (xy 193.10994 54.0437) (xy 193.10994 54.0519)
			(xy 193.10994 54.0601) (xy 193.10994 54.06829) (xy 193.10994 54.07649) (xy 193.10994 54.08468) (xy 193.10994 54.09287)
			(xy 193.10994 54.10107) (xy 193.10994 54.10926) (xy 193.10994 54.11746) (xy 193.10994 54.12565) (xy 193.10994 54.13385)
			(xy 193.10994 54.14204) (xy 193.10994 54.15023) (xy 193.10994 54.15843) (xy 193.10994 54.16662) (xy 193.10994 54.17482)
			(xy 193.10994 54.18301) (xy 193.10994 54.19121) (xy 193.10994 54.1994) (xy 193.10994 54.2076) (xy 193.10994 54.21579)
			(xy 193.10994 54.22398) (xy 193.10994 54.23218) (xy 193.10994 54.24037) (xy 193.10994 54.24857) (xy 193.10994 54.25676)
			(xy 193.10994 54.26496) (xy 193.10994 54.27315) (xy 193.10994 54.28134) (xy 193.10994 54.28954) (xy 193.10994 54.29774)
			(xy 193.10994 54.30593) (xy 193.10994 54.31413) (xy 193.10994 54.32232) (xy 193.10994 54.33051) (xy 193.10994 54.33871)
			(xy 193.10994 54.3469) (xy 193.10994 54.3551) (xy 193.10994 54.36329) (xy 193.10994 54.37149) (xy 193.10994 54.37968)
			(xy 193.10994 54.38787) (xy 193.10994 54.39607) (xy 193.10994 54.40426) (xy 193.10994 54.41246) (xy 193.10994 54.42065)
			(xy 193.10994 54.42885) (xy 193.10994 54.43704) (xy 193.10994 54.44524) (xy 193.10994 54.45343) (xy 193.10994 54.46162)
			(xy 193.10994 54.46982) (xy 193.10994 54.47801) (xy 193.10994 54.48621) (xy 193.10994 54.4944) (xy 193.10994 54.5026)
			(xy 193.10994 54.51079) (xy 193.10994 54.51899) (xy 193.10994 54.52718) (xy 193.10994 54.53538) (xy 193.10994 54.54357)
			(xy 193.10994 54.55176) (xy 193.10994 54.55996) (xy 193.10994 54.56815) (xy 193.10994 54.57635) (xy 193.10994 54.58454)
			(xy 193.10994 54.59274) (xy 193.10994 54.60093) (xy 193.10994 54.60913) (xy 193.10994 54.61732) (xy 193.10994 54.62551)
			(xy 193.10994 54.63371) (xy 193.10994 54.6419) (xy 193.10994 54.6501) (xy 193.10994 54.65829) (xy 193.10994 54.66649)
			(xy 193.10994 54.67468) (xy 193.10994 54.68288) (xy 193.10994 54.69107) (xy 193.10994 54.69926) (xy 193.10994 54.70746)
			(xy 193.10994 54.71565) (xy 193.10994 54.72385) (xy 193.10994 54.73204) (xy 193.10994 54.74024) (xy 193.10994 54.74843)
			(xy 193.10994 54.75663) (xy 193.10994 54.76482) (xy 193.10994 54.77302) (xy 193.10994 54.78121) (xy 193.10994 54.78941)
			(xy 193.10994 54.7976) (xy 193.10994 54.80579) (xy 193.10994 54.81399) (xy 193.10994 54.82218) (xy 193.10994 54.83038)
			(xy 193.10994 54.83857) (xy 193.10994 54.84677) (xy 193.10994 54.85496) (xy 193.10994 54.86316) (xy 193.10994 54.87135)
			(xy 193.10994 54.87955) (xy 193.10994 54.88774) (xy 193.10994 54.89593) (xy 193.10994 54.90413) (xy 193.10994 54.91232)
			(xy 193.10994 54.92052) (xy 193.10994 54.92871) (xy 193.10994 54.93691) (xy 193.10994 54.9451) (xy 193.10994 54.95329)
			(xy 193.10994 54.96149) (xy 193.10994 54.96968) (xy 193.10994 54.97788) (xy 193.10994 54.98607) (xy 193.10994 54.99427)
			(xy 193.10994 55.00246) (xy 193.10994 55.01065) (xy 193.10994 55.01885) (xy 193.10994 55.02705) (xy 193.10994 55.03524)
			(xy 193.10994 55.04344) (xy 193.10994 55.05163) (xy 193.10994 55.05982) (xy 193.10994 55.06802) (xy 193.10994 55.07621)
			(xy 193.10994 55.08441) (xy 193.10994 55.0926) (xy 193.10994 55.1008) (xy 193.10994 55.10899) (xy 193.10994 55.11718)
			(xy 193.10994 55.12538) (xy 193.10994 55.13357) (xy 193.10994 55.14177) (xy 193.10994 55.14996) (xy 193.10994 55.15816)
			(xy 193.10994 55.16635) (xy 193.10994 55.17455) (xy 193.10994 55.18274) (xy 193.10994 55.19093) (xy 193.11813 55.19093)
			(xy 193.11813 55.19913) (xy 193.11813 55.20732) (xy 193.12633 55.20732) (xy 193.12633 55.21552) (xy 193.14271 55.21552)
			(xy 193.14271 55.22371) (xy 193.50327 55.22371) (xy 193.50327 55.21552) (xy 193.51147 55.21552) (xy 193.51147 55.20732)
			(xy 193.51966 55.20732) (xy 193.51966 55.19913) (xy 193.52786 55.19913) (xy 193.52786 55.19093) (xy 193.52786 55.18274)
			(xy 193.52786 55.17455) (xy 193.52786 55.16635) (xy 193.52786 55.15816) (xy 193.52786 55.14996) (xy 193.52786 55.14177)
			(xy 193.52786 55.13357) (xy 193.52786 55.12538) (xy 193.52786 55.11718) (xy 193.52786 55.10899) (xy 193.52786 55.1008)
			(xy 193.52786 55.0926) (xy 193.52786 55.08441) (xy 193.52786 55.07621) (xy 193.52786 55.06802) (xy 193.52786 55.05982)
			(xy 193.52786 55.05163) (xy 193.52786 55.04344) (xy 193.52786 55.03524) (xy 193.52786 55.02705) (xy 193.52786 55.01885)
			(xy 193.52786 55.01065) (xy 193.52786 55.00246) (xy 193.52786 54.99427) (xy 193.52786 54.98607) (xy 193.52786 54.97788)
			(xy 193.52786 54.96968) (xy 193.52786 54.96149) (xy 193.52786 54.95329) (xy 193.52786 54.9451) (xy 193.52786 54.93691)
			(xy 193.52786 54.92871) (xy 193.52786 54.92052) (xy 193.52786 54.91232) (xy 193.52786 54.90413) (xy 193.52786 54.89593)
			(xy 193.52786 54.88774) (xy 193.52786 54.87955) (xy 193.52786 54.87135) (xy 193.52786 54.86316) (xy 193.52786 54.85496)
			(xy 193.52786 54.84677) (xy 193.52786 54.83857) (xy 193.52786 54.83038) (xy 193.52786 54.82218) (xy 193.52786 54.81399)
			(xy 193.52786 54.80579) (xy 193.52786 54.7976) (xy 193.52786 54.78941) (xy 193.52786 54.78121) (xy 193.52786 54.77302)
			(xy 193.52786 54.76482) (xy 193.52786 54.75663) (xy 193.52786 54.74843) (xy 193.52786 54.74024) (xy 193.52786 54.73204)
			(xy 193.52786 54.72385) (xy 193.52786 54.71565) (xy 193.52786 54.70746) (xy 193.52786 54.69926) (xy 193.52786 54.69107)
			(xy 193.52786 54.68288) (xy 193.52786 54.67468) (xy 193.52786 54.66649) (xy 193.52786 54.65829) (xy 193.52786 54.6501)
			(xy 193.52786 54.6419) (xy 193.52786 54.63371) (xy 193.52786 54.62551) (xy 193.52786 54.61732) (xy 193.52786 54.60913)
			(xy 193.52786 54.60093) (xy 193.52786 54.59274) (xy 193.52786 54.58454) (xy 193.52786 54.57635) (xy 193.52786 54.56815)
			(xy 193.52786 54.55996) (xy 193.52786 54.55176) (xy 193.52786 54.54357) (xy 193.52786 54.53538) (xy 193.52786 54.52718)
			(xy 193.52786 54.51899) (xy 193.52786 54.51079) (xy 193.52786 54.5026) (xy 193.52786 54.4944) (xy 193.52786 54.48621)
			(xy 193.52786 54.47801) (xy 193.52786 54.46982) (xy 193.52786 54.46162) (xy 193.52786 54.45343) (xy 193.52786 54.44524)
			(xy 193.52786 54.43704) (xy 193.52786 54.42885) (xy 193.52786 54.42065) (xy 193.52786 54.41246) (xy 193.52786 54.40426)
			(xy 193.52786 54.39607) (xy 193.52786 54.38787) (xy 193.52786 54.37968) (xy 193.52786 54.37149) (xy 193.52786 54.36329)
			(xy 193.52786 54.3551) (xy 193.52786 54.3469) (xy 193.52786 54.33871) (xy 193.52786 54.33051) (xy 193.52786 54.32232)
			(xy 193.52786 54.31413) (xy 193.52786 54.30593) (xy 193.52786 54.29774) (xy 193.52786 54.28954) (xy 193.52786 54.28134)
			(xy 193.52786 54.27315) (xy 193.52786 54.26496) (xy 193.52786 54.25676) (xy 193.52786 54.24857) (xy 193.52786 54.24037)
			(xy 193.52786 54.23218) (xy 193.52786 54.22398) (xy 193.52786 54.21579) (xy 193.52786 54.2076) (xy 193.52786 54.1994)
			(xy 193.52786 54.19121) (xy 193.52786 54.18301) (xy 193.52786 54.17482) (xy 193.52786 54.16662) (xy 193.52786 54.15843)
			(xy 193.52786 54.15023) (xy 193.52786 54.14204) (xy 193.52786 54.13385) (xy 193.52786 54.12565) (xy 193.52786 54.11746)
			(xy 193.52786 54.10926) (xy 193.52786 54.10107) (xy 193.52786 54.09287) (xy 193.52786 54.08468) (xy 193.52786 54.07649)
			(xy 193.52786 54.06829) (xy 193.52786 54.0601) (xy 193.52786 54.0519) (xy 193.52786 54.0437) (xy 193.52786 54.03551)
			(xy 193.52786 54.02732) (xy 193.52786 54.01912) (xy 193.52786 54.01093) (xy 193.52786 54.00273) (xy 193.52786 53.99454)
			(xy 193.52786 53.98634) (xy 193.52786 53.97815) (xy 193.52786 53.96996) (xy 193.52786 53.96176) (xy 193.52786 53.95357)
			(xy 193.52786 53.94537) (xy 193.52786 53.93718) (xy 193.52786 53.92898) (xy 193.52786 53.92079) (xy 193.52786 53.91259)
			(xy 193.52786 53.9044) (xy 193.52786 53.8962) (xy 193.52786 53.88801) (xy 193.52786 53.87982) (xy 193.64258 53.87982)
			(xy 193.64258 53.87162) (xy 193.65077 53.87162) (xy 193.65077 53.87982) (xy 193.67536 53.87982) (xy 193.67536 53.87162)
			(xy 193.67536 53.86343) (xy 193.67536 53.85523) (xy 193.67536 53.84704) (xy 193.67536 53.83884) (xy 193.67536 53.83065)
			(xy 193.67536 53.82246) (xy 193.67536 53.81426) (xy 193.67536 53.80606) (xy 193.67536 53.79787) (xy 193.67536 53.78968)
			(xy 193.67536 53.78148) (xy 193.67536 53.77329) (xy 193.67536 53.76509) (xy 193.67536 53.7569) (xy 193.67536 53.7487)
			(xy 193.67536 53.74051) (xy 193.67536 53.73231) (xy 193.67536 53.72412) (xy 193.67536 53.71593) (xy 193.67536 53.70773)
			(xy 193.67536 53.69954) (xy 193.67536 53.69134) (xy 193.67536 53.68315) (xy 193.67536 53.67495) (xy 193.67536 53.66676)
			(xy 193.67536 53.65857) (xy 193.67536 53.65037) (xy 193.67536 53.64218) (xy 193.67536 53.63398) (xy 193.67536 53.62579)
			(xy 193.67536 53.61759) (xy 193.67536 53.6094) (xy 193.67536 53.6012) (xy 193.67536 53.59301) (xy 193.67536 53.58482)
			(xy 193.67536 53.57662) (xy 193.67536 53.56843) (xy 193.67536 53.56023) (xy 193.67536 53.55204) (xy 193.67536 53.54384)
			(xy 193.67536 53.53565) (xy 193.67536 53.52745) (xy 193.67536 53.51926) (xy 193.67536 53.51106) (xy 193.67536 53.50287)
			(xy 193.67536 53.49467) (xy 193.67536 53.48648) (xy 193.67536 53.47829) (xy 193.67536 53.47009) (xy 193.67536 53.4619)
			(xy 193.67536 53.4537) (xy 193.67536 53.44551) (xy 193.67536 53.43731) (xy 192.4216 53.43731) (xy 192.4216 53.44551)
			(xy 192.39702 53.44551) (xy 192.39702 53.4537) (xy 192.38882 53.4537) (xy 192.38882 53.4619) (xy 192.38882 53.47009)
			(xy 192.38063 53.47009) (xy 192.17576 53.47009) (xy 192.17576 53.4619) (xy 192.16757 53.4619) (xy 192.16757 53.4537)
			(xy 192.15938 53.4537) (xy 192.15938 53.44551) (xy 192.14298 53.44551) (xy 192.14298 53.43731) (xy 191.76604 53.43731)
			(xy 191.76604 53.44551) (xy 191.74146 53.44551) (xy 191.74146 53.4537) (xy 191.74146 53.4619) (xy 191.73326 53.4619)
			(xy 191.73326 53.47009) (xy 191.73326 53.47829) (xy 191.72507 53.47829) (xy 191.61854 53.47829) (xy 191.61854 53.47009)
			(xy 191.61854 53.4619) (xy 191.61034 53.4619) (xy 191.61034 53.4537) (xy 191.60215 53.4537) (xy 191.60215 53.44551)
			(xy 191.58576 53.44551) (xy 191.58576 53.43731) (xy 191.56937 53.43731) (xy 191.56937 53.44551) (xy 191.56118 53.44551)
			(xy 191.56118 53.43731) (xy 190.29923 53.43731) (xy 190.29923 53.44551) (xy 190.27464 53.44551) (xy 190.27464 53.4537)
			(xy 190.26645 53.4537) (xy 190.26645 53.4619) (xy 190.26645 53.47009) (xy 190.25825 53.47009) (xy 189.02908 53.47009)
			(xy 189.02908 53.4619) (xy 189.02908 53.4537) (xy 189.02908 53.44551) (xy 189.02908 53.43731) (xy 189.02908 53.42912)
			(xy 189.02908 53.42092) (xy 189.02908 53.41273) (xy 189.02908 53.40453) (xy 189.02908 53.39634) (xy 189.02908 53.38815)
			(xy 189.02908 53.37995) (xy 189.02908 53.37176) (xy 189.02908 53.36356) (xy 189.02908 53.35537) (xy 189.02908 53.34718)
			(xy 189.02908 53.33898) (xy 189.02908 53.33079) (xy 189.02908 53.32259) (xy 189.02908 53.31439) (xy 189.02908 53.3062)
			(xy 189.02908 53.29801) (xy 191.61854 53.29801) (xy 191.61854 53.3062) (xy 191.74965 53.3062) (xy 191.74965 53.29801)
			(xy 191.75784 53.29801) (xy 191.75784 53.28981) (xy 191.76604 53.28981) (xy 191.76604 53.28162) (xy 191.76604 53.27342)
			(xy 191.77424 53.27342) (xy 191.77424 53.26523) (xy 191.78243 53.26523) (xy 191.78243 53.25703) (xy 191.79063 53.25703)
			(xy 191.79063 53.24884) (xy 191.79882 53.24884) (xy 191.79882 53.24065) (xy 191.80701 53.24065) (xy 191.80701 53.23245)
			(xy 191.81521 53.23245) (xy 191.81521 53.22426) (xy 191.8234 53.22426) (xy 191.8234 53.21606) (xy 191.8316 53.21606)
			(xy 191.8316 53.20787) (xy 191.8316 53.19967) (xy 191.83979 53.19967) (xy 191.83979 53.19148) (xy 191.84798 53.19148)
			(xy 191.84798 53.18328) (xy 191.85618 53.18328) (xy 191.85618 53.17509) (xy 191.86437 53.17509) (xy 191.86437 53.16689)
			(xy 191.87257 53.16689) (xy 191.87257 53.1587) (xy 191.88076 53.1587) (xy 191.88076 53.15051) (xy 191.88896 53.15051)
			(xy 191.88896 53.14231) (xy 191.89715 53.14231) (xy 191.89715 53.13412) (xy 191.90534 53.13412) (xy 191.90534 53.12592)
			(xy 191.91354 53.12592) (xy 191.91354 53.11773) (xy 191.92174 53.11773) (xy 191.92174 53.10953) (xy 191.92993 53.10953)
			(xy 191.92993 53.10134) (xy 191.93812 53.10134) (xy 191.93812 53.09315) (xy 191.94632 53.09315) (xy 191.94632 53.08495)
			(xy 191.95451 53.08495) (xy 191.95451 53.07675) (xy 191.96271 53.07675) (xy 191.96271 53.06856) (xy 191.9709 53.06856)
			(xy 191.9709 53.06037) (xy 191.9791 53.06037) (xy 191.9791 53.05217) (xy 191.98729 53.05217) (xy 191.98729 53.04398)
			(xy 191.99548 53.04398) (xy 191.99548 53.03578) (xy 192.01188 53.03578) (xy 192.01188 53.02759) (xy 192.02007 53.02759)
			(xy 192.02007 53.01939) (xy 192.02826 53.01939) (xy 192.02826 53.0112) (xy 192.03646 53.0112) (xy 192.03646 53.00301)
			(xy 192.04465 53.00301) (xy 192.04465 52.99481) (xy 192.05285 52.99481) (xy 192.05285 52.98662) (xy 192.06104 52.98662)
			(xy 192.06104 52.97842) (xy 192.06924 52.97842) (xy 192.06924 52.97023) (xy 192.07743 52.97023) (xy 192.07743 52.96203)
			(xy 192.09382 52.96203) (xy 192.09382 52.95384) (xy 192.10201 52.95384) (xy 192.10201 52.94564) (xy 192.11021 52.94564)
			(xy 192.11021 52.93745) (xy 192.1184 52.93745) (xy 192.1184 52.92926) (xy 192.1266 52.92926) (xy 192.1266 52.92106)
			(xy 192.14298 52.92106) (xy 192.14298 52.91287) (xy 192.15118 52.91287) (xy 192.15118 52.90467) (xy 192.15938 52.90467)
			(xy 192.15938 52.89648) (xy 192.16757 52.89648) (xy 192.16757 52.88828) (xy 192.18396 52.88828) (xy 192.18396 52.88009)
			(xy 192.19215 52.88009) (xy 192.19215 52.87189) (xy 192.20035 52.87189) (xy 192.20035 52.8637) (xy 192.20854 52.8637)
			(xy 192.20854 52.85551) (xy 192.22493 52.85551) (xy 192.22493 52.84731) (xy 192.23313 52.84731) (xy 192.23313 52.83911)
			(xy 192.24132 52.83911) (xy 192.24132 52.83092) (xy 192.25771 52.83092) (xy 192.25771 52.82273) (xy 192.2659 52.82273)
			(xy 192.2659 52.81453) (xy 192.2741 52.81453) (xy 192.2741 52.80634) (xy 192.29049 52.80634) (xy 192.29049 52.79814)
			(xy 192.29868 52.79814) (xy 192.29868 52.78995) (xy 192.30688 52.78995) (xy 192.30688 52.78175) (xy 192.32327 52.78175)
			(xy 192.32327 52.77356) (xy 192.33146 52.77356) (xy 192.33146 52.76536) (xy 192.34785 52.76536) (xy 192.34785 52.75717)
			(xy 192.35604 52.75717) (xy 192.35604 52.74898) (xy 192.37243 52.74898) (xy 192.37243 52.74078) (xy 192.38063 52.74078)
			(xy 192.38063 52.73259) (xy 192.39702 52.73259) (xy 192.39702 52.72439) (xy 192.40521 52.72439) (xy 192.40521 52.7162)
			(xy 192.4216 52.7162) (xy 192.4216 52.708) (xy 192.42979 52.708) (xy 192.42979 52.69981) (xy 192.44618 52.69981)
			(xy 192.44618 52.69162) (xy 192.45438 52.69162) (xy 192.45438 52.68342) (xy 192.47077 52.68342) (xy 192.47077 52.67522)
			(xy 192.48715 52.67522) (xy 192.48715 52.66703) (xy 192.49535 52.66703) (xy 192.49535 52.65884) (xy 192.51174 52.65884)
			(xy 192.51174 52.65064) (xy 192.52813 52.65064) (xy 192.52813 52.64245) (xy 192.53632 52.64245) (xy 192.53632 52.63425)
			(xy 192.55271 52.63425) (xy 192.55271 52.62606) (xy 192.5691 52.62606) (xy 192.5691 52.61787) (xy 192.5773 52.61787)
			(xy 192.5773 52.60967) (xy 192.59368 52.60967) (xy 192.59368 52.60148) (xy 192.61007 52.60148) (xy 192.61007 52.59328)
			(xy 192.62646 52.59328) (xy 192.62646 52.58509) (xy 192.64285 52.58509) (xy 192.64285 52.57689) (xy 192.65924 52.57689)
			(xy 192.65924 52.5687) (xy 192.67563 52.5687) (xy 192.67563 52.5605) (xy 192.68382 52.5605) (xy 192.68382 52.55231)
			(xy 192.70021 52.55231) (xy 192.70021 52.54411) (xy 192.7166 52.54411) (xy 192.7166 52.53592) (xy 192.73299 52.53592)
			(xy 192.73299 52.52772) (xy 192.74938 52.52772) (xy 192.74938 52.51953) (xy 192.77396 52.51953) (xy 192.77396 52.51134)
			(xy 192.79035 52.51134) (xy 192.79035 52.50314) (xy 192.80674 52.50314) (xy 192.80674 52.49495) (xy 192.82313 52.49495)
			(xy 192.82313 52.48675) (xy 192.83952 52.48675) (xy 192.83952 52.47856) (xy 192.85591 52.47856) (xy 192.85591 52.47036)
			(xy 192.88049 52.47036) (xy 192.88049 52.46217) (xy 192.89688 52.46217) (xy 192.89688 52.45397) (xy 192.91327 52.45397)
			(xy 192.91327 52.44578) (xy 192.93785 52.44578) (xy 192.93785 52.43759) (xy 192.95424 52.43759) (xy 192.95424 52.42939)
			(xy 192.97883 52.42939) (xy 192.97883 52.4212) (xy 193.00341 52.4212) (xy 193.00341 52.413) (xy 193.0198 52.413)
			(xy 193.0198 52.40481) (xy 193.04438 52.40481) (xy 193.04438 52.39661) (xy 193.06896 52.39661) (xy 193.06896 52.38842)
			(xy 193.09355 52.38842) (xy 193.09355 52.38022) (xy 193.10994 52.38022) (xy 193.10994 52.37203) (xy 193.14271 52.37203)
			(xy 193.14271 52.36384) (xy 193.1673 52.36384) (xy 193.1673 52.35564) (xy 193.19188 52.35564) (xy 193.19188 52.34744)
			(xy 193.21646 52.34744) (xy 193.21646 52.33925) (xy 193.24924 52.33925) (xy 193.24924 52.33106) (xy 193.27383 52.33106)
			(xy 193.27383 52.32286) (xy 193.30661 52.32286) (xy 193.30661 52.31467) (xy 193.33938 52.31467) (xy 193.33938 52.30647)
			(xy 193.37216 52.30647) (xy 193.37216 52.29828) (xy 193.40494 52.29828) (xy 193.40494 52.29008) (xy 193.44591 52.29008)
			(xy 193.44591 52.28189) (xy 193.48688 52.28189) (xy 193.48688 52.2737) (xy 193.51966 52.2737) (xy 193.51966 52.2655)
			(xy 193.57702 52.2655) (xy 193.57702 52.25731) (xy 193.62619 52.25731) (xy 193.62619 52.24911) (xy 193.68355 52.24911)
			(xy 193.68355 52.24092) (xy 193.74911 52.24092) (xy 193.74911 52.23272) (xy 193.83925 52.23272) (xy 193.83925 52.22453)
			(xy 193.98675 52.22453) (xy 193.98675 52.21633) (xy 194.19161 52.21633) (xy 194.19161 52.22453) (xy 194.19981 52.22453)
			(xy 194.19981 52.21633) (xy 194.208 52.21633) (xy 194.208 52.22453) (xy 194.33911 52.22453) (xy 194.33911 52.23272)
			(xy 194.42925 52.23272) (xy 194.42925 52.24092) (xy 194.503 52.24092) (xy 194.503 52.24911) (xy 194.55217 52.24911)
			(xy 194.55217 52.25731) (xy 194.60133 52.25731) (xy 194.60133 52.2655) (xy 194.6505 52.2655) (xy 194.6505 52.2737)
			(xy 194.69148 52.2737) (xy 194.69148 52.28189) (xy 194.73245 52.28189) (xy 194.73245 52.29008) (xy 194.77342 52.29008)
			(xy 194.77342 52.29828) (xy 194.8062 52.29828) (xy 194.8062 52.30647) (xy 194.83898 52.30647) (xy 194.83898 52.31467)
			(xy 194.87175 52.31467) (xy 194.87175 52.32286) (xy 194.90453 52.32286) (xy 194.90453 52.33106) (xy 194.92912 52.33106)
			(xy 194.92912 52.33925) (xy 194.96189 52.33925) (xy 194.96189 52.34744) (xy 194.98648 52.34744) (xy 194.98648 52.35564)
			(xy 195.01106 52.35564) (xy 195.01106 52.36384) (xy 195.03564 52.36384) (xy 195.03564 52.37203) (xy 195.06023 52.37203)
			(xy 195.06023 52.38022) (xy 195.08481 52.38022) (xy 195.08481 52.38842) (xy 195.10939 52.38842) (xy 195.10939 52.39661)
			(xy 195.13398 52.39661) (xy 195.13398 52.40481) (xy 195.15856 52.40481) (xy 195.15856 52.413) (xy 195.17495 52.413)
			(xy 195.17495 52.4212) (xy 195.19953 52.4212) (xy 195.19953 52.42939) (xy 195.21592 52.42939) (xy 195.21592 52.43759)
			(xy 195.2405 52.43759) (xy 195.2405 52.44578) (xy 195.2569 52.44578) (xy 195.2569 52.45397) (xy 195.28148 52.45397)
			(xy 195.28148 52.46217) (xy 195.29787 52.46217) (xy 195.29787 52.47036) (xy 195.31425 52.47036) (xy 195.31425 52.47856)
			(xy 195.33884 52.47856) (xy 195.33884 52.48675) (xy 195.35523 52.48675) (xy 195.35523 52.49495) (xy 195.37162 52.49495)
			(xy 195.37162 52.50314) (xy 195.388 52.50314) (xy 195.388 52.51134) (xy 195.4044 52.51134) (xy 195.4044 52.51953)
			(xy 195.42898 52.51953) (xy 195.42898 52.52772) (xy 195.44537 52.52772) (xy 195.44537 52.53592) (xy 195.45356 52.53592)
			(xy 195.45356 52.54411) (xy 195.46995 52.54411) (xy 195.46995 52.55231) (xy 195.48634 52.55231) (xy 195.48634 52.5605)
			(xy 195.50273 52.5605) (xy 195.50273 52.5687) (xy 195.51912 52.5687) (xy 195.51912 52.57689) (xy 195.53551 52.57689)
			(xy 195.53551 52.58509) (xy 195.5519 52.58509) (xy 195.5519 52.59328) (xy 195.56828 52.59328) (xy 195.56828 52.60148)
			(xy 195.58467 52.60148) (xy 195.58467 52.60967) (xy 195.59287 52.60967) (xy 195.59287 52.61787) (xy 195.60926 52.61787)
			(xy 195.60926 52.62606) (xy 195.62564 52.62606) (xy 195.62564 52.63425) (xy 195.64204 52.63425) (xy 195.64204 52.64245)
			(xy 195.65023 52.64245) (xy 195.65023 52.65064) (xy 195.66662 52.65064) (xy 195.66662 52.65884) (xy 195.68301 52.65884)
			(xy 195.68301 52.66703) (xy 195.6912 52.66703) (xy 195.6912 52.67522) (xy 195.70759 52.67522) (xy 195.70759 52.68342)
			(xy 195.72398 52.68342) (xy 195.72398 52.69162) (xy 195.73217 52.69162) (xy 195.73217 52.69981) (xy 195.74856 52.69981)
			(xy 195.74856 52.708) (xy 195.75676 52.708) (xy 195.75676 52.7162) (xy 195.77315 52.7162) (xy 195.77315 52.72439)
			(xy 195.78134 52.72439) (xy 195.78134 52.73259) (xy 195.79773 52.73259) (xy 195.79773 52.74078) (xy 195.80592 52.74078)
			(xy 195.80592 52.74898) (xy 195.82231 52.74898) (xy 195.82231 52.75717) (xy 195.83051 52.75717) (xy 195.83051 52.76536)
			(xy 195.8469 52.76536) (xy 195.8469 52.77356) (xy 195.85509 52.77356) (xy 195.85509 52.78175) (xy 195.86329 52.78175)
			(xy 195.86329 52.78995) (xy 195.87968 52.78995) (xy 195.87968 52.79814) (xy 195.88787 52.79814) (xy 195.88787 52.80634)
			(xy 195.90426 52.80634) (xy 195.90426 52.81453) (xy 195.91245 52.81453) (xy 195.91245 52.82273) (xy 195.92065 52.82273)
			(xy 195.92065 52.83092) (xy 195.93704 52.83092) (xy 195.93704 52.83911) (xy 195.94523 52.83911) (xy 195.94523 52.84731)
			(xy 195.95343 52.84731) (xy 195.95343 52.85551) (xy 195.96981 52.85551) (xy 195.96981 52.8637) (xy 195.97801 52.8637)
			(xy 195.97801 52.87189) (xy 195.98621 52.87189) (xy 195.98621 52.88009) (xy 195.9944 52.88009) (xy 195.9944 52.88828)
			(xy 196.01079 52.88828) (xy 196.01079 52.89648) (xy 196.01898 52.89648) (xy 196.01898 52.90467) (xy 196.02718 52.90467)
			(xy 196.02718 52.91287) (xy 196.03537 52.91287) (xy 196.03537 52.92106) (xy 196.05176 52.92106) (xy 196.05176 52.92926)
			(xy 196.05995 52.92926) (xy 196.05995 52.93745) (xy 196.06815 52.93745) (xy 196.06815 52.94564) (xy 196.07634 52.94564)
			(xy 196.07634 52.95384) (xy 196.08454 52.95384) (xy 196.08454 52.96203) (xy 196.09273 52.96203) (xy 196.09273 52.97023)
			(xy 196.10912 52.97023) (xy 196.10912 52.97842) (xy 196.11732 52.97842) (xy 196.11732 52.98662) (xy 196.12551 52.98662)
			(xy 196.12551 52.99481) (xy 196.13371 52.99481) (xy 196.13371 53.00301) (xy 196.1419 53.00301) (xy 196.1419 53.0112)
			(xy 196.15009 53.0112) (xy 196.15009 53.01939) (xy 196.15829 53.01939) (xy 196.15829 53.02759) (xy 196.16648 53.02759)
			(xy 196.16648 53.03578) (xy 196.17468 53.03578) (xy 196.17468 53.04398) (xy 196.19107 53.04398) (xy 196.19107 53.05217)
			(xy 196.19926 53.05217) (xy 196.19926 53.06037) (xy 196.20746 53.06037) (xy 196.20746 53.06856) (xy 196.21565 53.06856)
			(xy 196.21565 53.07675) (xy 196.22385 53.07675) (xy 196.22385 53.08495) (xy 196.23204 53.08495) (xy 196.23204 53.09315)
			(xy 196.24023 53.09315) (xy 196.24023 53.10134) (xy 196.24843 53.10134) (xy 196.24843 53.10953) (xy 196.25662 53.10953)
			(xy 196.25662 53.11773) (xy 196.26482 53.11773) (xy 196.26482 53.12592) (xy 196.27301 53.12592) (xy 196.27301 53.13412)
			(xy 196.28121 53.13412) (xy 196.28121 53.14231) (xy 196.2894 53.14231) (xy 196.2894 53.15051) (xy 196.29759 53.15051)
			(xy 196.29759 53.1587) (xy 196.30579 53.1587) (xy 196.30579 53.16689) (xy 196.31398 53.16689) (xy 196.31398 53.17509)
			(xy 196.32218 53.17509) (xy 196.32218 53.18328) (xy 196.33037 53.18328) (xy 196.33037 53.19148) (xy 196.33037 53.19967)
			(xy 196.33857 53.19967) (xy 196.33857 53.20787) (xy 196.34676 53.20787) (xy 196.34676 53.21606) (xy 196.35496 53.21606)
			(xy 196.35496 53.22426) (xy 196.36315 53.22426) (xy 196.36315 53.23245) (xy 196.37135 53.23245) (xy 196.37135 53.24065)
			(xy 196.37954 53.24065) (xy 196.37954 53.24884) (xy 196.38773 53.24884) (xy 196.38773 53.25703) (xy 196.39593 53.25703)
			(xy 196.39593 53.26523) (xy 196.40412 53.26523) (xy 196.40412 53.27342) (xy 196.40412 53.28162) (xy 196.41232 53.28162)
			(xy 196.41232 53.28981) (xy 196.42051 53.28981) (xy 196.42051 53.29801) (xy 196.42871 53.29801) (xy 196.42871 53.3062)
			(xy 196.4369 53.3062) (xy 196.4369 53.31439) (xy 196.4451 53.31439) (xy 196.4451 53.32259) (xy 196.45329 53.32259)
			(xy 196.45329 53.33079) (xy 196.45329 53.33898) (xy 196.46148 53.33898) (xy 196.46148 53.34718) (xy 196.46968 53.34718)
			(xy 196.46968 53.35537) (xy 196.47787 53.35537) (xy 196.47787 53.36356) (xy 196.48607 53.36356) (xy 196.48607 53.37176)
			(xy 196.48607 53.37995) (xy 196.49426 53.37995) (xy 196.49426 53.38815) (xy 196.50246 53.38815) (xy 196.50246 53.39634)
			(xy 196.51065 53.39634) (xy 196.51065 53.40453) (xy 196.51885 53.40453) (xy 196.51885 53.41273) (xy 196.51885 53.42092)
			(xy 196.52704 53.42092) (xy 196.52704 53.42912) (xy 196.53523 53.42912) (xy 196.53523 53.43731) (xy 196.54343 53.43731)
			(xy 196.54343 53.44551) (xy 196.54343 53.4537) (xy 196.55162 53.4537) (xy 196.55162 53.4619) (xy 196.55982 53.4619)
			(xy 196.55982 53.47009) (xy 196.56801 53.47009) (xy 196.56801 53.47829) (xy 196.56801 53.48648) (xy 196.57621 53.48648)
			(xy 196.57621 53.49467) (xy 196.5844 53.49467) (xy 196.5844 53.50287) (xy 196.5844 53.51106) (xy 196.5926 53.51106)
			(xy 196.5926 53.51926) (xy 196.60079 53.51926) (xy 196.60079 53.52745) (xy 196.60899 53.52745) (xy 196.60899 53.53565)
			(xy 196.60899 53.54384) (xy 196.61718 53.54384) (xy 196.61718 53.55204) (xy 196.62538 53.55204) (xy 196.62538 53.56023)
			(xy 196.62538 53.56843) (xy 196.63357 53.56843) (xy 196.63357 53.57662) (xy 196.64176 53.57662) (xy 196.64176 53.58482)
			(xy 196.64176 53.59301) (xy 196.64996 53.59301) (xy 196.64996 53.6012) (xy 196.65815 53.6012) (xy 196.65815 53.6094)
			(xy 196.65815 53.61759) (xy 196.66635 53.61759) (xy 196.66635 53.62579) (xy 196.67454 53.62579) (xy 196.67454 53.63398)
			(xy 196.67454 53.64218) (xy 196.68274 53.64218) (xy 196.68274 53.65037) (xy 196.69093 53.65037) (xy 196.69093 53.65857)
			(xy 196.69093 53.66676) (xy 196.69913 53.66676) (xy 196.69913 53.67495) (xy 196.69913 53.68315) (xy 196.70732 53.68315)
			(xy 196.70732 53.69134) (xy 196.71552 53.69134) (xy 196.71552 53.69954) (xy 196.71552 53.70773) (xy 196.72371 53.70773)
			(xy 196.72371 53.71593) (xy 196.72371 53.72412) (xy 196.7319 53.72412) (xy 196.7319 53.73231) (xy 196.7401 53.73231)
			(xy 196.7401 53.74051) (xy 196.7401 53.7487) (xy 196.74829 53.7487) (xy 196.74829 53.7569) (xy 196.74829 53.76509)
			(xy 196.75649 53.76509) (xy 196.75649 53.77329) (xy 196.75649 53.78148) (xy 196.76468 53.78148) (xy 196.76468 53.78968)
			(xy 196.77287 53.78968) (xy 196.77287 53.79787) (xy 196.77287 53.80606) (xy 196.78107 53.80606) (xy 196.78107 53.81426)
			(xy 196.78107 53.82246) (xy 196.78926 53.82246) (xy 196.78926 53.83065) (xy 196.78926 53.83884) (xy 196.79746 53.83884)
			(xy 196.79746 53.84704) (xy 196.79746 53.85523) (xy 196.80565 53.85523) (xy 196.80565 53.86343) (xy 196.80565 53.87162)
			(xy 196.81385 53.87162) (xy 196.81385 53.87982) (xy 196.82204 53.87982) (xy 196.82204 53.88801) (xy 196.82204 53.8962)
			(xy 196.83023 53.8962) (xy 196.83023 53.9044) (xy 196.83023 53.91259) (xy 196.83843 53.91259) (xy 196.83843 53.92079)
			(xy 196.83843 53.92898) (xy 196.84663 53.92898) (xy 196.84663 53.93718) (xy 196.84663 53.94537) (xy 196.85482 53.94537)
			(xy 196.85482 53.95357) (xy 196.85482 53.96176) (xy 196.85482 53.96996) (xy 196.86302 53.96996) (xy 196.86302 53.97815)
			(xy 196.86302 53.98634) (xy 196.87121 53.98634) (xy 196.87121 53.99454) (xy 196.87121 54.00273) (xy 196.8794 54.00273)
			(xy 196.8794 54.01093) (xy 196.8794 54.01912) (xy 196.8876 54.01912) (xy 196.8876 54.02732) (xy 196.8876 54.03551)
			(xy 196.89579 54.03551) (xy 196.89579 54.0437) (xy 196.89579 54.0519) (xy 196.90399 54.0519) (xy 196.90399 54.0601)
			(xy 196.90399 54.06829) (xy 196.90399 54.07649) (xy 196.91218 54.07649) (xy 196.91218 54.08468) (xy 196.91218 54.09287)
			(xy 196.92038 54.09287) (xy 196.92038 54.10107) (xy 196.92038 54.10926) (xy 196.92857 54.10926) (xy 196.92857 54.11746)
			(xy 196.92857 54.12565) (xy 196.92857 54.13385) (xy 196.93676 54.13385) (xy 196.93676 54.14204) (xy 196.93676 54.15023)
			(xy 196.94496 54.15023) (xy 196.94496 54.15843) (xy 196.94496 54.16662) (xy 196.94496 54.17482) (xy 196.95315 54.17482)
			(xy 196.95315 54.18301) (xy 196.95315 54.19121) (xy 196.96135 54.19121) (xy 196.96135 54.1994) (xy 196.96135 54.2076)
			(xy 196.96135 54.21579) (xy 196.96954 54.21579) (xy 196.96954 54.22398) (xy 196.96954 54.23218) (xy 196.96954 54.24037)
			(xy 196.97774 54.24037) (xy 196.97774 54.24857) (xy 196.97774 54.25676) (xy 196.97774 54.26496) (xy 196.98593 54.26496)
			(xy 196.98593 54.27315) (xy 196.98593 54.28134) (xy 196.99413 54.28134) (xy 196.99413 54.28954) (xy 196.99413 54.29774)
			(xy 196.99413 54.30593) (xy 197.00232 54.30593) (xy 197.00232 54.31413) (xy 197.00232 54.32232) (xy 197.00232 54.33051)
			(xy 197.01052 54.33051) (xy 197.01052 54.33871) (xy 197.01052 54.3469) (xy 197.01052 54.3551) (xy 197.01052 54.36329)
			(xy 197.01871 54.36329) (xy 197.01871 54.37149) (xy 197.01871 54.37968) (xy 197.01871 54.38787) (xy 197.0269 54.38787)
			(xy 197.0269 54.39607) (xy 197.0269 54.40426) (xy 197.0269 54.41246) (xy 197.0351 54.41246) (xy 197.0351 54.42065)
			(xy 197.0351 54.42885) (xy 197.0351 54.43704) (xy 197.0351 54.44524) (xy 197.0433 54.44524) (xy 197.0433 54.45343)
			(xy 197.0433 54.46162) (xy 197.0433 54.46982) (xy 197.05149 54.46982) (xy 197.05149 54.47801) (xy 197.05149 54.48621)
			(xy 197.05149 54.4944) (xy 197.05149 54.5026) (xy 197.05968 54.5026) (xy 197.05968 54.51079) (xy 197.05968 54.51899)
			(xy 197.05968 54.52718) (xy 197.05968 54.53538) (xy 197.06788 54.53538) (xy 197.06788 54.54357) (xy 197.06788 54.55176)
			(xy 197.06788 54.55996) (xy 197.06788 54.56815) (xy 197.07607 54.56815) (xy 197.07607 54.57635) (xy 197.07607 54.58454)
			(xy 197.07607 54.59274) (xy 197.07607 54.60093) (xy 197.08427 54.60093) (xy 197.08427 54.60913) (xy 197.08427 54.61732)
			(xy 197.08427 54.62551) (xy 197.08427 54.63371) (xy 197.08427 54.6419) (xy 197.09246 54.6419) (xy 197.09246 54.6501)
			(xy 197.09246 54.65829) (xy 197.09246 54.66649) (xy 197.09246 54.67468) (xy 197.10066 54.67468) (xy 197.10066 54.68288)
			(xy 197.10066 54.69107) (xy 197.10066 54.69926) (xy 197.10066 54.70746) (xy 197.10066 54.71565) (xy 197.10066 54.72385)
			(xy 197.10885 54.72385) (xy 197.10885 54.73204) (xy 197.10885 54.74024) (xy 197.10885 54.74843) (xy 197.10885 54.75663)
			(xy 197.10885 54.76482) (xy 197.11704 54.76482) (xy 197.11704 54.77302) (xy 197.11704 54.78121) (xy 197.11704 54.78941)
			(xy 197.11704 54.7976) (xy 197.11704 54.80579) (xy 197.11704 54.81399) (xy 197.12524 54.81399) (xy 197.12524 54.82218)
			(xy 197.12524 54.83038) (xy 197.12524 54.83857) (xy 197.12524 54.84677) (xy 197.12524 54.85496) (xy 197.12524 54.86316)
			(xy 197.12524 54.87135) (xy 197.13343 54.87135) (xy 197.13343 54.87955) (xy 197.13343 54.88774) (xy 197.13343 54.89593)
			(xy 197.13343 54.90413) (xy 197.13343 54.91232) (xy 197.13343 54.92052) (xy 197.13343 54.92871) (xy 197.13343 54.93691)
			(xy 197.13343 54.9451) (xy 197.14163 54.9451) (xy 197.14163 54.95329) (xy 197.14163 54.96149) (xy 197.14163 54.96968)
			(xy 197.14163 54.97788) (xy 197.14163 54.98607) (xy 197.14163 54.99427) (xy 197.14163 55.00246) (xy 197.14163 55.01065)
			(xy 197.14163 55.01885) (xy 197.14982 55.01885) (xy 197.14982 55.02705) (xy 197.14982 55.03524) (xy 197.14982 55.04344)
			(xy 197.14982 55.05163) (xy 197.14982 55.05982) (xy 197.14982 55.06802) (xy 197.14982 55.07621) (xy 197.14982 55.08441)
			(xy 197.14982 55.0926) (xy 197.14982 55.1008) (xy 197.14982 55.10899) (xy 197.14982 55.11718) (xy 197.14982 55.12538)
			(xy 197.14982 55.13357) (xy 197.14982 55.14177) (xy 197.14982 55.14996) (xy 197.14982 55.15816) (xy 197.15802 55.15816)
			(xy 197.15802 55.16635) (xy 197.15802 55.17455) (xy 197.15802 55.18274) (xy 197.15802 55.19093) (xy 197.15802 55.19913)
			(xy 197.15802 55.20732) (xy 197.15802 55.21552) (xy 197.15802 55.22371) (xy 197.15802 55.23191) (xy 197.15802 55.2401)
			(xy 197.15802 55.2483) (xy 197.25635 55.2483) (xy 197.25635 55.2401) (xy 197.25635 55.23191) (xy 197.25635 55.22371)
			(xy 197.25635 55.21552) (xy 197.25635 55.20732) (xy 197.25635 55.19913) (xy 197.25635 55.19093) (xy 197.25635 55.18274)
			(xy 197.25635 55.17455) (xy 197.25635 55.16635) (xy 197.25635 55.15816) (xy 197.25635 55.14996) (xy 197.24816 55.14996)
			(xy 197.24816 55.14177) (xy 197.25635 55.14177) (xy 197.25635 55.13357) (xy 197.25635 55.12538) (xy 197.25635 55.11718)
			(xy 197.24816 55.11718) (xy 197.24816 55.10899) (xy 197.24816 55.1008) (xy 197.24816 55.0926) (xy 197.24816 55.08441)
			(xy 197.24816 55.07621) (xy 197.24816 55.06802) (xy 197.24816 55.05982) (xy 197.24816 55.05163) (xy 197.24816 55.04344)
			(xy 197.24816 55.03524) (xy 197.24816 55.02705) (xy 197.24816 55.01885) (xy 197.24816 55.01065) (xy 197.24816 55.00246)
			(xy 197.23996 55.00246) (xy 197.23996 54.99427) (xy 197.23996 54.98607) (xy 197.23996 54.97788) (xy 197.23996 54.96968)
			(xy 197.23996 54.96149) (xy 197.23996 54.95329) (xy 197.23996 54.9451) (xy 197.23996 54.93691) (xy 197.23996 54.92871)
			(xy 197.23996 54.92052) (xy 197.23177 54.92052) (xy 197.23177 54.91232) (xy 197.23177 54.90413) (xy 197.23177 54.89593)
			(xy 197.23177 54.88774) (xy 197.23177 54.87955) (xy 197.23177 54.87135) (xy 197.23177 54.86316) (xy 197.23177 54.85496)
			(xy 197.22357 54.85496) (xy 197.22357 54.84677) (xy 197.22357 54.83857) (xy 197.22357 54.83038) (xy 197.22357 54.82218)
			(xy 197.22357 54.81399) (xy 197.22357 54.80579) (xy 197.22357 54.7976) (xy 197.21538 54.7976) (xy 197.21538 54.78941)
			(xy 197.21538 54.78121) (xy 197.21538 54.77302) (xy 197.21538 54.76482) (xy 197.21538 54.75663) (xy 197.21538 54.74843)
			(xy 197.20719 54.74843) (xy 197.20719 54.74024) (xy 197.20719 54.73204) (xy 197.20719 54.72385) (xy 197.20719 54.71565)
			(xy 197.20719 54.70746) (xy 197.19899 54.70746) (xy 197.19899 54.69926) (xy 197.19899 54.69107) (xy 197.19899 54.68288)
			(xy 197.19899 54.67468) (xy 197.19899 54.66649) (xy 197.19079 54.66649) (xy 197.19079 54.65829) (xy 197.19079 54.6501)
			(xy 197.19079 54.6419) (xy 197.19079 54.63371) (xy 197.19079 54.62551) (xy 197.1826 54.62551) (xy 197.1826 54.61732)
			(xy 197.1826 54.60913) (xy 197.1826 54.60093) (xy 197.1826 54.59274) (xy 197.1826 54.58454) (xy 197.17441 54.58454)
			(xy 197.17441 54.57635) (xy 197.17441 54.56815) (xy 197.17441 54.55996) (xy 197.17441 54.55176) (xy 197.16621 54.55176)
			(xy 197.16621 54.54357) (xy 197.16621 54.53538) (xy 197.16621 54.52718) (xy 197.16621 54.51899) (xy 197.15802 54.51899)
			(xy 197.15802 54.51079) (xy 197.15802 54.5026) (xy 197.15802 54.4944) (xy 197.15802 54.48621) (xy 197.14982 54.48621)
			(xy 197.14982 54.47801) (xy 197.14982 54.46982) (xy 197.14982 54.46162) (xy 197.14982 54.45343) (xy 197.14163 54.45343)
			(xy 197.14163 54.44524) (xy 197.14163 54.43704) (xy 197.14163 54.42885) (xy 197.13343 54.42885) (xy 197.13343 54.42065)
			(xy 197.13343 54.41246) (xy 197.13343 54.40426) (xy 197.13343 54.39607) (xy 197.12524 54.39607) (xy 197.12524 54.38787)
			(xy 197.12524 54.37968) (xy 197.12524 54.37149) (xy 197.11704 54.37149) (xy 197.11704 54.36329) (xy 197.11704 54.3551)
			(xy 197.11704 54.3469) (xy 197.11704 54.33871) (xy 197.10885 54.33871) (xy 197.10885 54.33051) (xy 197.10885 54.32232)
			(xy 197.10885 54.31413) (xy 197.10066 54.31413) (xy 197.10066 54.30593) (xy 197.10066 54.29774) (xy 197.10066 54.28954)
			(xy 197.09246 54.28954) (xy 197.09246 54.28134) (xy 197.09246 54.27315) (xy 197.09246 54.26496) (xy 197.08427 54.26496)
			(xy 197.08427 54.25676) (xy 197.08427 54.24857) (xy 197.08427 54.24037) (xy 197.07607 54.24037) (xy 197.07607 54.23218)
			(xy 197.07607 54.22398) (xy 197.07607 54.21579) (xy 197.06788 54.21579) (xy 197.06788 54.2076) (xy 197.06788 54.1994)
			(xy 197.05968 54.1994) (xy 197.05968 54.19121) (xy 197.05968 54.18301) (xy 197.05968 54.17482) (xy 197.05149 54.17482)
			(xy 197.05149 54.16662) (xy 197.05149 54.15843) (xy 197.05149 54.15023) (xy 197.0433 54.15023) (xy 197.0433 54.14204)
			(xy 197.0433 54.13385) (xy 197.0351 54.13385) (xy 197.0351 54.12565) (xy 197.0351 54.11746) (xy 197.0351 54.10926)
			(xy 197.0269 54.10926) (xy 197.0269 54.10107) (xy 197.0269 54.09287) (xy 197.01871 54.09287) (xy 197.01871 54.08468)
			(xy 197.01871 54.07649) (xy 197.01871 54.06829) (xy 197.01052 54.06829) (xy 197.01052 54.0601) (xy 197.01052 54.0519)
			(xy 197.00232 54.0519) (xy 197.00232 54.0437) (xy 197.00232 54.03551) (xy 196.99413 54.03551) (xy 196.99413 54.02732)
			(xy 196.99413 54.01912) (xy 196.99413 54.01093) (xy 196.98593 54.01093) (xy 196.98593 54.00273) (xy 196.98593 53.99454)
			(xy 196.97774 53.99454) (xy 196.97774 53.98634) (xy 196.97774 53.97815) (xy 196.96954 53.97815) (xy 196.96954 53.96996)
			(xy 196.96954 53.96176) (xy 196.96135 53.96176) (xy 196.96135 53.95357) (xy 196.96135 53.94537) (xy 196.96135 53.93718)
			(xy 196.95315 53.93718) (xy 196.95315 53.92898) (xy 196.95315 53.92079) (xy 196.94496 53.92079) (xy 196.94496 53.91259)
			(xy 196.94496 53.9044) (xy 196.93676 53.9044) (xy 196.93676 53.8962) (xy 196.93676 53.88801) (xy 196.92857 53.88801)
			(xy 196.92857 53.87982) (xy 196.92857 53.87162) (xy 196.92038 53.87162) (xy 196.92038 53.86343) (xy 196.92038 53.85523)
			(xy 196.91218 53.85523) (xy 196.91218 53.84704) (xy 196.91218 53.83884) (xy 196.90399 53.83884) (xy 196.90399 53.83065)
			(xy 196.90399 53.82246) (xy 196.89579 53.82246) (xy 196.89579 53.81426) (xy 196.89579 53.80606) (xy 196.8876 53.80606)
			(xy 196.8876 53.79787) (xy 196.8876 53.78968) (xy 196.8794 53.78968) (xy 196.8794 53.78148) (xy 196.87121 53.78148)
			(xy 196.87121 53.77329) (xy 196.87121 53.76509) (xy 196.86302 53.76509) (xy 196.86302 53.7569) (xy 196.86302 53.7487)
			(xy 196.85482 53.7487) (xy 196.85482 53.74051) (xy 196.85482 53.73231) (xy 196.84663 53.73231) (xy 196.84663 53.72412)
			(xy 196.84663 53.71593) (xy 196.83843 53.71593) (xy 196.83843 53.70773) (xy 196.83023 53.70773) (xy 196.83023 53.69954)
			(xy 196.83023 53.69134) (xy 196.82204 53.69134) (xy 196.82204 53.68315) (xy 196.82204 53.67495) (xy 196.81385 53.67495)
			(xy 196.81385 53.66676) (xy 196.80565 53.66676) (xy 196.80565 53.65857) (xy 196.80565 53.65037) (xy 196.79746 53.65037)
			(xy 196.79746 53.64218) (xy 196.79746 53.63398) (xy 196.78926 53.63398) (xy 196.78926 53.62579) (xy 196.78107 53.62579)
			(xy 196.78107 53.61759) (xy 196.78107 53.6094) (xy 196.77287 53.6094) (xy 196.77287 53.6012) (xy 196.77287 53.59301)
			(xy 196.76468 53.59301) (xy 196.76468 53.58482) (xy 196.75649 53.58482) (xy 196.75649 53.57662) (xy 196.75649 53.56843)
			(xy 196.74829 53.56843) (xy 196.74829 53.56023) (xy 196.7401 53.56023) (xy 196.7401 53.55204) (xy 196.7401 53.54384)
			(xy 196.7319 53.54384) (xy 196.7319 53.53565) (xy 196.72371 53.53565) (xy 196.72371 53.52745) (xy 196.72371 53.51926)
			(xy 196.71552 53.51926) (xy 196.71552 53.51106) (xy 196.70732 53.51106) (xy 196.70732 53.50287) (xy 196.70732 53.49467)
			(xy 196.69913 53.49467) (xy 196.69913 53.48648) (xy 196.69093 53.48648) (xy 196.69093 53.47829) (xy 196.69093 53.47009)
			(xy 196.68274 53.47009) (xy 196.68274 53.4619) (xy 196.67454 53.4619) (xy 196.67454 53.4537) (xy 196.66635 53.4537)
			(xy 196.66635 53.44551) (xy 196.66635 53.43731) (xy 196.65815 53.43731) (xy 196.65815 53.42912) (xy 196.64996 53.42912)
			(xy 196.64996 53.42092) (xy 196.64996 53.41273) (xy 196.64176 53.41273) (xy 196.64176 53.40453) (xy 196.63357 53.40453)
			(xy 196.63357 53.39634) (xy 196.62538 53.39634) (xy 196.62538 53.38815) (xy 196.62538 53.37995) (xy 196.61718 53.37995)
			(xy 196.61718 53.37176) (xy 196.60899 53.37176) (xy 196.60899 53.36356) (xy 196.60079 53.36356) (xy 196.60079 53.35537)
			(xy 196.5926 53.35537) (xy 196.5926 53.34718) (xy 196.5926 53.33898) (xy 196.5844 53.33898) (xy 196.5844 53.33079)
			(xy 196.57621 53.33079) (xy 196.57621 53.32259) (xy 196.56801 53.32259) (xy 196.56801 53.31439) (xy 196.56801 53.3062)
			(xy 196.55982 53.3062) (xy 196.55982 53.29801) (xy 196.55162 53.29801) (xy 196.55162 53.28981) (xy 196.54343 53.28981)
			(xy 196.54343 53.28162) (xy 196.53523 53.28162) (xy 196.53523 53.27342) (xy 196.52704 53.27342) (xy 196.52704 53.26523)
			(xy 196.52704 53.25703) (xy 196.51885 53.25703) (xy 196.51885 53.24884) (xy 196.51065 53.24884) (xy 196.51065 53.24065)
			(xy 196.50246 53.24065) (xy 196.50246 53.23245) (xy 196.49426 53.23245) (xy 196.49426 53.22426) (xy 196.48607 53.22426)
			(xy 196.48607 53.21606) (xy 196.48607 53.20787) (xy 196.47787 53.20787) (xy 196.47787 53.19967) (xy 196.46968 53.19967)
			(xy 196.46968 53.19148) (xy 196.46148 53.19148) (xy 196.46148 53.18328) (xy 196.45329 53.18328) (xy 196.45329 53.17509)
			(xy 196.4451 53.17509) (xy 196.4451 53.16689) (xy 196.4369 53.16689) (xy 196.4369 53.1587) (xy 196.42871 53.1587)
			(xy 196.42871 53.15051) (xy 196.42051 53.15051) (xy 196.42051 53.14231) (xy 196.42051 53.13412) (xy 196.41232 53.13412)
			(xy 196.41232 53.12592) (xy 196.40412 53.12592) (xy 196.40412 53.11773) (xy 196.39593 53.11773) (xy 196.39593 53.10953)
			(xy 196.38773 53.10953) (xy 196.38773 53.10134) (xy 196.37954 53.10134) (xy 196.37954 53.09315) (xy 196.37135 53.09315)
			(xy 196.37135 53.08495) (xy 196.36315 53.08495) (xy 196.36315 53.07675) (xy 196.35496 53.07675) (xy 196.35496 53.06856)
			(xy 196.34676 53.06856) (xy 196.34676 53.06037) (xy 196.33857 53.06037) (xy 196.33857 53.05217) (xy 196.33037 53.05217)
			(xy 196.33037 53.04398) (xy 196.32218 53.04398) (xy 196.32218 53.03578) (xy 196.31398 53.03578) (xy 196.31398 53.02759)
			(xy 196.30579 53.02759) (xy 196.30579 53.01939) (xy 196.29759 53.01939) (xy 196.29759 53.0112) (xy 196.2894 53.0112)
			(xy 196.2894 53.00301) (xy 196.28121 53.00301) (xy 196.28121 52.99481) (xy 196.27301 52.99481) (xy 196.27301 52.98662)
			(xy 196.26482 52.98662) (xy 196.26482 52.97842) (xy 196.25662 52.97842) (xy 196.25662 52.97023) (xy 196.24843 52.97023)
			(xy 196.24843 52.96203) (xy 196.23204 52.96203) (xy 196.23204 52.95384) (xy 196.22385 52.95384) (xy 196.22385 52.94564)
			(xy 196.21565 52.94564) (xy 196.21565 52.93745) (xy 196.20746 52.93745) (xy 196.20746 52.92926) (xy 196.19926 52.92926)
			(xy 196.19926 52.92106) (xy 196.19107 52.92106) (xy 196.19107 52.91287) (xy 196.18287 52.91287) (xy 196.18287 52.90467)
			(xy 196.17468 52.90467) (xy 196.17468 52.89648) (xy 196.16648 52.89648) (xy 196.16648 52.88828) (xy 196.15009 52.88828)
			(xy 196.15009 52.88009) (xy 196.1419 52.88009) (xy 196.1419 52.87189) (xy 196.13371 52.87189) (xy 196.13371 52.8637)
			(xy 196.12551 52.8637) (xy 196.12551 52.85551) (xy 196.11732 52.85551) (xy 196.11732 52.84731) (xy 196.10093 52.84731)
			(xy 196.10093 52.83911) (xy 196.09273 52.83911) (xy 196.09273 52.83092) (xy 196.08454 52.83092) (xy 196.08454 52.82273)
			(xy 196.07634 52.82273) (xy 196.07634 52.81453) (xy 196.06815 52.81453) (xy 196.06815 52.80634) (xy 196.05176 52.80634)
			(xy 196.05176 52.79814) (xy 196.04356 52.79814) (xy 196.04356 52.78995) (xy 196.03537 52.78995) (xy 196.03537 52.78175)
			(xy 196.01898 52.78175) (xy 196.01898 52.77356) (xy 196.01079 52.77356) (xy 196.01079 52.76536) (xy 196.00259 52.76536)
			(xy 196.00259 52.75717) (xy 195.9944 52.75717) (xy 195.9944 52.74898) (xy 195.97801 52.74898) (xy 195.97801 52.74078)
			(xy 195.96981 52.74078) (xy 195.96981 52.73259) (xy 195.95343 52.73259) (xy 195.95343 52.72439) (xy 195.94523 52.72439)
			(xy 195.94523 52.7162) (xy 195.93704 52.7162) (xy 195.93704 52.708) (xy 195.92065 52.708) (xy 195.92065 52.69981)
			(xy 195.91245 52.69981) (xy 195.91245 52.69162) (xy 195.90426 52.69162) (xy 195.90426 52.68342) (xy 195.88787 52.68342)
			(xy 195.88787 52.67522) (xy 195.87968 52.67522) (xy 195.87968 52.66703) (xy 195.86329 52.66703) (xy 195.86329 52.65884)
			(xy 195.85509 52.65884) (xy 195.85509 52.65064) (xy 195.8387 52.65064) (xy 195.8387 52.64245) (xy 195.83051 52.64245)
			(xy 195.83051 52.63425) (xy 195.81412 52.63425) (xy 195.81412 52.62606) (xy 195.80592 52.62606) (xy 195.80592 52.61787)
			(xy 195.78954 52.61787) (xy 195.78954 52.60967) (xy 195.77315 52.60967) (xy 195.77315 52.60148) (xy 195.76495 52.60148)
			(xy 195.76495 52.59328) (xy 195.74856 52.59328) (xy 195.74856 52.58509) (xy 195.74037 52.58509) (xy 195.74037 52.57689)
			(xy 195.72398 52.57689) (xy 195.72398 52.5687) (xy 195.70759 52.5687) (xy 195.70759 52.5605) (xy 195.6994 52.5605)
			(xy 195.6994 52.55231) (xy 195.68301 52.55231) (xy 195.68301 52.54411) (xy 195.66662 52.54411) (xy 195.66662 52.53592)
			(xy 195.65023 52.53592) (xy 195.65023 52.52772) (xy 195.64204 52.52772) (xy 195.64204 52.51953) (xy 195.62564 52.51953)
			(xy 195.62564 52.51134) (xy 195.60926 52.51134) (xy 195.60926 52.50314) (xy 195.59287 52.50314) (xy 195.59287 52.49495)
			(xy 195.57648 52.49495) (xy 195.57648 52.48675) (xy 195.56828 52.48675) (xy 195.56828 52.47856) (xy 195.5437 52.47856)
			(xy 195.5437 52.47036) (xy 195.53551 52.47036) (xy 195.53551 52.46217) (xy 195.51912 52.46217) (xy 195.51912 52.45397)
			(xy 195.49454 52.45397) (xy 195.49454 52.44578) (xy 195.47815 52.44578) (xy 195.47815 52.43759) (xy 195.46995 52.43759)
			(xy 195.46995 52.42939) (xy 195.45356 52.42939) (xy 195.45356 52.4212) (xy 195.42898 52.4212) (xy 195.42898 52.413)
			(xy 195.41259 52.413) (xy 195.41259 52.40481) (xy 195.3962 52.40481) (xy 195.3962 52.39661) (xy 195.37981 52.39661)
			(xy 195.37981 52.38842) (xy 195.36342 52.38842) (xy 195.36342 52.38022) (xy 195.33884 52.38022) (xy 195.33884 52.37203)
			(xy 195.32245 52.37203) (xy 195.32245 52.36384) (xy 195.30606 52.36384) (xy 195.30606 52.35564) (xy 195.28148 52.35564)
			(xy 195.28148 52.34744) (xy 195.26509 52.34744) (xy 195.26509 52.33925) (xy 195.2405 52.33925) (xy 195.2405 52.33106)
			(xy 195.21592 52.33106) (xy 195.21592 52.32286) (xy 195.19953 52.32286) (xy 195.19953 52.31467) (xy 195.17495 52.31467)
			(xy 195.17495 52.30647) (xy 195.15037 52.30647) (xy 195.15037 52.29828) (xy 195.12578 52.29828) (xy 195.12578 52.29008)
			(xy 195.10939 52.29008) (xy 195.10939 52.28189) (xy 195.08481 52.28189) (xy 195.08481 52.2737) (xy 195.06023 52.2737)
			(xy 195.06023 52.2655) (xy 195.02745 52.2655) (xy 195.02745 52.25731) (xy 195.00286 52.25731) (xy 195.00286 52.24911)
			(xy 194.97828 52.24911) (xy 194.97828 52.24092) (xy 194.9455 52.24092) (xy 194.9455 52.23272) (xy 194.92092 52.23272)
			(xy 194.92092 52.22453) (xy 194.88814 52.22453) (xy 194.88814 52.21633) (xy 194.85536 52.21633) (xy 194.85536 52.20814)
			(xy 194.82259 52.20814) (xy 194.82259 52.19995) (xy 194.78981 52.19995) (xy 194.78981 52.19175) (xy 194.74884 52.19175)
			(xy 194.74884 52.18356) (xy 194.70786 52.18356) (xy 194.70786 52.17536) (xy 194.66689 52.17536) (xy 194.66689 52.16717)
			(xy 194.61772 52.16717) (xy 194.61772 52.15897) (xy 194.56856 52.15897) (xy 194.56856 52.15078) (xy 194.503 52.15078)
			(xy 194.503 52.14258) (xy 194.43745 52.14258) (xy 194.43745 52.13439) (xy 194.36369 52.13439) (xy 194.36369 52.1262)
			(xy 194.24078 52.1262) (xy 194.24078 52.118) (xy 193.93758 52.118) (xy 193.93758 52.1262) (xy 193.81466 52.1262)
			(xy 193.81466 52.13439) (xy 193.73272 52.13439) (xy 193.73272 52.14258) (xy 193.66716 52.14258) (xy 193.66716 52.15078)
			(xy 193.618 52.15078) (xy 193.618 52.15897) (xy 193.56063 52.15897) (xy 193.56063 52.16717) (xy 193.51147 52.16717)
			(xy 193.51147 52.17536) (xy 193.4705 52.17536) (xy 193.4705 52.18356) (xy 193.42952 52.18356) (xy 193.42952 52.19175)
			(xy 193.38855 52.19175) (xy 193.38855 52.19995) (xy 193.35577 52.19995) (xy 193.35577 52.20814) (xy 193.32299 52.20814)
			(xy 193.32299 52.21633) (xy 193.29021 52.21633) (xy 193.29021 52.22453) (xy 193.25744 52.22453) (xy 193.25744 52.23272)
			(xy 193.23286 52.23272) (xy 193.23286 52.24092) (xy 193.20008 52.24092) (xy 193.20008 52.24911) (xy 193.17549 52.24911)
			(xy 193.17549 52.25731) (xy 193.15091 52.25731) (xy 193.15091 52.2655) (xy 193.11813 52.2655) (xy 193.11813 52.2737)
			(xy 193.09355 52.2737) (xy 193.09355 52.28189) (xy 193.06896 52.28189) (xy 193.06896 52.29008) (xy 193.04438 52.29008)
			(xy 193.04438 52.29828) (xy 193.02799 52.29828) (xy 193.02799 52.30647) (xy 193.00341 52.30647) (xy 193.00341 52.31467)
			(xy 192.97883 52.31467) (xy 192.97883 52.32286) (xy 192.95424 52.32286) (xy 192.95424 52.33106) (xy 192.93785 52.33106)
			(xy 192.93785 52.33925) (xy 192.91327 52.33925) (xy 192.91327 52.34744) (xy 192.89688 52.34744) (xy 192.89688 52.35564)
			(xy 192.8723 52.35564) (xy 192.8723 52.36384) (xy 192.85591 52.36384) (xy 192.85591 52.37203) (xy 192.83952 52.37203)
			(xy 192.83952 52.38022) (xy 192.81494 52.38022) (xy 192.81494 52.38842) (xy 192.79855 52.38842) (xy 192.79855 52.39661)
			(xy 192.78216 52.39661) (xy 192.78216 52.40481) (xy 192.76577 52.40481) (xy 192.76577 52.413) (xy 192.74119 52.413)
			(xy 192.74119 52.4212) (xy 192.72479 52.4212) (xy 192.72479 52.42939) (xy 192.70841 52.42939) (xy 192.70841 52.43759)
			(xy 192.69202 52.43759) (xy 192.69202 52.44578) (xy 192.67563 52.44578) (xy 192.67563 52.45397) (xy 192.65924 52.45397)
			(xy 192.65924 52.46217) (xy 192.64285 52.46217) (xy 192.64285 52.47036) (xy 192.62646 52.47036) (xy 192.62646 52.47856)
			(xy 192.61007 52.47856) (xy 192.61007 52.48675) (xy 192.59368 52.48675) (xy 192.59368 52.49495) (xy 192.58549 52.49495)
			(xy 192.58549 52.50314) (xy 192.5691 52.50314) (xy 192.5691 52.51134) (xy 192.55271 52.51134) (xy 192.55271 52.51953)
			(xy 192.53632 52.51953) (xy 192.53632 52.52772) (xy 192.51993 52.52772) (xy 192.51993 52.53592) (xy 192.51174 52.53592)
			(xy 192.51174 52.54411) (xy 192.49535 52.54411) (xy 192.49535 52.55231) (xy 192.47896 52.55231) (xy 192.47896 52.5605)
			(xy 192.47077 52.5605) (xy 192.47077 52.5687) (xy 192.45438 52.5687) (xy 192.45438 52.57689) (xy 192.43799 52.57689)
			(xy 192.43799 52.58509) (xy 192.42979 52.58509) (xy 192.42979 52.59328) (xy 192.4134 52.59328) (xy 192.4134 52.60148)
			(xy 192.39702 52.60148) (xy 192.39702 52.60967) (xy 192.38882 52.60967) (xy 192.38882 52.61787) (xy 192.37243 52.61787)
			(xy 192.37243 52.62606) (xy 192.36424 52.62606) (xy 192.36424 52.63425) (xy 192.34785 52.63425) (xy 192.34785 52.64245)
			(xy 192.33965 52.64245) (xy 192.33965 52.65064) (xy 192.32327 52.65064) (xy 192.32327 52.65884) (xy 192.31507 52.65884)
			(xy 192.31507 52.66703) (xy 192.29868 52.66703) (xy 192.29868 52.67522) (xy 192.29049 52.67522) (xy 192.29049 52.68342)
			(xy 192.2741 52.68342) (xy 192.2741 52.69162) (xy 192.2659 52.69162) (xy 192.2659 52.69981) (xy 192.25771 52.69981)
			(xy 192.25771 52.708) (xy 192.24132 52.708) (xy 192.24132 52.7162) (xy 192.23313 52.7162) (xy 192.23313 52.72439)
			(xy 192.21674 52.72439) (xy 192.21674 52.73259) (xy 192.20854 52.73259) (xy 192.20854 52.74078) (xy 192.20035 52.74078)
			(xy 192.20035 52.74898) (xy 192.18396 52.74898) (xy 192.18396 52.75717) (xy 192.17576 52.75717) (xy 192.17576 52.76536)
			(xy 192.16757 52.76536) (xy 192.16757 52.77356) (xy 192.15118 52.77356) (xy 192.15118 52.78175) (xy 192.14298 52.78175)
			(xy 192.14298 52.78995) (xy 192.13479 52.78995) (xy 192.13479 52.79814) (xy 192.1266 52.79814) (xy 192.1266 52.80634)
			(xy 192.11021 52.80634) (xy 192.11021 52.81453) (xy 192.10201 52.81453) (xy 192.10201 52.82273) (xy 192.09382 52.82273)
			(xy 192.09382 52.83092) (xy 192.08563 52.83092) (xy 192.08563 52.83911) (xy 192.06924 52.83911) (xy 192.06924 52.84731)
			(xy 192.06104 52.84731) (xy 192.06104 52.85551) (xy 192.05285 52.85551) (xy 192.05285 52.8637) (xy 192.04465 52.8637)
			(xy 192.04465 52.87189) (xy 192.03646 52.87189) (xy 192.03646 52.88009) (xy 192.02007 52.88009) (xy 192.02007 52.88828)
			(xy 192.01188 52.88828) (xy 192.01188 52.89648) (xy 192.00368 52.89648) (xy 192.00368 52.90467) (xy 191.99548 52.90467)
			(xy 191.99548 52.91287) (xy 191.98729 52.91287) (xy 191.98729 52.92106) (xy 191.9791 52.92106) (xy 191.9791 52.92926)
			(xy 191.9709 52.92926) (xy 191.9709 52.93745) (xy 191.96271 52.93745) (xy 191.96271 52.94564) (xy 191.94632 52.94564)
			(xy 191.94632 52.95384) (xy 191.93812 52.95384) (xy 191.93812 52.96203) (xy 191.92993 52.96203) (xy 191.92993 52.97023)
			(xy 191.92174 52.97023) (xy 191.92174 52.97842) (xy 191.91354 52.97842) (xy 191.91354 52.98662) (xy 191.90534 52.98662)
			(xy 191.90534 52.99481) (xy 191.89715 52.99481) (xy 191.89715 53.00301) (xy 191.88896 53.00301) (xy 191.88896 53.0112)
			(xy 191.88076 53.0112) (xy 191.88076 53.01939) (xy 191.87257 53.01939) (xy 191.87257 53.02759) (xy 191.86437 53.02759)
			(xy 191.86437 53.03578) (xy 191.85618 53.03578) (xy 191.85618 53.04398) (xy 191.84798 53.04398) (xy 191.84798 53.05217)
			(xy 191.83979 53.05217) (xy 191.83979 53.06037) (xy 191.8316 53.06037) (xy 191.8316 53.06856) (xy 191.8234 53.06856)
			(xy 191.8234 53.07675) (xy 191.81521 53.07675) (xy 191.81521 53.08495) (xy 191.80701 53.08495) (xy 191.80701 53.09315)
			(xy 191.79882 53.09315) (xy 191.79882 53.10134) (xy 191.79063 53.10134) (xy 191.79063 53.10953) (xy 191.78243 53.10953)
			(xy 191.78243 53.11773) (xy 191.77424 53.11773) (xy 191.77424 53.12592) (xy 191.76604 53.12592) (xy 191.76604 53.13412)
			(xy 191.75784 53.13412) (xy 191.75784 53.14231) (xy 191.74965 53.14231) (xy 191.74965 53.15051) (xy 191.74965 53.1587)
			(xy 191.74146 53.1587) (xy 191.74146 53.16689) (xy 191.73326 53.16689) (xy 191.73326 53.17509) (xy 191.72507 53.17509)
			(xy 191.72507 53.18328) (xy 191.71687 53.18328) (xy 191.71687 53.19148) (xy 191.70868 53.19148) (xy 191.70868 53.19967)
			(xy 191.70048 53.19967) (xy 191.70048 53.20787) (xy 191.69229 53.20787) (xy 191.69229 53.21606) (xy 191.6841 53.21606)
			(xy 191.6841 53.22426) (xy 191.6841 53.23245) (xy 191.6759 53.23245) (xy 191.6759 53.24065) (xy 191.66771 53.24065)
			(xy 191.66771 53.24884) (xy 191.65951 53.24884) (xy 191.65951 53.25703) (xy 191.65132 53.25703) (xy 191.65132 53.26523)
			(xy 191.64312 53.26523) (xy 191.64312 53.27342) (xy 191.64312 53.28162) (xy 191.63493 53.28162) (xy 191.63493 53.28981)
			(xy 191.62673 53.28981) (xy 191.62673 53.29801) (xy 191.61854 53.29801) (xy 189.02908 53.29801) (xy 189.02908 53.28981)
			(xy 189.02908 53.28162) (xy 189.02908 53.27342) (xy 189.02908 53.26523) (xy 189.02908 53.25703) (xy 189.02908 53.24884)
			(xy 189.02908 53.24065) (xy 189.02908 53.23245) (xy 189.02908 53.22426) (xy 189.02908 53.21606) (xy 189.02908 53.20787)
			(xy 189.02908 53.19967) (xy 189.02908 53.19148) (xy 189.02908 53.18328) (xy 189.02908 53.17509) (xy 189.02908 53.16689)
			(xy 189.02908 53.1587) (xy 189.02908 53.15051) (xy 189.02908 53.14231) (xy 189.02908 53.13412) (xy 189.02908 53.12592)
			(xy 189.02908 53.11773) (xy 189.02908 53.10953) (xy 189.02908 53.10134) (xy 189.02908 53.09315) (xy 189.02908 53.08495)
			(xy 189.02908 53.07675) (xy 189.02908 53.06856) (xy 189.02908 53.06037) (xy 189.02908 53.05217) (xy 189.02908 53.04398)
			(xy 189.02908 53.03578) (xy 189.02908 53.02759) (xy 189.02908 53.01939) (xy 189.02908 53.0112) (xy 189.02908 53.00301)
			(xy 189.02908 52.99481) (xy 189.02908 52.98662) (xy 189.02908 52.97842) (xy 189.02908 52.97023) (xy 189.02908 52.96203)
			(xy 189.02908 52.95384) (xy 189.02908 52.94564) (xy 189.02908 52.93745) (xy 189.02908 52.92926) (xy 189.02908 52.92106)
			(xy 189.02908 52.91287) (xy 189.02908 52.90467) (xy 189.02908 52.89648) (xy 189.02908 52.88828) (xy 189.02908 52.88009)
			(xy 189.02908 52.87189) (xy 189.02908 52.8637) (xy 189.02908 52.85551) (xy 189.02908 52.84731) (xy 189.02908 52.83911)
			(xy 189.02908 52.83092) (xy 189.02908 52.82273) (xy 189.02908 52.81453) (xy 189.02908 52.80634) (xy 189.02908 52.79814)
			(xy 189.02908 52.78995) (xy 189.02908 52.78175) (xy 189.02908 52.77356) (xy 189.02908 52.76536) (xy 189.02908 52.75717)
			(xy 189.02908 52.74898) (xy 189.02908 52.74078) (xy 189.02908 52.73259) (xy 189.02908 52.72439) (xy 189.02908 52.7162)
			(xy 189.02908 52.708) (xy 189.02908 52.69981) (xy 189.02908 52.69162) (xy 189.02908 52.68342) (xy 189.02908 52.67522)
			(xy 189.02908 52.66703) (xy 189.02908 52.65884) (xy 189.02908 52.65064) (xy 189.02908 52.64245) (xy 189.02908 52.63425)
			(xy 189.02908 52.62606) (xy 189.02908 52.61787) (xy 189.02908 52.60967) (xy 189.02908 52.60148) (xy 189.02908 52.59328)
			(xy 189.02908 52.58509) (xy 189.02908 52.57689) (xy 189.02908 52.5687) (xy 189.02908 52.5605) (xy 189.02908 52.55231)
			(xy 189.02908 52.54411) (xy 189.02908 52.53592) (xy 189.02908 52.52772) (xy 189.02908 52.51953) (xy 189.02908 52.51134)
			(xy 189.02908 52.50314) (xy 189.02908 52.49495) (xy 189.02908 52.48675) (xy 189.02908 52.47856) (xy 189.02908 52.47036)
			(xy 189.02908 52.46217) (xy 189.02908 52.45397) (xy 189.02908 52.44578) (xy 189.02908 52.43759) (xy 189.02908 52.42939)
			(xy 189.02908 52.4212) (xy 189.02908 52.413) (xy 189.02908 52.40481) (xy 189.02908 52.39661) (xy 189.02908 52.38842)
			(xy 189.02908 52.38022) (xy 189.02908 52.37203) (xy 189.02908 52.36384) (xy 189.02908 52.35564) (xy 189.02908 52.34744)
			(xy 189.02908 52.33925) (xy 189.02908 52.33106) (xy 189.02908 52.32286) (xy 189.02908 52.31467) (xy 189.02908 52.30647)
			(xy 189.02908 52.29828) (xy 189.02908 52.29008) (xy 189.02908 52.28189) (xy 189.02908 52.2737) (xy 189.02908 52.2655)
			(xy 189.02908 52.25731) (xy 189.02908 52.24911) (xy 189.02908 52.24092) (xy 189.02908 52.23272) (xy 189.02908 52.22453)
			(xy 189.02908 52.21633) (xy 189.02908 52.20814) (xy 189.02908 52.19995) (xy 189.02908 52.19175) (xy 189.02908 52.18356)
			(xy 189.02908 52.17536) (xy 189.02908 52.16717) (xy 189.02908 52.15897) (xy 189.02908 52.15078) (xy 189.02908 52.14258)
			(xy 189.02908 52.13439) (xy 189.02908 52.1262) (xy 189.02908 52.118) (xy 189.02908 52.1098) (xy 189.02908 52.10161)
			(xy 189.02908 52.09342) (xy 189.02908 52.08522) (xy 189.02908 52.07703) (xy 189.02908 52.06883) (xy 189.02908 52.06064)
			(xy 189.02908 52.05244) (xy 189.02908 52.04425) (xy 189.02908 52.03606) (xy 189.02908 52.02786) (xy 189.02908 52.01967)
			(xy 189.02908 52.01147) (xy 189.02908 52.00328) (xy 189.02908 51.99508) (xy 189.02908 51.98689) (xy 189.02908 51.97869)
			(xy 189.02908 51.9705) (xy 189.02908 51.9623) (xy 189.02908 51.95411) (xy 189.02908 51.94592) (xy 189.02908 51.93772)
			(xy 189.02908 51.92953) (xy 189.02908 51.92133) (xy 189.02908 51.91314) (xy 189.02908 51.90494) (xy 189.02908 51.89675)
			(xy 189.02908 51.88856) (xy 189.02908 51.88036) (xy 189.02908 51.87216) (xy 189.02908 51.86397) (xy 189.02908 51.85578)
			(xy 189.02908 51.84758) (xy 189.02908 51.83939) (xy 189.02908 51.83119) (xy 189.02908 51.823) (xy 189.02908 51.8148)
			(xy 189.02908 51.80661) (xy 189.02908 51.79841) (xy 189.02908 51.79022) (xy 189.02908 51.78203) (xy 189.02908 51.77383)
			(xy 189.02908 51.76564) (xy 189.02908 51.75744) (xy 189.02908 51.74925) (xy 189.02908 51.74105) (xy 189.02908 51.73286)
			(xy 189.02908 51.72466) (xy 189.02908 51.71647) (xy 189.02908 51.70828) (xy 189.02908 51.70008) (xy 189.02908 51.69189)
			(xy 189.02908 51.68369) (xy 189.02908 51.6755) (xy 189.02908 51.6673) (xy 189.02908 51.65911) (xy 189.02908 51.65091)
			(xy 189.02908 51.64272) (xy 189.02908 51.63452) (xy 189.02908 51.62633) (xy 189.02908 51.61814) (xy 189.02908 51.60994)
			(xy 189.02908 51.60175) (xy 189.02908 51.59355) (xy 189.02908 51.58536) (xy 189.02908 51.57716) (xy 189.02908 51.56897)
			(xy 189.02908 51.56077) (xy 189.02908 51.55258) (xy 189.02908 51.54439) (xy 189.02908 51.53619) (xy 189.02908 51.52799)
			(xy 189.02908 51.5198) (xy 189.02908 51.51161) (xy 189.02908 51.50341) (xy 189.02908 51.49522) (xy 189.02908 51.48702)
			(xy 189.02908 51.47883) (xy 189.02908 51.47064) (xy 189.02908 51.46244) (xy 189.02908 51.45424) (xy 189.02908 51.44605)
			(xy 189.03727 51.44605) (xy 189.03727 51.43786) (xy 199.37873 51.43786)
		)
		(stroke
			(width 0)
			(type default)
		)
		(fill yes)
		(layer "F.Cu")
	)
	(gr_rect
		(start 110.3216 154.6036)
		(end 112.8466 152.8786)
		(stroke
			(width 0)
			(type default)
		)
		(fill yes)
		(layer "F.Cu")
		(net "+12V_PCIE")
	)
	(gr_rect
		(start 110.4216 153.0786)
		(end 112.82896 145.6162)
		(stroke
			(width 0)
			(type default)
		)
		(fill yes)
		(layer "F.Cu")
		(net "+12V_PCIE")
	)
	(gr_rect
		(start 228.671425 128.841365)
		(end 230.571425 130.416375)
		(stroke
			(width 0)
			(type default)
		)
		(fill yes)
		(layer "F.Cu")
		(net "GND")
	)
	(gr_rect
		(start 230.57178 123.64102)
		(end 228.67178 122.06602)
		(stroke
			(width 0)
			(type default)
		)
		(fill yes)
		(layer "F.Cu")
		(net "GND")
	)
	(gr_rect
		(start 110.9716 154.6036)
		(end 112.8466 152.8786)
		(stroke
			(width 0)
			(type default)
		)
		(fill yes)
		(layer "B.Cu")
		(net "+12V_PCIE")
	)
	(gr_line
		(start 64.61719 49.4286)
		(end 64.61719 156.0786)
		(stroke
			(width 0.05)
			(type solid)
		)
		(layer "Edge.Cuts")
	)
	(gr_arc
		(start 64.61719 49.4286)
		(mid 64.691705 49.248705)
		(end 64.8716 49.17419)
		(stroke
			(width 0.05)
			(type solid)
		)
		(layer "Edge.Cuts")
	)
	(gr_line
		(start 64.8716 156.333)
		(end 79.8716 156.33301)
		(stroke
			(width 0.05)
			(type solid)
		)
		(layer "Edge.Cuts")
	)
	(gr_arc
		(start 64.8716 156.33301)
		(mid 64.691705 156.258495)
		(end 64.61719 156.0786)
		(stroke
			(width 0.05)
			(type solid)
		)
		(layer "Edge.Cuts")
	)
	(gr_line
		(start 64.8716 156.33301)
		(end 64.8716 156.333)
		(stroke
			(width 0.05)
			(type solid)
		)
		(layer "Edge.Cuts")
	)
	(gr_line
		(start 80.12601 148.08301)
		(end 97.96719 148.08301)
		(stroke
			(width 0.05)
			(type solid)
		)
		(layer "Edge.Cuts")
	)
	(gr_arc
		(start 80.12601 156.0786)
		(mid 80.051495 156.258495)
		(end 79.8716 156.33301)
		(stroke
			(width 0.05)
			(type solid)
		)
		(layer "Edge.Cuts")
	)
	(gr_line
		(start 80.12601 156.0786)
		(end 80.12601 148.08301)
		(stroke
			(width 0.05)
			(type solid)
		)
		(layer "Edge.Cuts")
	)
	(gr_line
		(start 97.96719 148.08301)
		(end 97.96719 156.0786)
		(stroke
			(width 0.05)
			(type solid)
		)
		(layer "Edge.Cuts")
	)
	(gr_line
		(start 98.2216 156.333)
		(end 106.2216 156.33301)
		(stroke
			(width 0.05)
			(type solid)
		)
		(layer "Edge.Cuts")
	)
	(gr_arc
		(start 98.2216 156.33301)
		(mid 98.041705 156.258495)
		(end 97.96719 156.0786)
		(stroke
			(width 0.05)
			(type solid)
		)
		(layer "Edge.Cuts")
	)
	(gr_line
		(start 98.2216 156.33301)
		(end 98.2216 156.333)
		(stroke
			(width 0.05)
			(type solid)
		)
		(layer "Edge.Cuts")
	)
	(gr_arc
		(start 106.47601 149.6536)
		(mid 108.0466 148.08301)
		(end 109.61719 149.6536)
		(stroke
			(width 0.05)
			(type solid)
		)
		(layer "Edge.Cuts")
	)
	(gr_arc
		(start 106.47601 156.0786)
		(mid 106.401495 156.258495)
		(end 106.2216 156.33301)
		(stroke
			(width 0.05)
			(type solid)
		)
		(layer "Edge.Cuts")
	)
	(gr_line
		(start 106.47601 156.0786)
		(end 106.47601 149.6536)
		(stroke
			(width 0.05)
			(type solid)
		)
		(layer "Edge.Cuts")
	)
	(gr_line
		(start 109.61719 149.6536)
		(end 109.61719 149.65474)
		(stroke
			(width 0.05)
			(type solid)
		)
		(layer "Edge.Cuts")
	)
	(gr_line
		(start 109.61719 149.65474)
		(end 109.61719 160.0786)
		(stroke
			(width 0.05)
			(type solid)
		)
		(layer "Edge.Cuts")
	)
	(gr_arc
		(start 109.691705 160.258495)
		(mid 109.636556 160.175958)
		(end 109.61719 160.0786)
		(stroke
			(width 0.05)
			(type solid)
		)
		(layer "Edge.Cuts")
	)
	(gr_line
		(start 109.691705 160.258495)
		(end 109.69171 160.25849)
		(stroke
			(width 0.05)
			(type solid)
		)
		(layer "Edge.Cuts")
	)
	(gr_line
		(start 109.69171 160.25849)
		(end 110.191708 160.758494)
		(stroke
			(width 0.05)
			(type solid)
		)
		(layer "Edge.Cuts")
	)
	(gr_arc
		(start 110.371598 160.83301)
		(mid 110.274241 160.813644)
		(end 110.191708 160.758494)
		(stroke
			(width 0.05)
			(type solid)
		)
		(layer "Edge.Cuts")
	)
	(gr_line
		(start 110.371598 160.83301)
		(end 110.3716 160.83301)
		(stroke
			(width 0.05)
			(type solid)
		)
		(layer "Edge.Cuts")
	)
	(gr_line
		(start 110.3716 160.83301)
		(end 120.571599 160.83301)
		(stroke
			(width 0.05)
			(type solid)
		)
		(layer "Edge.Cuts")
	)
	(gr_line
		(start 120.75149 160.75849)
		(end 121.251494 160.258492)
		(stroke
			(width 0.05)
			(type solid)
		)
		(layer "Edge.Cuts")
	)
	(gr_arc
		(start 120.751494 160.758496)
		(mid 120.668957 160.813645)
		(end 120.571599 160.83301)
		(stroke
			(width 0.05)
			(type solid)
		)
		(layer "Edge.Cuts")
	)
	(gr_line
		(start 120.751494 160.758496)
		(end 120.75149 160.75849)
		(stroke
			(width 0.05)
			(type solid)
		)
		(layer "Edge.Cuts")
	)
	(gr_arc
		(start 121.32601 153.1286)
		(mid 122.0216 152.43301)
		(end 122.71719 153.1286)
		(stroke
			(width 0.05)
			(type solid)
		)
		(layer "Edge.Cuts")
	)
	(gr_arc
		(start 121.32601 160.078602)
		(mid 121.306644 160.175959)
		(end 121.251494 160.258492)
		(stroke
			(width 0.05)
			(type solid)
		)
		(layer "Edge.Cuts")
	)
	(gr_line
		(start 121.32601 160.0786)
		(end 121.32601 153.1286)
		(stroke
			(width 0.05)
			(type solid)
		)
		(layer "Edge.Cuts")
	)
	(gr_line
		(start 121.32601 160.078602)
		(end 121.32601 160.0786)
		(stroke
			(width 0.05)
			(type solid)
		)
		(layer "Edge.Cuts")
	)
	(gr_line
		(start 122.71719 153.1286)
		(end 122.7172 153.1286)
		(stroke
			(width 0.05)
			(type solid)
		)
		(layer "Edge.Cuts")
	)
	(gr_line
		(start 122.7172 153.1286)
		(end 122.71719 160.0786)
		(stroke
			(width 0.05)
			(type solid)
		)
		(layer "Edge.Cuts")
	)
	(gr_arc
		(start 122.791705 160.258495)
		(mid 122.736556 160.175958)
		(end 122.71719 160.0786)
		(stroke
			(width 0.05)
			(type solid)
		)
		(layer "Edge.Cuts")
	)
	(gr_line
		(start 122.791705 160.258495)
		(end 122.79171 160.25849)
		(stroke
			(width 0.05)
			(type solid)
		)
		(layer "Edge.Cuts")
	)
	(gr_line
		(start 122.79171 160.25849)
		(end 123.291708 160.758494)
		(stroke
			(width 0.05)
			(type solid)
		)
		(layer "Edge.Cuts")
	)
	(gr_arc
		(start 123.471598 160.83301)
		(mid 123.374241 160.813644)
		(end 123.291708 160.758494)
		(stroke
			(width 0.05)
			(type solid)
		)
		(layer "Edge.Cuts")
	)
	(gr_line
		(start 123.471598 160.83301)
		(end 123.4716 160.83301)
		(stroke
			(width 0.05)
			(type solid)
		)
		(layer "Edge.Cuts")
	)
	(gr_line
		(start 123.4716 160.83301)
		(end 143.671599 160.83301)
		(stroke
			(width 0.05)
			(type solid)
		)
		(layer "Edge.Cuts")
	)
	(gr_line
		(start 143.85149 160.75849)
		(end 144.351484 160.258492)
		(stroke
			(width 0.05)
			(type solid)
		)
		(layer "Edge.Cuts")
	)
	(gr_arc
		(start 143.851494 160.758496)
		(mid 143.768957 160.813645)
		(end 143.671599 160.83301)
		(stroke
			(width 0.05)
			(type solid)
		)
		(layer "Edge.Cuts")
	)
	(gr_line
		(start 143.851494 160.758496)
		(end 143.85149 160.75849)
		(stroke
			(width 0.05)
			(type solid)
		)
		(layer "Edge.Cuts")
	)
	(gr_arc
		(start 144.426 160.078602)
		(mid 144.406633 160.175958)
		(end 144.351484 160.258492)
		(stroke
			(width 0.05)
			(type solid)
		)
		(layer "Edge.Cuts")
	)
	(gr_line
		(start 144.426 160.078602)
		(end 144.42601 160.0786)
		(stroke
			(width 0.05)
			(type solid)
		)
		(layer "Edge.Cuts")
	)
	(gr_line
		(start 144.42601 148.08301)
		(end 232.13062 148.08301)
		(stroke
			(width 0.05)
			(type solid)
		)
		(layer "Edge.Cuts")
	)
	(gr_line
		(start 144.42601 160.0786)
		(end 144.42601 148.08301)
		(stroke
			(width 0.05)
			(type solid)
		)
		(layer "Edge.Cuts")
	)
	(gr_line
		(start 232.13063 49.1742)
		(end 64.8716 49.17419)
		(stroke
			(width 0.05)
			(type solid)
		)
		(layer "Edge.Cuts")
	)
	(gr_line
		(start 232.130629 49.1742)
		(end 232.13063 49.1742)
		(stroke
			(width 0.05)
			(type solid)
		)
		(layer "Edge.Cuts")
	)
	(gr_arc
		(start 232.130629 49.1742)
		(mid 232.220563 49.211392)
		(end 232.25801 49.301225)
		(stroke
			(width 0.05)
			(type solid)
		)
		(layer "Edge.Cuts")
	)
	(gr_arc
		(start 232.258 147.955986)
		(mid 232.220556 148.045815)
		(end 232.13062 148.08301)
		(stroke
			(width 0.05)
			(type solid)
		)
		(layer "Edge.Cuts")
	)
	(gr_line
		(start 232.258 147.955986)
		(end 232.258011 147.955979)
		(stroke
			(width 0.05)
			(type solid)
		)
		(layer "Edge.Cuts")
	)
	(gr_line
		(start 232.258009 49.301221)
		(end 232.25801 49.301225)
		(stroke
			(width 0.05)
			(type solid)
		)
		(layer "Edge.Cuts")
	)
	(gr_arc
		(start 232.258009 49.301221)
		(mid 232.347817 49.338675)
		(end 232.38501 49.428603)
		(stroke
			(width 0.05)
			(type solid)
		)
		(layer "Edge.Cuts")
	)
	(gr_arc
		(start 232.38501 147.828599)
		(mid 232.347838 147.918547)
		(end 232.258011 147.955979)
		(stroke
			(width 0.05)
			(type solid)
		)
		(layer "Edge.Cuts")
	)
	(gr_line
		(start 232.38501 147.8286)
		(end 232.38501 49.428603)
		(stroke
			(width 0.05)
			(type solid)
		)
		(layer "Edge.Cuts")
	)
	(gr_line
		(start 232.38501 147.828599)
		(end 232.38501 147.8286)
		(stroke
			(width 0.05)
			(type solid)
		)
		(layer "Edge.Cuts")
	)
	(gr_text "www.timingcard.com"
		(at 140.07847 147.25301 360)
		(layer "F.Cu")
		(effects
			(font
				(size 2.032 2.032)
				(thickness 0.635)
			)
			(justify left bottom)
		)
	)
	(via
		(at 193.96421 139.2087)
		(size 5.08)
		(drill 3.0988)
		(layers "F.Cu" "B.Cu")
		(net "")
	)
	(via
		(at 104.4791 53.13362)
		(size 5.08)
		(drill 3.0988)
		(layers "F.Cu" "B.Cu")
		(net "")
	)
	(via
		(at 219.96421 139.2087)
		(size 5.08)
		(drill 3.0988)
		(layers "F.Cu" "B.Cu")
		(net "")
	)
	(via
		(at 219.96421 78.70869)
		(size 5.08)
		(drill 3.0988)
		(layers "F.Cu" "B.Cu")
		(net "")
	)
	(via
		(at 193.96421 78.70869)
		(size 5.08)
		(drill 3.0988)
		(layers "F.Cu" "B.Cu")
		(net "")
	)
	(via
		(at 164.97911 79.13361)
		(size 5.08)
		(drill 3.0988)
		(layers "F.Cu" "B.Cu")
		(net "")
	)
	(via
		(at 164.97911 53.13362)
		(size 5.08)
		(drill 3.0988)
		(layers "F.Cu" "B.Cu")
		(net "")
	)
	(via
		(at 104.4791 79.13361)
		(size 5.08)
		(drill 3.0988)
		(layers "F.Cu" "B.Cu")
		(locked yes)
		(net "")
	)
	(segment
		(start 179.5216 97.3524)
		(end 179.5216 95.6662)
		(width 0.2032)
		(layer "F.Cu")
		(net "NetR183_2")
	)
	(via
		(at 179.5216 97.3524)
		(size 0.4064)
		(drill 0.2032)
		(layers "F.Cu" "B.Cu")
		(net "NetR183_2")
	)
	(segment
		(start 179.5216 97.3524)
		(end 179.5216 97.31116)
		(width 0.254)
		(layer "B.Cu")
		(net "NetR183_2")
	)
	(segment
		(start 183.19649 92.6412)
		(end 184.3216 92.6412)
		(width 0.254)
		(layer "B.Cu")
		(net "NetR183_2")
	)
	(segment
		(start 184.3216 92.6412)
		(end 184.3216 92.6412)
		(width 0.254)
		(layer "B.Cu")
		(net "NetR183_2")
	)
	(segment
		(start 183.19649 92.6662)
		(end 183.19649 92.6412)
		(width 0.254)
		(layer "B.Cu")
		(net "NetR183_2")
	)
	(segment
		(start 179.78297 97.04979)
		(end 179.78297 96.7412)
		(width 0.254)
		(layer "B.Cu")
		(net "NetR183_2")
	)
	(segment
		(start 184.3216 92.6412)
		(end 184.3341 92.6287)
		(width 0.254)
		(layer "B.Cu")
		(net "NetR183_2")
	)
	(segment
		(start 181.40797 95.1162)
		(end 181.47281 95.1162)
		(width 0.254)
		(layer "B.Cu")
		(net "NetR183_2")
	)
	(segment
		(start 181.47281 95.1162)
		(end 181.6216 94.96741)
		(width 0.254)
		(layer "B.Cu")
		(net "NetR183_2")
	)
	(segment
		(start 179.5216 97.31116)
		(end 179.78297 97.04979)
		(width 0.254)
		(layer "B.Cu")
		(net "NetR183_2")
	)
	(segment
		(start 181.6216 94.24109)
		(end 183.19649 92.6662)
		(width 0.254)
		(layer "B.Cu")
		(net "NetR183_2")
	)
	(segment
		(start 181.6216 94.96741)
		(end 181.6216 94.24109)
		(width 0.254)
		(layer "B.Cu")
		(net "NetR183_2")
	)
	(segment
		(start 179.78297 96.7412)
		(end 181.40797 95.1162)
		(width 0.254)
		(layer "B.Cu")
		(net "NetR183_2")
	)
	(segment
		(start 180.7216 95.6662)
		(end 180.79373 95.6662)
		(width 0.2032)
		(layer "F.Cu")
		(net "NetR129_2")
	)
	(segment
		(start 180.79373 97.52567)
		(end 180.79373 95.6662)
		(width 0.2032)
		(layer "F.Cu")
		(net "NetR129_2")
	)
	(via
		(at 180.79373 97.52567)
		(size 0.4064)
		(drill 0.2032)
		(layers "F.Cu" "B.Cu")
		(net "NetR129_2")
	)
	(segment
		(start 185.09781 95.04825)
		(end 185.2466 94.89946)
		(width 0.254)
		(layer "B.Cu")
		(net "NetR129_2")
	)
	(segment
		(start 180.79373 97.52567)
		(end 181.72182 96.59758)
		(width 0.254)
		(layer "B.Cu")
		(net "NetR129_2")
	)
	(segment
		(start 185.6696 94.1432)
		(end 187.1466 92.6662)
		(width 0.254)
		(layer "B.Cu")
		(net "NetR129_2")
	)
	(segment
		(start 181.72182 96.06513)
		(end 182.73871 95.04825)
		(width 0.254)
		(layer "B.Cu")
		(net "NetR129_2")
	)
	(segment
		(start 187.1466 92.6662)
		(end 187.1466 92.6412)
		(width 0.254)
		(layer "B.Cu")
		(net "NetR129_2")
	)
	(segment
		(start 181.72182 96.59758)
		(end 181.72182 96.06513)
		(width 0.254)
		(layer "B.Cu")
		(net "NetR129_2")
	)
	(segment
		(start 185.4196 94.1432)
		(end 185.6696 94.1432)
		(width 0.254)
		(layer "B.Cu")
		(net "NetR129_2")
	)
	(segment
		(start 182.73871 95.04825)
		(end 185.09781 95.04825)
		(width 0.254)
		(layer "B.Cu")
		(net "NetR129_2")
	)
	(segment
		(start 185.2466 94.3162)
		(end 185.4196 94.1432)
		(width 0.254)
		(layer "B.Cu")
		(net "NetR129_2")
	)
	(segment
		(start 185.2466 94.89946)
		(end 185.2466 94.3162)
		(width 0.254)
		(layer "B.Cu")
		(net "NetR129_2")
	)
	(segment
		(start 87.8216 54.95744)
		(end 87.8216 54.9162)
		(width 0.254)
		(layer "F.Cu")
		(net "NetR9_2")
	)
	(segment
		(start 87.7216 55.05744)
		(end 87.8216 54.95744)
		(width 0.254)
		(layer "F.Cu")
		(net "NetR9_2")
	)
	(segment
		(start 87.7216 56.5662)
		(end 87.7216 55.05744)
		(width 0.254)
		(layer "F.Cu")
		(net "NetR9_2")
	)
	(via
		(at 87.8216 54.9162)
		(size 0.4064)
		(drill 0.2032)
		(layers "F.Cu" "B.Cu")
		(net "NetR9_2")
	)
	(segment
		(start 88.6216 56.5662)
		(end 88.7946 56.3932)
		(width 0.254)
		(layer "B.Cu")
		(net "NetR9_2")
	)
	(segment
		(start 89.4966 55.6662)
		(end 89.4966 54.9162)
		(width 0.254)
		(layer "B.Cu")
		(net "NetR9_2")
	)
	(segment
		(start 89.4716 54.9162)
		(end 89.4966 54.9162)
		(width 0.254)
		(layer "B.Cu")
		(net "NetR9_2")
	)
	(segment
		(start 88.5966 56.5662)
		(end 88.6216 56.5662)
		(width 0.254)
		(layer "B.Cu")
		(net "NetR9_2")
	)
	(segment
		(start 88.7946 56.3682)
		(end 89.4966 55.6662)
		(width 0.254)
		(layer "B.Cu")
		(net "NetR9_2")
	)
	(segment
		(start 88.7946 56.3932)
		(end 88.7946 56.3682)
		(width 0.254)
		(layer "B.Cu")
		(net "NetR9_2")
	)
	(segment
		(start 87.8216 54.9162)
		(end 89.4716 54.9162)
		(width 0.254)
		(layer "B.Cu")
		(net "NetR9_2")
	)
	(segment
		(start 214.72081 124.43542)
		(end 215.62081 124.43542)
		(width 0.254)
		(layer "B.Cu")
		(net "NetR180_1")
	)
	(segment
		(start 214.03831 125.11792)
		(end 214.72081 124.43542)
		(width 0.254)
		(layer "B.Cu")
		(net "NetR180_1")
	)
	(segment
		(start 215.60331 125.36791)
		(end 215.62081 125.35041)
		(width 0.254)
		(layer "B.Cu")
		(net "NetR180_1")
	)
	(segment
		(start 215.62081 125.35041)
		(end 215.62081 124.43542)
		(width 0.254)
		(layer "B.Cu")
		(net "NetR180_1")
	)
	(segment
		(start 208.31727 125.6692)
		(end 208.35027 125.6362)
		(width 0.254)
		(layer "B.Cu")
		(net "NetR49_1")
	)
	(segment
		(start 208.4616 125.6362)
		(end 209.68715 125.6362)
		(width 0.254)
		(layer "B.Cu")
		(net "NetR49_1")
	)
	(segment
		(start 209.68715 125.6362)
		(end 209.91727 125.86632)
		(width 0.254)
		(layer "B.Cu")
		(net "NetR49_1")
	)
	(segment
		(start 208.31727 126.86632)
		(end 208.31727 125.6692)
		(width 0.254)
		(layer "B.Cu")
		(net "NetR49_1")
	)
	(segment
		(start 208.35027 125.6362)
		(end 208.4616 125.6362)
		(width 0.254)
		(layer "B.Cu")
		(net "NetR49_1")
	)
	(segment
		(start 214.2216 141.5162)
		(end 214.5592 141.5162)
		(width 0.762)
		(layer "F.Cu")
		(net "GNSS2_P5V0")
	)
	(segment
		(start 206.55919 141.2162)
		(end 206.55919 138.6612)
		(width 0.762)
		(layer "F.Cu")
		(net "GNSS2_P5V0")
	)
	(segment
		(start 206.55919 141.2162)
		(end 206.8216 141.2162)
		(width 0.762)
		(layer "F.Cu")
		(net "GNSS2_P5V0")
	)
	(segment
		(start 214.5592 141.5162)
		(end 214.5592 138.6612)
		(width 0.762)
		(layer "F.Cu")
		(net "GNSS2_P5V0")
	)
	(via
		(at 206.8216 141.2162)
		(size 0.4064)
		(drill 0.2032)
		(layers "F.Cu" "B.Cu")
		(net "GNSS2_P5V0")
	)
	(via
		(at 218.02068 126.44113)
		(size 0.4064)
		(drill 0.2032)
		(layers "F.Cu" "B.Cu")
		(net "GNSS2_P5V0")
	)
	(via
		(at 214.6216 141.5162)
		(size 0.4064)
		(drill 0.2032)
		(layers "F.Cu" "B.Cu")
		(net "GNSS2_P5V0")
	)
	(segment
		(start 214.6216 141.5162)
		(end 214.6216 139.0162)
		(width 0.762)
		(layer "B.Cu")
		(net "GNSS2_P5V0")
	)
	(segment
		(start 217.3216 128.5412)
		(end 218.02068 127.84212)
		(width 0.254)
		(layer "B.Cu")
		(net "GNSS2_P5V0")
	)
	(segment
		(start 215.43331 126.36791)
		(end 215.60331 126.36791)
		(width 0.254)
		(layer "B.Cu")
		(net "GNSS2_P5V0")
	)
	(segment
		(start 218.02068 127.84212)
		(end 218.02068 126.44113)
		(width 0.254)
		(layer "B.Cu")
		(net "GNSS2_P5V0")
	)
	(segment
		(start 213.94884 127.66844)
		(end 213.94884 126.42791)
		(width 0.254)
		(layer "B.Cu")
		(net "GNSS2_P5V0")
	)
	(segment
		(start 217.07331 126.36791)
		(end 217.94747 126.36791)
		(width 0.254)
		(layer "B.Cu")
		(net "GNSS2_P5V0")
	)
	(segment
		(start 213.94884 126.42791)
		(end 215.37331 126.42791)
		(width 0.254)
		(layer "B.Cu")
		(net "GNSS2_P5V0")
	)
	(segment
		(start 206.5592 141.2162)
		(end 206.8216 141.2162)
		(width 0.762)
		(layer "B.Cu")
		(net "GNSS2_P5V0")
	)
	(segment
		(start 217.94747 126.36791)
		(end 218.02068 126.44113)
		(width 0.254)
		(layer "B.Cu")
		(net "GNSS2_P5V0")
	)
	(segment
		(start 214.8216 128.5412)
		(end 217.3216 128.5412)
		(width 0.254)
		(layer "B.Cu")
		(net "GNSS2_P5V0")
	)
	(segment
		(start 213.94884 127.66844)
		(end 214.8216 128.5412)
		(width 0.254)
		(layer "B.Cu")
		(net "GNSS2_P5V0")
	)
	(segment
		(start 206.5592 141.2162)
		(end 206.5592 138.64087)
		(width 0.762)
		(layer "B.Cu")
		(net "GNSS2_P5V0")
	)
	(segment
		(start 215.37331 126.42791)
		(end 215.43331 126.36791)
		(width 0.254)
		(layer "B.Cu")
		(net "GNSS2_P5V0")
	)
	(segment
		(start 199.7216 121.7662)
		(end 199.7216 120.4412)
		(width 0.254)
		(layer "F.Cu")
		(net "GNSS2_P3V3")
	)
	(segment
		(start 216.1667 132.1162)
		(end 216.8216 132.1162)
		(width 0.762)
		(layer "F.Cu")
		(net "GNSS2_P3V3")
	)
	(segment
		(start 200.2216 121.7662)
		(end 200.2216 120.4412)
		(width 0.254)
		(layer "F.Cu")
		(net "GNSS2_P3V3")
	)
	(segment
		(start 199.13415 120.34234)
		(end 199.13415 120.3011)
		(width 0.254)
		(layer "F.Cu")
		(net "GNSS2_P3V3")
	)
	(segment
		(start 216.6216 120.3412)
		(end 216.7216 120.3412)
		(width 0.2032)
		(layer "F.Cu")
		(net "GNSS2_P3V3")
	)
	(segment
		(start 214.5592 134.2162)
		(end 214.5592 133.7237)
		(width 0.762)
		(layer "F.Cu")
		(net "GNSS2_P3V3")
	)
	(segment
		(start 217.2216 121.7662)
		(end 217.2216 120.3412)
		(width 0.254)
		(layer "F.Cu")
		(net "GNSS2_P3V3")
	)
	(segment
		(start 199.2216 121.7662)
		(end 199.2216 120.42979)
		(width 0.254)
		(layer "F.Cu")
		(net "GNSS2_P3V3")
	)
	(segment
		(start 206.55919 131.5162)
		(end 206.9216 131.5162)
		(width 0.762)
		(layer "F.Cu")
		(net "GNSS2_P3V3")
	)
	(segment
		(start 214.5592 133.7237)
		(end 216.1667 132.1162)
		(width 0.762)
		(layer "F.Cu")
		(net "GNSS2_P3V3")
	)
	(segment
		(start 206.55919 134.2162)
		(end 206.55919 131.5162)
		(width 0.762)
		(layer "F.Cu")
		(net "GNSS2_P3V3")
	)
	(segment
		(start 199.13415 120.34234)
		(end 199.2216 120.42979)
		(width 0.254)
		(layer "F.Cu")
		(net "GNSS2_P3V3")
	)
	(segment
		(start 154.1716 129.7162)
		(end 154.86871 129.7162)
		(width 0.2032)
		(layer "F.Cu")
		(net "GNSS2_P3V3")
	)
	(segment
		(start 216.7216 121.7662)
		(end 216.7216 120.3412)
		(width 0.254)
		(layer "F.Cu")
		(net "GNSS2_P3V3")
	)
	(segment
		(start 200.2216 120.4412)
		(end 200.2216 120.4412)
		(width 0.2032)
		(layer "F.Cu")
		(net "GNSS2_P3V3")
	)
	(via
		(at 199.13415 120.3011)
		(size 0.4064)
		(drill 0.2032)
		(layers "F.Cu" "B.Cu")
		(net "GNSS2_P3V3")
	)
	(via
		(at 198.26304 133.98121)
		(size 0.4064)
		(drill 0.2032)
		(layers "F.Cu" "B.Cu")
		(net "GNSS2_P3V3")
	)
	(via
		(at 199.7216 120.4412)
		(size 0.4064)
		(drill 0.2032)
		(layers "F.Cu" "B.Cu")
		(net "GNSS2_P3V3")
	)
	(via
		(at 217.2216 120.3412)
		(size 0.4064)
		(drill 0.2032)
		(layers "F.Cu" "B.Cu")
		(net "GNSS2_P3V3")
	)
	(via
		(at 200.2216 120.4412)
		(size 0.4064)
		(drill 0.2032)
		(layers "F.Cu" "B.Cu")
		(net "GNSS2_P3V3")
	)
	(via
		(at 154.86871 129.7162)
		(size 0.4064)
		(drill 0.2032)
		(layers "F.Cu" "B.Cu")
		(net "GNSS2_P3V3")
	)
	(via
		(at 216.8216 132.1162)
		(size 0.4064)
		(drill 0.2032)
		(layers "F.Cu" "B.Cu")
		(net "GNSS2_P3V3")
	)
	(via
		(at 211.4216 123.60265)
		(size 0.4064)
		(drill 0.2032)
		(layers "F.Cu" "B.Cu")
		(net "GNSS2_P3V3")
	)
	(via
		(at 206.9216 131.5162)
		(size 0.4064)
		(drill 0.2032)
		(layers "F.Cu" "B.Cu")
		(net "GNSS2_P3V3")
	)
	(via
		(at 216.6216 120.3412)
		(size 0.4064)
		(drill 0.2032)
		(layers "F.Cu" "B.Cu")
		(net "GNSS2_P3V3")
	)
	(segment
		(start 207.52584 120.1412)
		(end 207.52584 119.4602)
		(width 0.254)
		(layer "B.Cu")
		(net "GNSS2_P3V3")
	)
	(segment
		(start 200.2216 121.19078)
		(end 200.70606 121.19078)
		(width 0.254)
		(layer "B.Cu")
		(net "GNSS2_P3V3")
	)
	(segment
		(start 211.4216 123.60265)
		(end 211.4216 123.1162)
		(width 0.254)
		(layer "B.Cu")
		(net "GNSS2_P3V3")
	)
	(segment
		(start 216.23714 121.4405)
		(end 216.23714 120.3412)
		(width 0.254)
		(layer "B.Cu")
		(net "GNSS2_P3V3")
	)
	(segment
		(start 207.22681 118.8412)
		(end 207.25181 118.8412)
		(width 0.254)
		(layer "B.Cu")
		(net "GNSS2_P3V3")
	)
	(segment
		(start 214.9216 136.2162)
		(end 214.9216 133.8162)
		(width 0.762)
		(layer "B.Cu")
		(net "GNSS2_P3V3")
	)
	(segment
		(start 206.2216 124.19198)
		(end 206.63282 124.6032)
		(width 0.254)
		(layer "B.Cu")
		(net "GNSS2_P3V3")
	)
	(segment
		(start 198.88714 120.54812)
		(end 199.13415 120.3011)
		(width 0.254)
		(layer "B.Cu")
		(net "GNSS2_P3V3")
	)
	(segment
		(start 206.9586 124.6032)
		(end 206.9916 124.6362)
		(width 0.254)
		(layer "B.Cu")
		(net "GNSS2_P3V3")
	)
	(segment
		(start 207.1966 122.5412)
		(end 210.8466 122.5412)
		(width 0.254)
		(layer "B.Cu")
		(net "GNSS2_P3V3")
	)
	(segment
		(start 206.5592 131.5162)
		(end 206.9216 131.5162)
		(width 0.762)
		(layer "B.Cu")
		(net "GNSS2_P3V3")
	)
	(segment
		(start 208.4616 124.6362)
		(end 208.4946 124.6032)
		(width 0.254)
		(layer "B.Cu")
		(net "GNSS2_P3V3")
	)
	(segment
		(start 207.20181 118.8412)
		(end 207.22681 118.8412)
		(width 0.254)
		(layer "B.Cu")
		(net "GNSS2_P3V3")
	)
	(segment
		(start 153.88714 129.7162)
		(end 154.86871 129.7162)
		(width 0.2032)
		(layer "B.Cu")
		(net "GNSS2_P3V3")
	)
	(segment
		(start 214.9216 136.2162)
		(end 215.2216 136.2162)
		(width 0.762)
		(layer "B.Cu")
		(net "GNSS2_P3V3")
	)
	(segment
		(start 216.4966 132.1162)
		(end 216.8216 132.1162)
		(width 0.762)
		(layer "B.Cu")
		(net "GNSS2_P3V3")
	)
	(segment
		(start 206.71672 118.35611)
		(end 206.71672 117.4412)
		(width 0.254)
		(layer "B.Cu")
		(net "GNSS2_P3V3")
	)
	(segment
		(start 206.5592 134.4334)
		(end 206.5592 131.5162)
		(width 0.762)
		(layer "B.Cu")
		(net "GNSS2_P3V3")
	)
	(segment
		(start 217.2216 120.3412)
		(end 217.38106 120.3412)
		(width 0.254)
		(layer "B.Cu")
		(net "GNSS2_P3V3")
	)
	(segment
		(start 206.71672 118.35611)
		(end 207.20181 118.8412)
		(width 0.254)
		(layer "B.Cu")
		(net "GNSS2_P3V3")
	)
	(segment
		(start 208.4946 124.6032)
		(end 210.34593 124.6032)
		(width 0.254)
		(layer "B.Cu")
		(net "GNSS2_P3V3")
	)
	(segment
		(start 210.4896 124.45953)
		(end 210.9216 124.45953)
		(width 0.254)
		(layer "B.Cu")
		(net "GNSS2_P3V3")
	)
	(segment
		(start 210.9216 124.45953)
		(end 211.4216 123.95953)
		(width 0.254)
		(layer "B.Cu")
		(net "GNSS2_P3V3")
	)
	(segment
		(start 206.71672 117.4412)
		(end 206.8776 117.28032)
		(width 0.254)
		(layer "B.Cu")
		(net "GNSS2_P3V3")
	)
	(segment
		(start 206.8776 116.7602)
		(end 207.0216 116.6162)
		(width 0.254)
		(layer "B.Cu")
		(net "GNSS2_P3V3")
	)
	(segment
		(start 198.88714 121.1162)
		(end 198.88714 120.54812)
		(width 0.254)
		(layer "B.Cu")
		(net "GNSS2_P3V3")
	)
	(segment
		(start 199.7216 120.4412)
		(end 199.7216 119.2162)
		(width 0.254)
		(layer "B.Cu")
		(net "GNSS2_P3V3")
	)
	(segment
		(start 210.8466 122.5412)
		(end 211.4216 123.1162)
		(width 0.254)
		(layer "B.Cu")
		(net "GNSS2_P3V3")
	)
	(segment
		(start 206.2216 124.19198)
		(end 206.2216 123.5162)
		(width 0.254)
		(layer "B.Cu")
		(net "GNSS2_P3V3")
	)
	(segment
		(start 214.9216 133.8162)
		(end 214.9216 133.6912)
		(width 0.762)
		(layer "B.Cu")
		(net "GNSS2_P3V3")
	)
	(segment
		(start 210.41727 124.53186)
		(end 210.4896 124.45953)
		(width 0.254)
		(layer "B.Cu")
		(net "GNSS2_P3V3")
	)
	(segment
		(start 206.2216 123.5162)
		(end 207.1966 122.5412)
		(width 0.254)
		(layer "B.Cu")
		(net "GNSS2_P3V3")
	)
	(segment
		(start 207.25181 118.8412)
		(end 207.42481 119.0142)
		(width 0.254)
		(layer "B.Cu")
		(net "GNSS2_P3V3")
	)
	(segment
		(start 207.42481 119.35917)
		(end 207.42481 119.0142)
		(width 0.254)
		(layer "B.Cu")
		(net "GNSS2_P3V3")
	)
	(segment
		(start 206.8776 117.28032)
		(end 206.8776 116.7602)
		(width 0.254)
		(layer "B.Cu")
		(net "GNSS2_P3V3")
	)
	(segment
		(start 198.78713 119.2162)
		(end 199.7216 119.2162)
		(width 0.254)
		(layer "B.Cu")
		(net "GNSS2_P3V3")
	)
	(segment
		(start 207.42481 119.35917)
		(end 207.52584 119.4602)
		(width 0.254)
		(layer "B.Cu")
		(net "GNSS2_P3V3")
	)
	(segment
		(start 217.38106 121.4412)
		(end 217.38106 120.3412)
		(width 0.254)
		(layer "B.Cu")
		(net "GNSS2_P3V3")
	)
	(segment
		(start 210.34593 124.6032)
		(end 210.41727 124.53186)
		(width 0.254)
		(layer "B.Cu")
		(net "GNSS2_P3V3")
	)
	(segment
		(start 211.4216 123.95953)
		(end 211.4216 123.60265)
		(width 0.254)
		(layer "B.Cu")
		(net "GNSS2_P3V3")
	)
	(segment
		(start 206.63282 124.6032)
		(end 206.9586 124.6032)
		(width 0.254)
		(layer "B.Cu")
		(net "GNSS2_P3V3")
	)
	(segment
		(start 216.23714 120.3412)
		(end 216.6216 120.3412)
		(width 0.254)
		(layer "B.Cu")
		(net "GNSS2_P3V3")
	)
	(segment
		(start 214.9216 133.6912)
		(end 216.4966 132.1162)
		(width 0.762)
		(layer "B.Cu")
		(net "GNSS2_P3V3")
	)
	(segment
		(start 200.2216 121.19078)
		(end 200.2216 120.4412)
		(width 0.254)
		(layer "B.Cu")
		(net "GNSS2_P3V3")
	)
	(segment
		(start 211.41309 123.61116)
		(end 211.4216 123.60265)
		(width 0.2032)
		(layer "In2.Cu")
		(net "GNSS2_P3V3")
	)
	(segment
		(start 198.4716 130.9662)
		(end 199.91503 132.40963)
		(width 0.2032)
		(layer "In2.Cu")
		(net "GNSS2_P3V3")
	)
	(segment
		(start 207.6216 133.6162)
		(end 213.29104 133.6162)
		(width 0.762)
		(layer "In2.Cu")
		(net "GNSS2_P3V3")
	)
	(segment
		(start 213.29104 133.6162)
		(end 214.79104 132.1162)
		(width 0.762)
		(layer "In2.Cu")
		(net "GNSS2_P3V3")
	)
	(segment
		(start 201.33611 124.50168)
		(end 210.22757 124.50168)
		(width 0.2032)
		(layer "In2.Cu")
		(net "GNSS2_P3V3")
	)
	(segment
		(start 206.9216 132.9162)
		(end 206.9216 131.5162)
		(width 0.762)
		(layer "In2.Cu")
		(net "GNSS2_P3V3")
	)
	(segment
		(start 198.4716 127.3662)
		(end 201.33611 124.50168)
		(width 0.2032)
		(layer "In2.Cu")
		(net "GNSS2_P3V3")
	)
	(segment
		(start 198.4716 130.9662)
		(end 198.4716 127.3662)
		(width 0.2032)
		(layer "In2.Cu")
		(net "GNSS2_P3V3")
	)
	(segment
		(start 198.26304 133.98121)
		(end 199.54042 133.98121)
		(width 0.2032)
		(layer "In2.Cu")
		(net "GNSS2_P3V3")
	)
	(segment
		(start 211.11809 123.61116)
		(end 211.41309 123.61116)
		(width 0.2032)
		(layer "In2.Cu")
		(net "GNSS2_P3V3")
	)
	(segment
		(start 199.91503 133.6066)
		(end 199.91503 132.40963)
		(width 0.2032)
		(layer "In2.Cu")
		(net "GNSS2_P3V3")
	)
	(segment
		(start 210.22757 124.50168)
		(end 211.11809 123.61116)
		(width 0.2032)
		(layer "In2.Cu")
		(net "GNSS2_P3V3")
	)
	(segment
		(start 214.79104 132.1162)
		(end 216.8216 132.1162)
		(width 0.762)
		(layer "In2.Cu")
		(net "GNSS2_P3V3")
	)
	(segment
		(start 206.9216 132.9162)
		(end 207.6216 133.6162)
		(width 0.762)
		(layer "In2.Cu")
		(net "GNSS2_P3V3")
	)
	(segment
		(start 199.54042 133.98121)
		(end 199.91503 133.6066)
		(width 0.2032)
		(layer "In2.Cu")
		(net "GNSS2_P3V3")
	)
	(segment
		(start 161.7216 129.7162)
		(end 162.60218 129.7162)
		(width 0.2032)
		(layer "In3.Cu")
		(net "GNSS2_P3V3")
	)
	(segment
		(start 198.79255 132.32651)
		(end 199.22018 132.32651)
		(width 0.2032)
		(layer "In3.Cu")
		(net "GNSS2_P3V3")
	)
	(segment
		(start 176.47024 130.6162)
		(end 177.11205 131.258)
		(width 0.2032)
		(layer "In3.Cu")
		(net "GNSS2_P3V3")
	)
	(segment
		(start 198.00287 133.1162)
		(end 198.79255 132.32651)
		(width 0.2032)
		(layer "In3.Cu")
		(net "GNSS2_P3V3")
	)
	(segment
		(start 199.55204 133.38576)
		(end 199.55204 132.65837)
		(width 0.2032)
		(layer "In3.Cu")
		(net "GNSS2_P3V3")
	)
	(segment
		(start 189.15921 131.258)
		(end 189.97177 132.07057)
		(width 0.2032)
		(layer "In3.Cu")
		(net "GNSS2_P3V3")
	)
	(segment
		(start 154.86871 129.7162)
		(end 155.8216 129.7162)
		(width 0.2032)
		(layer "In3.Cu")
		(net "GNSS2_P3V3")
	)
	(segment
		(start 162.60218 129.7162)
		(end 163.50218 130.6162)
		(width 0.2032)
		(layer "In3.Cu")
		(net "GNSS2_P3V3")
	)
	(segment
		(start 198.95659 133.98121)
		(end 199.55204 133.38576)
		(width 0.2032)
		(layer "In3.Cu")
		(net "GNSS2_P3V3")
	)
	(segment
		(start 163.50218 130.6162)
		(end 176.47024 130.6162)
		(width 0.2032)
		(layer "In3.Cu")
		(net "GNSS2_P3V3")
	)
	(segment
		(start 199.22018 132.32651)
		(end 199.55204 132.65837)
		(width 0.2032)
		(layer "In3.Cu")
		(net "GNSS2_P3V3")
	)
	(segment
		(start 155.8216 129.7162)
		(end 156.1216 130.0162)
		(width 0.2032)
		(layer "In3.Cu")
		(net "GNSS2_P3V3")
	)
	(segment
		(start 161.4216 130.0162)
		(end 161.7216 129.7162)
		(width 0.2032)
		(layer "In3.Cu")
		(net "GNSS2_P3V3")
	)
	(segment
		(start 198.26304 133.98121)
		(end 198.95659 133.98121)
		(width 0.2032)
		(layer "In3.Cu")
		(net "GNSS2_P3V3")
	)
	(segment
		(start 189.97177 132.07057)
		(end 195.87597 132.07057)
		(width 0.2032)
		(layer "In3.Cu")
		(net "GNSS2_P3V3")
	)
	(segment
		(start 196.9216 133.1162)
		(end 198.00287 133.1162)
		(width 0.2032)
		(layer "In3.Cu")
		(net "GNSS2_P3V3")
	)
	(segment
		(start 156.1216 130.0162)
		(end 161.4216 130.0162)
		(width 0.2032)
		(layer "In3.Cu")
		(net "GNSS2_P3V3")
	)
	(segment
		(start 195.87597 132.07057)
		(end 196.9216 133.1162)
		(width 0.2032)
		(layer "In3.Cu")
		(net "GNSS2_P3V3")
	)
	(segment
		(start 177.11205 131.258)
		(end 189.15921 131.258)
		(width 0.2032)
		(layer "In3.Cu")
		(net "GNSS2_P3V3")
	)
	(segment
		(start 218.5716 127.51025)
		(end 218.96126 127.12059)
		(width 0.254)
		(layer "B.Cu")
		(net "FTDI_P3V3")
	)
	(segment
		(start 205.92855 125.28499)
		(end 206.07734 125.1362)
		(width 0.254)
		(layer "B.Cu")
		(net "FTDI_P3V3")
	)
	(segment
		(start 212.11094 128.5412)
		(end 213.03394 129.4642)
		(width 0.254)
		(layer "B.Cu")
		(net "FTDI_P3V3")
	)
	(segment
		(start 206.91533 128.5412)
		(end 212.11094 128.5412)
		(width 0.254)
		(layer "B.Cu")
		(net "FTDI_P3V3")
	)
	(segment
		(start 213.03394 129.4642)
		(end 218.3946 129.4642)
		(width 0.254)
		(layer "B.Cu")
		(net "FTDI_P3V3")
	)
	(segment
		(start 206.07734 125.1362)
		(end 206.9916 125.1362)
		(width 0.254)
		(layer "B.Cu")
		(net "FTDI_P3V3")
	)
	(segment
		(start 218.3946 129.4642)
		(end 218.5716 129.2872)
		(width 0.254)
		(layer "B.Cu")
		(net "FTDI_P3V3")
	)
	(segment
		(start 218.96126 127.12059)
		(end 219.66155 127.12059)
		(width 0.254)
		(layer "B.Cu")
		(net "FTDI_P3V3")
	)
	(segment
		(start 219.66155 127.12059)
		(end 219.66155 125.96469)
		(width 0.508)
		(layer "B.Cu")
		(net "FTDI_P3V3")
	)
	(segment
		(start 205.92855 127.55441)
		(end 205.92855 125.28499)
		(width 0.254)
		(layer "B.Cu")
		(net "FTDI_P3V3")
	)
	(segment
		(start 205.92855 127.55441)
		(end 206.91533 128.5412)
		(width 0.254)
		(layer "B.Cu")
		(net "FTDI_P3V3")
	)
	(segment
		(start 218.5716 129.2872)
		(end 218.5716 127.51025)
		(width 0.254)
		(layer "B.Cu")
		(net "FTDI_P3V3")
	)
	(segment
		(start 223.47 92.9178)
		(end 223.47 92.6178)
		(width 0.2032)
		(layer "F.Cu")
		(net "NetD19_1")
	)
	(segment
		(start 223.47 92.6178)
		(end 224.2716 91.8162)
		(width 0.2032)
		(layer "F.Cu")
		(net "NetD19_1")
	)
	(segment
		(start 223.1716 93.2162)
		(end 223.47 92.9178)
		(width 0.2032)
		(layer "F.Cu")
		(net "NetD19_1")
	)
	(segment
		(start 222.3216 103.3162)
		(end 223.25035 102.38745)
		(width 0.2032)
		(layer "F.Cu")
		(net "NetD12_1")
	)
	(segment
		(start 223.25035 102.38745)
		(end 224.5216 102.38745)
		(width 0.2032)
		(layer "F.Cu")
		(net "NetD12_1")
	)
	(via
		(at 222.3216 103.3162)
		(size 0.4064)
		(drill 0.2032)
		(layers "F.Cu" "B.Cu")
		(net "NetD12_1")
	)
	(segment
		(start 222.3216 103.2162)
		(end 222.3216 102.4662)
		(width 0.2032)
		(layer "B.Cu")
		(net "NetD12_1")
	)
	(segment
		(start 222.1716 102.3162)
		(end 222.3216 102.4662)
		(width 0.2032)
		(layer "B.Cu")
		(net "NetD12_1")
	)
	(segment
		(start 190.5216 130.8662)
		(end 191.2216 131.5662)
		(width 0.2032)
		(layer "F.Cu")
		(net "RCB_GPS2_TX")
	)
	(segment
		(start 212.5216 140.4162)
		(end 212.5592 140.4162)
		(width 0.2032)
		(layer "F.Cu")
		(net "RCB_GPS2_TX")
	)
	(segment
		(start 191.2216 131.5662)
		(end 192.1738 131.5662)
		(width 0.2032)
		(layer "F.Cu")
		(net "RCB_GPS2_TX")
	)
	(segment
		(start 212.5592 140.4162)
		(end 212.5592 138.6612)
		(width 0.2032)
		(layer "F.Cu")
		(net "RCB_GPS2_TX")
	)
	(via
		(at 212.5216 140.4162)
		(size 0.4064)
		(drill 0.2032)
		(layers "F.Cu" "B.Cu")
		(net "RCB_GPS2_TX")
	)
	(via
		(at 190.5216 130.8662)
		(size 0.4064)
		(drill 0.2032)
		(layers "F.Cu" "B.Cu")
		(net "RCB_GPS2_TX")
	)
	(segment
		(start 190.3216 136.2162)
		(end 190.34431 136.19349)
		(width 0.2032)
		(layer "B.Cu")
		(net "RCB_GPS2_TX")
	)
	(segment
		(start 188.3216 133.00841)
		(end 188.3216 131.2162)
		(width 0.2032)
		(layer "B.Cu")
		(net "RCB_GPS2_TX")
	)
	(segment
		(start 189.10315 133.00841)
		(end 190.34431 134.24957)
		(width 0.2032)
		(layer "B.Cu")
		(net "RCB_GPS2_TX")
	)
	(segment
		(start 206.37984 143.5162)
		(end 206.37984 142.17273)
		(width 0.2032)
		(layer "B.Cu")
		(net "RCB_GPS2_TX")
	)
	(segment
		(start 188.3216 133.00841)
		(end 189.10315 133.00841)
		(width 0.2032)
		(layer "B.Cu")
		(net "RCB_GPS2_TX")
	)
	(segment
		(start 190.3216 141.6162)
		(end 191.0892 142.3838)
		(width 0.2032)
		(layer "B.Cu")
		(net "RCB_GPS2_TX")
	)
	(segment
		(start 188.3216 131.2162)
		(end 188.6716 130.8662)
		(width 0.2032)
		(layer "B.Cu")
		(net "RCB_GPS2_TX")
	)
	(segment
		(start 188.6716 130.8662)
		(end 190.5216 130.8662)
		(width 0.2032)
		(layer "B.Cu")
		(net "RCB_GPS2_TX")
	)
	(segment
		(start 205.4216 141.21449)
		(end 205.4216 139.23523)
		(width 0.2032)
		(layer "B.Cu")
		(net "RCB_GPS2_TX")
	)
	(segment
		(start 206.37984 143.5162)
		(end 209.4216 143.5162)
		(width 0.2032)
		(layer "B.Cu")
		(net "RCB_GPS2_TX")
	)
	(segment
		(start 190.3216 141.6162)
		(end 190.3216 136.2162)
		(width 0.2032)
		(layer "B.Cu")
		(net "RCB_GPS2_TX")
	)
	(segment
		(start 205.30257 139.1162)
		(end 205.4216 139.23523)
		(width 0.2032)
		(layer "B.Cu")
		(net "RCB_GPS2_TX")
	)
	(segment
		(start 190.34431 136.19349)
		(end 190.34431 134.24957)
		(width 0.2032)
		(layer "B.Cu")
		(net "RCB_GPS2_TX")
	)
	(segment
		(start 191.0892 142.3838)
		(end 196.054 142.3838)
		(width 0.2032)
		(layer "B.Cu")
		(net "RCB_GPS2_TX")
	)
	(segment
		(start 196.054 142.3838)
		(end 199.3216 139.1162)
		(width 0.2032)
		(layer "B.Cu")
		(net "RCB_GPS2_TX")
	)
	(segment
		(start 199.3216 139.1162)
		(end 205.30257 139.1162)
		(width 0.2032)
		(layer "B.Cu")
		(net "RCB_GPS2_TX")
	)
	(segment
		(start 209.4216 143.5162)
		(end 212.5216 140.4162)
		(width 0.2032)
		(layer "B.Cu")
		(net "RCB_GPS2_TX")
	)
	(segment
		(start 205.4216 141.21449)
		(end 206.37984 142.17273)
		(width 0.2032)
		(layer "B.Cu")
		(net "RCB_GPS2_TX")
	)
	(segment
		(start 194.3716 130.8684)
		(end 194.3716 129.7162)
		(width 0.2032)
		(layer "F.Cu")
		(net "RCB_GPS2_TP2")
	)
	(segment
		(start 208.5592 141.7162)
		(end 209.4216 141.7162)
		(width 0.2032)
		(layer "F.Cu")
		(net "RCB_GPS2_TP2")
	)
	(segment
		(start 194.3716 129.7162)
		(end 194.9216 129.1662)
		(width 0.2032)
		(layer "F.Cu")
		(net "RCB_GPS2_TP2")
	)
	(segment
		(start 208.5592 141.7162)
		(end 208.5592 138.6612)
		(width 0.2032)
		(layer "F.Cu")
		(net "RCB_GPS2_TP2")
	)
	(via
		(at 194.9216 129.1662)
		(size 0.4064)
		(drill 0.2032)
		(layers "F.Cu" "B.Cu")
		(net "RCB_GPS2_TP2")
	)
	(via
		(at 209.4216 141.7162)
		(size 0.4064)
		(drill 0.2032)
		(layers "F.Cu" "B.Cu")
		(net "RCB_GPS2_TP2")
	)
	(segment
		(start 194.9216 129.1662)
		(end 198.62473 129.1662)
		(width 0.2032)
		(layer "B.Cu")
		(net "RCB_GPS2_TP2")
	)
	(segment
		(start 208.95489 135.486)
		(end 209.6216 134.81929)
		(width 0.2032)
		(layer "B.Cu")
		(net "RCB_GPS2_TP2")
	)
	(segment
		(start 211.6216 136.9162)
		(end 212.54221 135.99559)
		(width 0.2032)
		(layer "B.Cu")
		(net "RCB_GPS2_TP2")
	)
	(segment
		(start 212.0898 133.2543)
		(end 212.0898 131.29174)
		(width 0.2032)
		(layer "B.Cu")
		(net "RCB_GPS2_TP2")
	)
	(segment
		(start 211.33743 130.90037)
		(end 211.69842 130.90037)
		(width 0.2032)
		(layer "B.Cu")
		(net "RCB_GPS2_TP2")
	)
	(segment
		(start 198.62473 131.11933)
		(end 198.62473 129.1662)
		(width 0.2032)
		(layer "B.Cu")
		(net "RCB_GPS2_TP2")
	)
	(segment
		(start 211.6216 140.3162)
		(end 211.6216 136.9162)
		(width 0.2032)
		(layer "B.Cu")
		(net "RCB_GPS2_TP2")
	)
	(segment
		(start 198.62473 131.11933)
		(end 200.5216 133.0162)
		(width 0.2032)
		(layer "B.Cu")
		(net "RCB_GPS2_TP2")
	)
	(segment
		(start 201.0216 133.0162)
		(end 203.4914 135.486)
		(width 0.2032)
		(layer "B.Cu")
		(net "RCB_GPS2_TP2")
	)
	(segment
		(start 203.4914 135.486)
		(end 208.95489 135.486)
		(width 0.2032)
		(layer "B.Cu")
		(net "RCB_GPS2_TP2")
	)
	(segment
		(start 212.0898 133.2543)
		(end 212.54221 133.70671)
		(width 0.2032)
		(layer "B.Cu")
		(net "RCB_GPS2_TP2")
	)
	(segment
		(start 212.54221 135.99559)
		(end 212.54221 133.70671)
		(width 0.2032)
		(layer "B.Cu")
		(net "RCB_GPS2_TP2")
	)
	(segment
		(start 209.4216 141.7162)
		(end 210.2216 141.7162)
		(width 0.2032)
		(layer "B.Cu")
		(net "RCB_GPS2_TP2")
	)
	(segment
		(start 209.6216 132.6162)
		(end 211.33743 130.90037)
		(width 0.2032)
		(layer "B.Cu")
		(net "RCB_GPS2_TP2")
	)
	(segment
		(start 210.2216 141.7162)
		(end 211.6216 140.3162)
		(width 0.2032)
		(layer "B.Cu")
		(net "RCB_GPS2_TP2")
	)
	(segment
		(start 200.5216 133.0162)
		(end 201.0216 133.0162)
		(width 0.2032)
		(layer "B.Cu")
		(net "RCB_GPS2_TP2")
	)
	(segment
		(start 209.6216 134.81929)
		(end 209.6216 132.6162)
		(width 0.2032)
		(layer "B.Cu")
		(net "RCB_GPS2_TP2")
	)
	(segment
		(start 211.69842 130.90037)
		(end 212.0898 131.29174)
		(width 0.2032)
		(layer "B.Cu")
		(net "RCB_GPS2_TP2")
	)
	(segment
		(start 195.3488 133.0662)
		(end 195.66157 133.37897)
		(width 0.2032)
		(layer "F.Cu")
		(net "RCB_GPS2_TP1")
	)
	(segment
		(start 195.66157 133.65837)
		(end 195.66157 133.37897)
		(width 0.2032)
		(layer "F.Cu")
		(net "RCB_GPS2_TP1")
	)
	(segment
		(start 195.66157 133.65837)
		(end 195.9194 133.9162)
		(width 0.2032)
		(layer "F.Cu")
		(net "RCB_GPS2_TP1")
	)
	(segment
		(start 210.5216 134.2162)
		(end 210.5592 134.2162)
		(width 0.2032)
		(layer "F.Cu")
		(net "RCB_GPS2_TP1")
	)
	(segment
		(start 195.9194 133.9162)
		(end 196.4716 133.9162)
		(width 0.2032)
		(layer "F.Cu")
		(net "RCB_GPS2_TP1")
	)
	(segment
		(start 195.0694 133.0662)
		(end 195.3488 133.0662)
		(width 0.2032)
		(layer "F.Cu")
		(net "RCB_GPS2_TP1")
	)
	(segment
		(start 210.5216 134.2162)
		(end 210.5216 132.6162)
		(width 0.2032)
		(layer "F.Cu")
		(net "RCB_GPS2_TP1")
	)
	(via
		(at 196.4716 133.9162)
		(size 0.4064)
		(drill 0.2032)
		(layers "F.Cu" "B.Cu")
		(net "RCB_GPS2_TP1")
	)
	(via
		(at 210.5216 132.6162)
		(size 0.4064)
		(drill 0.2032)
		(layers "F.Cu" "B.Cu")
		(net "RCB_GPS2_TP1")
	)
	(segment
		(start 209.3216 135.8162)
		(end 210.5216 134.6162)
		(width 0.2032)
		(layer "B.Cu")
		(net "RCB_GPS2_TP1")
	)
	(segment
		(start 196.9716 134.4162)
		(end 201.8653 134.4162)
		(width 0.2032)
		(layer "B.Cu")
		(net "RCB_GPS2_TP1")
	)
	(segment
		(start 196.4716 133.9162)
		(end 196.9716 134.4162)
		(width 0.2032)
		(layer "B.Cu")
		(net "RCB_GPS2_TP1")
	)
	(segment
		(start 210.5216 134.6162)
		(end 210.5216 132.6162)
		(width 0.2032)
		(layer "B.Cu")
		(net "RCB_GPS2_TP1")
	)
	(segment
		(start 203.26531 135.8162)
		(end 209.3216 135.8162)
		(width 0.2032)
		(layer "B.Cu")
		(net "RCB_GPS2_TP1")
	)
	(segment
		(start 201.8653 134.4162)
		(end 203.26531 135.8162)
		(width 0.2032)
		(layer "B.Cu")
		(net "RCB_GPS2_TP1")
	)
	(segment
		(start 210.5592 140.5162)
		(end 210.5592 138.6612)
		(width 0.2032)
		(layer "F.Cu")
		(net "RCB_GPS2_RX")
	)
	(segment
		(start 192.8716 134.0434)
		(end 192.8716 133.764)
		(width 0.2032)
		(layer "F.Cu")
		(net "RCB_GPS2_RX")
	)
	(segment
		(start 210.5216 140.5162)
		(end 210.5592 140.5162)
		(width 0.2032)
		(layer "F.Cu")
		(net "RCB_GPS2_RX")
	)
	(segment
		(start 192.4716 135.2162)
		(end 192.4716 134.4434)
		(width 0.2032)
		(layer "F.Cu")
		(net "RCB_GPS2_RX")
	)
	(segment
		(start 192.4716 134.4434)
		(end 192.8716 134.0434)
		(width 0.2032)
		(layer "F.Cu")
		(net "RCB_GPS2_RX")
	)
	(via
		(at 192.4716 135.2162)
		(size 0.4064)
		(drill 0.2032)
		(layers "F.Cu" "B.Cu")
		(net "RCB_GPS2_RX")
	)
	(via
		(at 210.5216 140.5162)
		(size 0.4064)
		(drill 0.2032)
		(layers "F.Cu" "B.Cu")
		(net "RCB_GPS2_RX")
	)
	(segment
		(start 193.75022 135.24482)
		(end 194.9216 136.4162)
		(width 0.2032)
		(layer "B.Cu")
		(net "RCB_GPS2_RX")
	)
	(segment
		(start 194.9216 136.4162)
		(end 195.8216 136.4162)
		(width 0.2032)
		(layer "B.Cu")
		(net "RCB_GPS2_RX")
	)
	(segment
		(start 210.142 137.5366)
		(end 210.5216 137.9162)
		(width 0.2032)
		(layer "B.Cu")
		(net "RCB_GPS2_RX")
	)
	(segment
		(start 192.50022 135.24482)
		(end 193.75022 135.24482)
		(width 0.2032)
		(layer "B.Cu")
		(net "RCB_GPS2_RX")
	)
	(segment
		(start 210.5216 140.5162)
		(end 210.5216 137.9162)
		(width 0.2032)
		(layer "B.Cu")
		(net "RCB_GPS2_RX")
	)
	(segment
		(start 195.8216 136.4162)
		(end 196.942 137.5366)
		(width 0.2032)
		(layer "B.Cu")
		(net "RCB_GPS2_RX")
	)
	(segment
		(start 196.942 137.5366)
		(end 210.142 137.5366)
		(width 0.2032)
		(layer "B.Cu")
		(net "RCB_GPS2_RX")
	)
	(segment
		(start 192.4716 135.2162)
		(end 192.50022 135.24482)
		(width 0.2032)
		(layer "B.Cu")
		(net "RCB_GPS2_RX")
	)
	(segment
		(start 199.55204 135.09978)
		(end 199.55204 131.88576)
		(width 0.2032)
		(layer "F.Cu")
		(net "RCB_GPS2_PIN12")
	)
	(segment
		(start 195.9466 125.3412)
		(end 196.30292 125.69752)
		(width 0.2032)
		(layer "F.Cu")
		(net "RCB_GPS2_PIN12")
	)
	(segment
		(start 188.63807 136.01291)
		(end 188.63807 131.59973)
		(width 0.2032)
		(layer "F.Cu")
		(net "RCB_GPS2_PIN12")
	)
	(segment
		(start 190.92819 142.32279)
		(end 190.92819 138.30302)
		(width 0.2032)
		(layer "F.Cu")
		(net "RCB_GPS2_PIN12")
	)
	(segment
		(start 195.5216 125.3412)
		(end 195.9466 125.3412)
		(width 0.2032)
		(layer "F.Cu")
		(net "RCB_GPS2_PIN12")
	)
	(segment
		(start 191.79116 127.7162)
		(end 194.7216 127.7162)
		(width 0.2032)
		(layer "F.Cu")
		(net "RCB_GPS2_PIN12")
	)
	(segment
		(start 188.63807 136.01291)
		(end 190.92819 138.30302)
		(width 0.2032)
		(layer "F.Cu")
		(net "RCB_GPS2_PIN12")
	)
	(segment
		(start 204.55919 134.2162)
		(end 204.55919 132.05379)
		(width 0.2032)
		(layer "F.Cu")
		(net "RCB_GPS2_PIN12")
	)
	(segment
		(start 191.1541 142.5487)
		(end 195.4891 142.5487)
		(width 0.2032)
		(layer "F.Cu")
		(net "RCB_GPS2_PIN12")
	)
	(segment
		(start 203.9216 131.4162)
		(end 204.55919 132.05379)
		(width 0.2032)
		(layer "F.Cu")
		(net "RCB_GPS2_PIN12")
	)
	(segment
		(start 199.55204 131.88576)
		(end 200.0216 131.4162)
		(width 0.2032)
		(layer "F.Cu")
		(net "RCB_GPS2_PIN12")
	)
	(segment
		(start 194.7216 127.7162)
		(end 196.30292 126.13488)
		(width 0.2032)
		(layer "F.Cu")
		(net "RCB_GPS2_PIN12")
	)
	(segment
		(start 194.7716 123.0162)
		(end 194.7732 123.0178)
		(width 0.2032)
		(layer "F.Cu")
		(net "RCB_GPS2_PIN12")
	)
	(segment
		(start 195.5216 125.3412)
		(end 195.5216 123.4162)
		(width 0.2032)
		(layer "F.Cu")
		(net "RCB_GPS2_PIN12")
	)
	(segment
		(start 190.92819 142.32279)
		(end 191.1541 142.5487)
		(width 0.2032)
		(layer "F.Cu")
		(net "RCB_GPS2_PIN12")
	)
	(segment
		(start 195.1232 123.0178)
		(end 195.5216 123.4162)
		(width 0.2032)
		(layer "F.Cu")
		(net "RCB_GPS2_PIN12")
	)
	(segment
		(start 196.30292 126.13488)
		(end 196.30292 125.69752)
		(width 0.2032)
		(layer "F.Cu")
		(net "RCB_GPS2_PIN12")
	)
	(segment
		(start 200.0216 131.4162)
		(end 203.9216 131.4162)
		(width 0.2032)
		(layer "F.Cu")
		(net "RCB_GPS2_PIN12")
	)
	(segment
		(start 189.9216 129.58576)
		(end 191.79116 127.7162)
		(width 0.2032)
		(layer "F.Cu")
		(net "RCB_GPS2_PIN12")
	)
	(segment
		(start 198.9537 139.0841)
		(end 198.9537 135.69812)
		(width 0.2032)
		(layer "F.Cu")
		(net "RCB_GPS2_PIN12")
	)
	(segment
		(start 188.63807 131.59973)
		(end 189.9216 130.3162)
		(width 0.2032)
		(layer "F.Cu")
		(net "RCB_GPS2_PIN12")
	)
	(segment
		(start 194.7732 123.0178)
		(end 195.1232 123.0178)
		(width 0.2032)
		(layer "F.Cu")
		(net "RCB_GPS2_PIN12")
	)
	(segment
		(start 198.9537 135.69812)
		(end 199.55204 135.09978)
		(width 0.2032)
		(layer "F.Cu")
		(net "RCB_GPS2_PIN12")
	)
	(segment
		(start 195.4891 142.5487)
		(end 198.9537 139.0841)
		(width 0.2032)
		(layer "F.Cu")
		(net "RCB_GPS2_PIN12")
	)
	(segment
		(start 189.9216 130.3162)
		(end 189.9216 129.58576)
		(width 0.2032)
		(layer "F.Cu")
		(net "RCB_GPS2_PIN12")
	)
	(segment
		(start 195.4216 122.2162)
		(end 195.9216 121.7162)
		(width 0.2032)
		(layer "F.Cu")
		(net "RCB_GPS2_PIN11")
	)
	(segment
		(start 204.6216 140.5162)
		(end 204.6216 138.72361)
		(width 0.2032)
		(layer "F.Cu")
		(net "RCB_GPS2_PIN11")
	)
	(segment
		(start 194.7716 122.2162)
		(end 195.4216 122.2162)
		(width 0.2032)
		(layer "F.Cu")
		(net "RCB_GPS2_PIN11")
	)
	(segment
		(start 204.55919 138.6612)
		(end 204.6216 138.72361)
		(width 0.2032)
		(layer "F.Cu")
		(net "RCB_GPS2_PIN11")
	)
	(segment
		(start 195.9216 121.7162)
		(end 195.9216 120.3912)
		(width 0.2032)
		(layer "F.Cu")
		(net "RCB_GPS2_PIN11")
	)
	(via
		(at 195.9216 120.3912)
		(size 0.4064)
		(drill 0.2032)
		(layers "F.Cu" "B.Cu")
		(net "RCB_GPS2_PIN11")
	)
	(via
		(at 187.63453 133.49185)
		(size 0.4064)
		(drill 0.2032)
		(layers "F.Cu" "B.Cu")
		(net "RCB_GPS2_PIN11")
	)
	(via
		(at 204.6216 140.5162)
		(size 0.4064)
		(drill 0.2032)
		(layers "F.Cu" "B.Cu")
		(net "RCB_GPS2_PIN11")
	)
	(segment
		(start 201.6216 143.5162)
		(end 204.6216 140.5162)
		(width 0.2032)
		(layer "B.Cu")
		(net "RCB_GPS2_PIN11")
	)
	(segment
		(start 187.65733 133.46904)
		(end 189.06361 133.46904)
		(width 0.2032)
		(layer "B.Cu")
		(net "RCB_GPS2_PIN11")
	)
	(segment
		(start 189.81571 142.31031)
		(end 189.81571 134.22114)
		(width 0.2032)
		(layer "B.Cu")
		(net "RCB_GPS2_PIN11")
	)
	(segment
		(start 189.81571 142.31031)
		(end 191.0216 143.5162)
		(width 0.2032)
		(layer "B.Cu")
		(net "RCB_GPS2_PIN11")
	)
	(segment
		(start 189.06361 133.46904)
		(end 189.81571 134.22114)
		(width 0.2032)
		(layer "B.Cu")
		(net "RCB_GPS2_PIN11")
	)
	(segment
		(start 191.0216 143.5162)
		(end 201.6216 143.5162)
		(width 0.2032)
		(layer "B.Cu")
		(net "RCB_GPS2_PIN11")
	)
	(segment
		(start 187.63453 133.49185)
		(end 187.65733 133.46904)
		(width 0.2032)
		(layer "B.Cu")
		(net "RCB_GPS2_PIN11")
	)
	(segment
		(start 187.6216 133.46904)
		(end 187.6216 128.66842)
		(width 0.2032)
		(layer "In2.Cu")
		(net "RCB_GPS2_PIN11")
	)
	(segment
		(start 192.3216 118.8162)
		(end 194.6216 118.8162)
		(width 0.2032)
		(layer "In2.Cu")
		(net "RCB_GPS2_PIN11")
	)
	(segment
		(start 190.0216 121.1162)
		(end 192.3216 118.8162)
		(width 0.2032)
		(layer "In2.Cu")
		(net "RCB_GPS2_PIN11")
	)
	(segment
		(start 187.6216 128.66842)
		(end 190.0216 126.26842)
		(width 0.2032)
		(layer "In2.Cu")
		(net "RCB_GPS2_PIN11")
	)
	(segment
		(start 194.6216 118.8162)
		(end 195.9216 120.1162)
		(width 0.2032)
		(layer "In2.Cu")
		(net "RCB_GPS2_PIN11")
	)
	(segment
		(start 190.0216 126.26842)
		(end 190.0216 121.1162)
		(width 0.2032)
		(layer "In2.Cu")
		(net "RCB_GPS2_PIN11")
	)
	(segment
		(start 195.9216 120.3912)
		(end 195.9216 120.1162)
		(width 0.2032)
		(layer "In2.Cu")
		(net "RCB_GPS2_PIN11")
	)
	(segment
		(start 108.3216 53.8934)
		(end 108.3216 51.7662)
		(width 0.2032)
		(layer "F.Cu")
		(net "RCB_GPS1_TX")
	)
	(segment
		(start 108.6944 54.2662)
		(end 108.9738 54.2662)
		(width 0.2032)
		(layer "F.Cu")
		(net "RCB_GPS1_TX")
	)
	(segment
		(start 101.9216 71.7286)
		(end 105.0266 71.7286)
		(width 0.2032)
		(layer "F.Cu")
		(net "RCB_GPS1_TX")
	)
	(segment
		(start 101.9216 71.7286)
		(end 101.9216 71.7162)
		(width 0.2032)
		(layer "F.Cu")
		(net "RCB_GPS1_TX")
	)
	(segment
		(start 108.3216 53.8934)
		(end 108.6944 54.2662)
		(width 0.2032)
		(layer "F.Cu")
		(net "RCB_GPS1_TX")
	)
	(via
		(at 101.9216 71.7162)
		(size 0.4064)
		(drill 0.2032)
		(layers "F.Cu" "B.Cu")
		(net "RCB_GPS1_TX")
	)
	(via
		(at 108.3216 51.7662)
		(size 0.4064)
		(drill 0.2032)
		(layers "F.Cu" "B.Cu")
		(net "RCB_GPS1_TX")
	)
	(segment
		(start 103.2591 58.7787)
		(end 105.8216 56.2162)
		(width 0.2032)
		(layer "B.Cu")
		(net "RCB_GPS1_TX")
	)
	(segment
		(start 108.8216 55.0162)
		(end 108.8216 52.2662)
		(width 0.2032)
		(layer "B.Cu")
		(net "RCB_GPS1_TX")
	)
	(segment
		(start 103.2591 59.78935)
		(end 103.2591 58.7787)
		(width 0.2032)
		(layer "B.Cu")
		(net "RCB_GPS1_TX")
	)
	(segment
		(start 100.7716 68.29346)
		(end 101.9216 69.44346)
		(width 0.2032)
		(layer "B.Cu")
		(net "RCB_GPS1_TX")
	)
	(segment
		(start 100.7716 68.29346)
		(end 100.7716 63.6662)
		(width 0.2032)
		(layer "B.Cu")
		(net "RCB_GPS1_TX")
	)
	(segment
		(start 100.7716 63.6662)
		(end 102.0966 62.3412)
		(width 0.2032)
		(layer "B.Cu")
		(net "RCB_GPS1_TX")
	)
	(segment
		(start 105.8216 56.2162)
		(end 107.6216 56.2162)
		(width 0.2032)
		(layer "B.Cu")
		(net "RCB_GPS1_TX")
	)
	(segment
		(start 102.0966 60.95185)
		(end 103.2591 59.78935)
		(width 0.2032)
		(layer "B.Cu")
		(net "RCB_GPS1_TX")
	)
	(segment
		(start 101.9216 71.7162)
		(end 101.9216 69.44346)
		(width 0.2032)
		(layer "B.Cu")
		(net "RCB_GPS1_TX")
	)
	(segment
		(start 108.3216 51.7662)
		(end 108.8216 52.2662)
		(width 0.2032)
		(layer "B.Cu")
		(net "RCB_GPS1_TX")
	)
	(segment
		(start 107.6216 56.2162)
		(end 108.8216 55.0162)
		(width 0.2032)
		(layer "B.Cu")
		(net "RCB_GPS1_TX")
	)
	(segment
		(start 102.0966 62.3412)
		(end 102.0966 60.95185)
		(width 0.2032)
		(layer "B.Cu")
		(net "RCB_GPS1_TX")
	)
	(segment
		(start 103.0216 68.5162)
		(end 103.07658 68.5162)
		(width 0.2032)
		(layer "F.Cu")
		(net "RCB_GPS1_TP2")
	)
	(segment
		(start 103.07658 68.5162)
		(end 103.40578 68.187)
		(width 0.2032)
		(layer "F.Cu")
		(net "RCB_GPS1_TP2")
	)
	(segment
		(start 103.40578 68.187)
		(end 104.5682 68.187)
		(width 0.2032)
		(layer "F.Cu")
		(net "RCB_GPS1_TP2")
	)
	(segment
		(start 104.5682 68.187)
		(end 105.0266 67.7286)
		(width 0.2032)
		(layer "F.Cu")
		(net "RCB_GPS1_TP2")
	)
	(segment
		(start 111.8194 53.5684)
		(end 112.7216 52.6662)
		(width 0.2032)
		(layer "F.Cu")
		(net "RCB_GPS1_TP2")
	)
	(segment
		(start 111.1716 53.5684)
		(end 111.8194 53.5684)
		(width 0.2032)
		(layer "F.Cu")
		(net "RCB_GPS1_TP2")
	)
	(via
		(at 103.0216 68.5162)
		(size 0.4064)
		(drill 0.2032)
		(layers "F.Cu" "B.Cu")
		(tenting
			(front yes)
			(back yes)
		)
		(net "RCB_GPS1_TP2")
	)
	(via
		(at 112.7216 52.6662)
		(size 0.4064)
		(drill 0.2032)
		(layers "F.Cu" "B.Cu")
		(net "RCB_GPS1_TP2")
	)
	(segment
		(start 109.10196 56.22419)
		(end 113.81361 56.22419)
		(width 0.2032)
		(layer "B.Cu")
		(net "RCB_GPS1_TP2")
	)
	(segment
		(start 114.1216 55.9162)
		(end 114.1216 54.0662)
		(width 0.2032)
		(layer "B.Cu")
		(net "RCB_GPS1_TP2")
	)
	(segment
		(start 104.5216 67.48191)
		(end 104.5216 65.69655)
		(width 0.2032)
		(layer "B.Cu")
		(net "RCB_GPS1_TP2")
	)
	(segment
		(start 113.81361 56.22419)
		(end 114.1216 55.9162)
		(width 0.2032)
		(layer "B.Cu")
		(net "RCB_GPS1_TP2")
	)
	(segment
		(start 103.06048 68.47732)
		(end 103.52619 68.47732)
		(width 0.2032)
		(layer "B.Cu")
		(net "RCB_GPS1_TP2")
	)
	(segment
		(start 103.52619 68.47732)
		(end 104.5216 67.48191)
		(width 0.2032)
		(layer "B.Cu")
		(net "RCB_GPS1_TP2")
	)
	(segment
		(start 106.6216 58.70455)
		(end 109.10196 56.22419)
		(width 0.2032)
		(layer "B.Cu")
		(net "RCB_GPS1_TP2")
	)
	(segment
		(start 104.5216 65.69655)
		(end 106.6216 63.59655)
		(width 0.2032)
		(layer "B.Cu")
		(net "RCB_GPS1_TP2")
	)
	(segment
		(start 103.0216 68.5162)
		(end 103.06048 68.47732)
		(width 0.2032)
		(layer "B.Cu")
		(net "RCB_GPS1_TP2")
	)
	(segment
		(start 106.6216 63.59655)
		(end 106.6216 58.70455)
		(width 0.2032)
		(layer "B.Cu")
		(net "RCB_GPS1_TP2")
	)
	(segment
		(start 112.7216 52.6662)
		(end 114.1216 54.0662)
		(width 0.2032)
		(layer "B.Cu")
		(net "RCB_GPS1_TP2")
	)
	(segment
		(start 112.1488 55.7662)
		(end 112.1742 55.7916)
		(width 0.2032)
		(layer "F.Cu")
		(net "RCB_GPS1_TP1")
	)
	(segment
		(start 112.1742 56.3188)
		(end 113.3966 57.5412)
		(width 0.2032)
		(layer "F.Cu")
		(net "RCB_GPS1_TP1")
	)
	(segment
		(start 109.4716 69.7286)
		(end 109.48401 69.7162)
		(width 0.2032)
		(layer "F.Cu")
		(net "RCB_GPS1_TP1")
	)
	(segment
		(start 111.8694 55.7662)
		(end 112.1488 55.7662)
		(width 0.2032)
		(layer "F.Cu")
		(net "RCB_GPS1_TP1")
	)
	(segment
		(start 112.1742 56.3188)
		(end 112.1742 55.7916)
		(width 0.2032)
		(layer "F.Cu")
		(net "RCB_GPS1_TP1")
	)
	(segment
		(start 113.4216 57.5662)
		(end 113.4216 57.5162)
		(width 0.2032)
		(layer "F.Cu")
		(net "RCB_GPS1_TP1")
	)
	(segment
		(start 109.48401 69.7162)
		(end 110.9216 69.7162)
		(width 0.2032)
		(layer "F.Cu")
		(net "RCB_GPS1_TP1")
	)
	(via
		(at 110.9216 69.7162)
		(size 0.4064)
		(drill 0.2032)
		(layers "F.Cu" "B.Cu")
		(tenting
			(front yes)
			(back yes)
		)
		(net "RCB_GPS1_TP1")
	)
	(via
		(at 113.4216 57.5162)
		(size 0.4064)
		(drill 0.2032)
		(layers "F.Cu" "B.Cu")
		(net "RCB_GPS1_TP1")
	)
	(segment
		(start 109.734 69.7286)
		(end 110.9092 69.7286)
		(width 0.2032)
		(layer "B.Cu")
		(net "RCB_GPS1_TP1")
	)
	(segment
		(start 113.4216 62.9162)
		(end 114.0216 62.3162)
		(width 0.2032)
		(layer "B.Cu")
		(net "RCB_GPS1_TP1")
	)
	(segment
		(start 113.4216 57.5162)
		(end 114.0216 58.1162)
		(width 0.2032)
		(layer "B.Cu")
		(net "RCB_GPS1_TP1")
	)
	(segment
		(start 108.67852 68.67312)
		(end 108.67852 65.32502)
		(width 0.2032)
		(layer "B.Cu")
		(net "RCB_GPS1_TP1")
	)
	(segment
		(start 111.08733 62.9162)
		(end 113.4216 62.9162)
		(width 0.2032)
		(layer "B.Cu")
		(net "RCB_GPS1_TP1")
	)
	(segment
		(start 108.67852 65.32502)
		(end 111.08733 62.9162)
		(width 0.2032)
		(layer "B.Cu")
		(net "RCB_GPS1_TP1")
	)
	(segment
		(start 114.0216 62.3162)
		(end 114.0216 58.1162)
		(width 0.2032)
		(layer "B.Cu")
		(net "RCB_GPS1_TP1")
	)
	(segment
		(start 110.9092 69.7286)
		(end 110.9216 69.7162)
		(width 0.2032)
		(layer "B.Cu")
		(net "RCB_GPS1_TP1")
	)
	(segment
		(start 108.67852 68.67312)
		(end 109.734 69.7286)
		(width 0.2032)
		(layer "B.Cu")
		(net "RCB_GPS1_TP1")
	)
	(segment
		(start 102.9716 69.7286)
		(end 105.0266 69.7286)
		(width 0.2032)
		(layer "F.Cu")
		(net "RCB_GPS1_RX")
	)
	(segment
		(start 109.6716 57.3162)
		(end 109.6716 56.464)
		(width 0.2032)
		(layer "F.Cu")
		(net "RCB_GPS1_RX")
	)
	(segment
		(start 108.8716 58.1162)
		(end 109.6716 57.3162)
		(width 0.2032)
		(layer "F.Cu")
		(net "RCB_GPS1_RX")
	)
	(via
		(at 102.9716 69.7286)
		(size 0.4064)
		(drill 0.2032)
		(layers "F.Cu" "B.Cu")
		(tenting
			(front yes)
			(back yes)
		)
		(net "RCB_GPS1_RX")
	)
	(via
		(at 108.8716 58.1162)
		(size 0.4064)
		(drill 0.2032)
		(layers "F.Cu" "B.Cu")
		(net "RCB_GPS1_RX")
	)
	(segment
		(start 108.8716 63.82861)
		(end 108.8716 58.1162)
		(width 0.2032)
		(layer "B.Cu")
		(net "RCB_GPS1_RX")
	)
	(segment
		(start 102.9716 69.7286)
		(end 108.8716 63.82861)
		(width 0.2032)
		(layer "B.Cu")
		(net "RCB_GPS1_RX")
	)
	(segment
		(start 121.3216 77.4162)
		(end 122.5466 77.4162)
		(width 0.2032)
		(layer "F.Cu")
		(net "RCB_GPS1_PIN12")
	)
	(segment
		(start 109.4716 63.72859)
		(end 111.6 63.72859)
		(width 0.2032)
		(layer "F.Cu")
		(net "RCB_GPS1_PIN12")
	)
	(segment
		(start 120.7232 78.4646)
		(end 120.7232 78.0146)
		(width 0.2032)
		(layer "F.Cu")
		(net "RCB_GPS1_PIN12")
	)
	(segment
		(start 120.7232 78.0146)
		(end 121.3216 77.4162)
		(width 0.2032)
		(layer "F.Cu")
		(net "RCB_GPS1_PIN12")
	)
	(segment
		(start 120.7216 78.4662)
		(end 120.7232 78.4646)
		(width 0.2032)
		(layer "F.Cu")
		(net "RCB_GPS1_PIN12")
	)
	(via
		(at 111.6 63.72859)
		(size 0.4064)
		(drill 0.2032)
		(layers "F.Cu" "B.Cu")
		(net "RCB_GPS1_PIN12")
	)
	(via
		(at 122.5466 77.4162)
		(size 0.4064)
		(drill 0.2032)
		(layers "F.Cu" "B.Cu")
		(net "RCB_GPS1_PIN12")
	)
	(segment
		(start 127.35756 71.65216)
		(end 127.5216 71.48813)
		(width 0.2032)
		(layer "B.Cu")
		(net "RCB_GPS1_PIN12")
	)
	(segment
		(start 122.5466 77.4162)
		(end 122.5466 73.45137)
		(width 0.2032)
		(layer "B.Cu")
		(net "RCB_GPS1_PIN12")
	)
	(segment
		(start 124.3458 71.65216)
		(end 127.35756 71.65216)
		(width 0.2032)
		(layer "B.Cu")
		(net "RCB_GPS1_PIN12")
	)
	(segment
		(start 122.5466 73.45137)
		(end 124.3458 71.65216)
		(width 0.2032)
		(layer "B.Cu")
		(net "RCB_GPS1_PIN12")
	)
	(segment
		(start 111.6 63.72859)
		(end 115.48074 63.72859)
		(width 0.2032)
		(layer "B.Cu")
		(net "RCB_GPS1_PIN12")
	)
	(segment
		(start 120.91835 69.1662)
		(end 127.0716 69.1662)
		(width 0.2032)
		(layer "B.Cu")
		(net "RCB_GPS1_PIN12")
	)
	(segment
		(start 127.0716 69.1662)
		(end 127.5216 69.6162)
		(width 0.2032)
		(layer "B.Cu")
		(net "RCB_GPS1_PIN12")
	)
	(segment
		(start 115.48074 63.72859)
		(end 120.91835 69.1662)
		(width 0.2032)
		(layer "B.Cu")
		(net "RCB_GPS1_PIN12")
	)
	(segment
		(start 127.5216 71.48813)
		(end 127.5216 69.6162)
		(width 0.2032)
		(layer "B.Cu")
		(net "RCB_GPS1_PIN12")
	)
	(segment
		(start 119.6216 77.4162)
		(end 119.9216 77.7162)
		(width 0.2032)
		(layer "F.Cu")
		(net "RCB_GPS1_PIN11")
	)
	(segment
		(start 119.9216 78.4662)
		(end 119.9216 77.7162)
		(width 0.2032)
		(layer "F.Cu")
		(net "RCB_GPS1_PIN11")
	)
	(segment
		(start 103.63399 63.72859)
		(end 105.0266 63.72859)
		(width 0.2032)
		(layer "F.Cu")
		(net "RCB_GPS1_PIN11")
	)
	(segment
		(start 117.9966 77.4162)
		(end 119.6216 77.4162)
		(width 0.2032)
		(layer "F.Cu")
		(net "RCB_GPS1_PIN11")
	)
	(segment
		(start 103.0216 63.1162)
		(end 103.63399 63.72859)
		(width 0.2032)
		(layer "F.Cu")
		(net "RCB_GPS1_PIN11")
	)
	(via
		(at 117.9966 77.4162)
		(size 0.4064)
		(drill 0.2032)
		(layers "F.Cu" "B.Cu")
		(net "RCB_GPS1_PIN11")
	)
	(via
		(at 103.0216 63.1162)
		(size 0.4064)
		(drill 0.2032)
		(layers "F.Cu" "B.Cu")
		(net "RCB_GPS1_PIN11")
	)
	(segment
		(start 117.2966 78.1162)
		(end 117.9966 77.4162)
		(width 0.2032)
		(layer "B.Cu")
		(net "RCB_GPS1_PIN11")
	)
	(segment
		(start 101.2955 63.69401)
		(end 101.87331 63.1162)
		(width 0.2032)
		(layer "B.Cu")
		(net "RCB_GPS1_PIN11")
	)
	(segment
		(start 102.3216 70.0162)
		(end 102.3216 69.26401)
		(width 0.2032)
		(layer "B.Cu")
		(net "RCB_GPS1_PIN11")
	)
	(segment
		(start 115.10488 78.1162)
		(end 117.2966 78.1162)
		(width 0.2032)
		(layer "B.Cu")
		(net "RCB_GPS1_PIN11")
	)
	(segment
		(start 105.51987 70.51447)
		(end 106.0791 71.0737)
		(width 0.2032)
		(layer "B.Cu")
		(net "RCB_GPS1_PIN11")
	)
	(segment
		(start 107.64188 75.93648)
		(end 108.2216 76.5162)
		(width 0.2032)
		(layer "B.Cu")
		(net "RCB_GPS1_PIN11")
	)
	(segment
		(start 101.2955 68.23791)
		(end 101.2955 63.69401)
		(width 0.2032)
		(layer "B.Cu")
		(net "RCB_GPS1_PIN11")
	)
	(segment
		(start 108.2216 76.5162)
		(end 113.50488 76.5162)
		(width 0.2032)
		(layer "B.Cu")
		(net "RCB_GPS1_PIN11")
	)
	(segment
		(start 113.50488 76.5162)
		(end 115.10488 78.1162)
		(width 0.2032)
		(layer "B.Cu")
		(net "RCB_GPS1_PIN11")
	)
	(segment
		(start 101.2955 68.23791)
		(end 102.3216 69.26401)
		(width 0.2032)
		(layer "B.Cu")
		(net "RCB_GPS1_PIN11")
	)
	(segment
		(start 106.0791 73.75342)
		(end 106.0791 71.0737)
		(width 0.2032)
		(layer "B.Cu")
		(net "RCB_GPS1_PIN11")
	)
	(segment
		(start 107.64188 75.93648)
		(end 107.64188 75.3162)
		(width 0.2032)
		(layer "B.Cu")
		(net "RCB_GPS1_PIN11")
	)
	(segment
		(start 106.0791 73.75342)
		(end 107.64188 75.3162)
		(width 0.2032)
		(layer "B.Cu")
		(net "RCB_GPS1_PIN11")
	)
	(segment
		(start 102.3216 70.0162)
		(end 102.81987 70.51447)
		(width 0.2032)
		(layer "B.Cu")
		(net "RCB_GPS1_PIN11")
	)
	(segment
		(start 102.81987 70.51447)
		(end 105.51987 70.51447)
		(width 0.2032)
		(layer "B.Cu")
		(net "RCB_GPS1_PIN11")
	)
	(segment
		(start 101.87331 63.1162)
		(end 103.0216 63.1162)
		(width 0.2032)
		(layer "B.Cu")
		(net "RCB_GPS1_PIN11")
	)
	(segment
		(start 121.1216 78.4428)
		(end 121.1232 78.4412)
		(width 0.2032)
		(layer "F.Cu")
		(net "NetR177_1")
	)
	(segment
		(start 121.1216 78.4662)
		(end 121.1216 78.4428)
		(width 0.2032)
		(layer "F.Cu")
		(net "NetR177_1")
	)
	(segment
		(start 122.5216 78.4412)
		(end 122.5466 78.4162)
		(width 0.2032)
		(layer "F.Cu")
		(net "NetR177_1")
	)
	(segment
		(start 121.1232 78.4412)
		(end 122.5216 78.4412)
		(width 0.2032)
		(layer "F.Cu")
		(net "NetR177_1")
	)
	(segment
		(start 118.0216 78.4912)
		(end 119.52 78.4912)
		(width 0.2032)
		(layer "F.Cu")
		(net "NetR176_1")
	)
	(segment
		(start 117.9966 78.5162)
		(end 118.0216 78.4912)
		(width 0.2032)
		(layer "F.Cu")
		(net "NetR176_1")
	)
	(segment
		(start 119.52 78.4912)
		(end 119.5216 78.4896)
		(width 0.2032)
		(layer "F.Cu")
		(net "NetR176_1")
	)
	(segment
		(start 119.5216 78.4896)
		(end 119.5216 78.4662)
		(width 0.2032)
		(layer "F.Cu")
		(net "NetR176_1")
	)
	(segment
		(start 194.7482 123.4162)
		(end 194.7716 123.4162)
		(width 0.2032)
		(layer "F.Cu")
		(net "NetR175_1")
	)
	(segment
		(start 194.7216 125.3412)
		(end 194.7466 125.3162)
		(width 0.2032)
		(layer "F.Cu")
		(net "NetR175_1")
	)
	(segment
		(start 194.7466 123.4178)
		(end 194.7482 123.4162)
		(width 0.2032)
		(layer "F.Cu")
		(net "NetR175_1")
	)
	(segment
		(start 194.7466 125.3162)
		(end 194.7466 123.4178)
		(width 0.2032)
		(layer "F.Cu")
		(net "NetR175_1")
	)
	(segment
		(start 194.82 121.8162)
		(end 194.8216 121.8146)
		(width 0.2032)
		(layer "F.Cu")
		(net "NetR171_1")
	)
	(segment
		(start 194.7716 121.8162)
		(end 194.82 121.8162)
		(width 0.2032)
		(layer "F.Cu")
		(net "NetR171_1")
	)
	(segment
		(start 194.8216 121.8146)
		(end 194.8216 120.3912)
		(width 0.2032)
		(layer "F.Cu")
		(net "NetR171_1")
	)
	(segment
		(start 108.6944 55.7662)
		(end 108.9738 55.7662)
		(width 0.2032)
		(layer "F.Cu")
		(net "NetR152_1")
	)
	(segment
		(start 108.669 56.7688)
		(end 108.669 55.7916)
		(width 0.2032)
		(layer "F.Cu")
		(net "NetR152_1")
	)
	(segment
		(start 108.669 55.7916)
		(end 108.6944 55.7662)
		(width 0.2032)
		(layer "F.Cu")
		(net "NetR152_1")
	)
	(segment
		(start 108.2453 57.1925)
		(end 108.669 56.7688)
		(width 0.2032)
		(layer "F.Cu")
		(net "NetR152_1")
	)
	(segment
		(start 107.59831 57.6162)
		(end 108.02201 57.1925)
		(width 0.2032)
		(layer "F.Cu")
		(net "NetR152_1")
	)
	(segment
		(start 106.8966 57.6162)
		(end 107.59831 57.6162)
		(width 0.2032)
		(layer "F.Cu")
		(net "NetR152_1")
	)
	(segment
		(start 108.02201 57.1925)
		(end 108.2453 57.1925)
		(width 0.2032)
		(layer "F.Cu")
		(net "NetR152_1")
	)
	(segment
		(start 111.921 57.4928)
		(end 112.2982 57.4928)
		(width 0.2032)
		(layer "F.Cu")
		(net "NetR150_1")
	)
	(segment
		(start 112.2982 57.4928)
		(end 112.4216 57.6162)
		(width 0.2032)
		(layer "F.Cu")
		(net "NetR150_1")
	)
	(segment
		(start 112.4216 57.6412)
		(end 112.4216 57.6162)
		(width 0.2032)
		(layer "F.Cu")
		(net "NetR150_1")
	)
	(segment
		(start 111.1716 56.7434)
		(end 111.921 57.4928)
		(width 0.2032)
		(layer "F.Cu")
		(net "NetR150_1")
	)
	(segment
		(start 111.1716 56.7434)
		(end 111.1716 56.464)
		(width 0.2032)
		(layer "F.Cu")
		(net "NetR150_1")
	)
	(segment
		(start 113.6754 52.7396)
		(end 113.7982 52.7396)
		(width 0.2032)
		(layer "F.Cu")
		(net "NetR147_1")
	)
	(segment
		(start 113.9216 52.6162)
		(end 113.9216 52.5912)
		(width 0.2032)
		(layer "F.Cu")
		(net "NetR147_1")
	)
	(segment
		(start 112.1488 54.2662)
		(end 113.6754 52.7396)
		(width 0.2032)
		(layer "F.Cu")
		(net "NetR147_1")
	)
	(segment
		(start 113.7982 52.7396)
		(end 113.9216 52.6162)
		(width 0.2032)
		(layer "F.Cu")
		(net "NetR147_1")
	)
	(segment
		(start 111.8694 54.2662)
		(end 112.1488 54.2662)
		(width 0.2032)
		(layer "F.Cu")
		(net "NetR147_1")
	)
	(segment
		(start 190.4216 133.5412)
		(end 191.4194 133.5412)
		(width 0.2032)
		(layer "F.Cu")
		(net "NetR146_1")
	)
	(segment
		(start 191.4194 133.5412)
		(end 191.8944 133.0662)
		(width 0.2032)
		(layer "F.Cu")
		(net "NetR146_1")
	)
	(segment
		(start 191.8944 133.0662)
		(end 192.1738 133.0662)
		(width 0.2032)
		(layer "F.Cu")
		(net "NetR146_1")
	)
	(segment
		(start 195.8213 134.9162)
		(end 196.5466 134.9162)
		(width 0.2032)
		(layer "F.Cu")
		(net "NetR145_1")
	)
	(segment
		(start 194.3716 134.0434)
		(end 194.3716 133.764)
		(width 0.2032)
		(layer "F.Cu")
		(net "NetR145_1")
	)
	(segment
		(start 194.397 134.0688)
		(end 194.9739 134.0688)
		(width 0.2032)
		(layer "F.Cu")
		(net "NetR145_1")
	)
	(segment
		(start 194.3716 134.0434)
		(end 194.397 134.0688)
		(width 0.2032)
		(layer "F.Cu")
		(net "NetR145_1")
	)
	(segment
		(start 194.9739 134.0688)
		(end 195.8213 134.9162)
		(width 0.2032)
		(layer "F.Cu")
		(net "NetR145_1")
	)
	(segment
		(start 109.6716 53.5684)
		(end 109.6716 51.7662)
		(width 0.2032)
		(layer "F.Cu")
		(net "NetR144_1")
	)
	(segment
		(start 109.4216 51.5162)
		(end 109.6716 51.7662)
		(width 0.2032)
		(layer "F.Cu")
		(net "NetR144_1")
	)
	(segment
		(start 109.4216 51.5162)
		(end 109.4216 51.4912)
		(width 0.2032)
		(layer "F.Cu")
		(net "NetR144_1")
	)
	(segment
		(start 195.0694 131.5662)
		(end 195.3488 131.5662)
		(width 0.2032)
		(layer "F.Cu")
		(net "NetR143_1")
	)
	(segment
		(start 195.3742 131.5408)
		(end 195.3742 130.9636)
		(width 0.2032)
		(layer "F.Cu")
		(net "NetR143_1")
	)
	(segment
		(start 196.2216 130.1162)
		(end 196.2216 130.0912)
		(width 0.2032)
		(layer "F.Cu")
		(net "NetR143_1")
	)
	(segment
		(start 195.3742 130.9636)
		(end 196.2216 130.1162)
		(width 0.2032)
		(layer "F.Cu")
		(net "NetR143_1")
	)
	(segment
		(start 195.3488 131.5662)
		(end 195.3742 131.5408)
		(width 0.2032)
		(layer "F.Cu")
		(net "NetR143_1")
	)
	(segment
		(start 192.2216 129.3162)
		(end 192.8716 129.9662)
		(width 0.2032)
		(layer "F.Cu")
		(net "NetR142_1")
	)
	(segment
		(start 192.2216 129.3162)
		(end 192.2216 129.2912)
		(width 0.2032)
		(layer "F.Cu")
		(net "NetR142_1")
	)
	(segment
		(start 192.8716 130.8684)
		(end 192.8716 129.9662)
		(width 0.2032)
		(layer "F.Cu")
		(net "NetR142_1")
	)
	(segment
		(start 193.2216 129.2662)
		(end 193.3462 129.3908)
		(width 0.2032)
		(layer "F.Cu")
		(net "M2_GPS2_TX")
	)
	(segment
		(start 201.2216 119.0412)
		(end 201.7216 119.0412)
		(width 0.2032)
		(layer "F.Cu")
		(net "M2_GPS2_TX")
	)
	(segment
		(start 193.3462 130.843)
		(end 193.3462 129.3908)
		(width 0.2032)
		(layer "F.Cu")
		(net "M2_GPS2_TX")
	)
	(segment
		(start 201.7216 121.7662)
		(end 201.7216 119.0412)
		(width 0.2032)
		(layer "F.Cu")
		(net "M2_GPS2_TX")
	)
	(segment
		(start 193.3462 130.843)
		(end 193.3716 130.8684)
		(width 0.2032)
		(layer "F.Cu")
		(net "M2_GPS2_TX")
	)
	(via
		(at 201.2216 119.0412)
		(size 0.4064)
		(drill 0.2032)
		(layers "F.Cu" "B.Cu")
		(net "M2_GPS2_TX")
	)
	(via
		(at 193.2216 129.2662)
		(size 0.4064)
		(drill 0.2032)
		(layers "F.Cu" "B.Cu")
		(net "M2_GPS2_TX")
	)
	(segment
		(start 194.7466 126.39965)
		(end 194.7466 124.8912)
		(width 0.2032)
		(layer "In2.Cu")
		(net "M2_GPS2_TX")
	)
	(segment
		(start 193.2216 127.92465)
		(end 194.7466 126.39965)
		(width 0.2032)
		(layer "In2.Cu")
		(net "M2_GPS2_TX")
	)
	(segment
		(start 199.8966 117.7162)
		(end 201.2216 119.0412)
		(width 0.2032)
		(layer "In2.Cu")
		(net "M2_GPS2_TX")
	)
	(segment
		(start 196.7216 122.9162)
		(end 196.7216 118.2162)
		(width 0.2032)
		(layer "In2.Cu")
		(net "M2_GPS2_TX")
	)
	(segment
		(start 197.2216 117.7162)
		(end 199.8966 117.7162)
		(width 0.2032)
		(layer "In2.Cu")
		(net "M2_GPS2_TX")
	)
	(segment
		(start 193.2216 129.2662)
		(end 193.2216 127.92465)
		(width 0.2032)
		(layer "In2.Cu")
		(net "M2_GPS2_TX")
	)
	(segment
		(start 196.7216 118.2162)
		(end 197.2216 117.7162)
		(width 0.2032)
		(layer "In2.Cu")
		(net "M2_GPS2_TX")
	)
	(segment
		(start 194.7466 124.8912)
		(end 196.7216 122.9162)
		(width 0.2032)
		(layer "In2.Cu")
		(net "M2_GPS2_TX")
	)
	(segment
		(start 205.7216 121.7662)
		(end 205.7216 118.5412)
		(width 0.2032)
		(layer "F.Cu")
		(net "M2_GPS2_TP2")
	)
	(segment
		(start 195.0694 132.0662)
		(end 195.0948 132.0916)
		(width 0.2032)
		(layer "F.Cu")
		(net "M2_GPS2_TP2")
	)
	(segment
		(start 204.7216 118.5412)
		(end 205.7216 118.5412)
		(width 0.2032)
		(layer "F.Cu")
		(net "M2_GPS2_TP2")
	)
	(segment
		(start 195.0948 132.0916)
		(end 197.047 132.0916)
		(width 0.2032)
		(layer "F.Cu")
		(net "M2_GPS2_TP2")
	)
	(via
		(at 197.1716 132.2162)
		(size 0.4064)
		(drill 0.2032)
		(layers "F.Cu" "B.Cu")
		(net "M2_GPS2_TP2")
	)
	(via
		(at 204.7216 118.5412)
		(size 0.4064)
		(drill 0.2032)
		(layers "F.Cu" "B.Cu")
		(net "M2_GPS2_TP2")
	)
	(segment
		(start 197.39527 118.4162)
		(end 199.5216 118.4162)
		(width 0.2032)
		(layer "In2.Cu")
		(net "M2_GPS2_TP2")
	)
	(segment
		(start 195.47713 126.74633)
		(end 197.0216 125.20186)
		(width 0.2032)
		(layer "In2.Cu")
		(net "M2_GPS2_TP2")
	)
	(segment
		(start 194.93156 126.96067)
		(end 195.47713 126.96067)
		(width 0.2032)
		(layer "In2.Cu")
		(net "M2_GPS2_TP2")
	)
	(segment
		(start 195.78497 130.82957)
		(end 197.1716 132.2162)
		(width 0.2032)
		(layer "In2.Cu")
		(net "M2_GPS2_TP2")
	)
	(segment
		(start 195.50734 130.82957)
		(end 195.78497 130.82957)
		(width 0.2032)
		(layer "In2.Cu")
		(net "M2_GPS2_TP2")
	)
	(segment
		(start 201.6216 119.6162)
		(end 202.6966 118.5412)
		(width 0.2032)
		(layer "In2.Cu")
		(net "M2_GPS2_TP2")
	)
	(segment
		(start 197.0216 123.78654)
		(end 197.2216 123.58654)
		(width 0.2032)
		(layer "In2.Cu")
		(net "M2_GPS2_TP2")
	)
	(segment
		(start 197.2216 123.58654)
		(end 197.2216 118.58987)
		(width 0.2032)
		(layer "In2.Cu")
		(net "M2_GPS2_TP2")
	)
	(segment
		(start 197.2216 118.58987)
		(end 197.39527 118.4162)
		(width 0.2032)
		(layer "In2.Cu")
		(net "M2_GPS2_TP2")
	)
	(segment
		(start 200.7216 119.6162)
		(end 201.6216 119.6162)
		(width 0.2032)
		(layer "In2.Cu")
		(net "M2_GPS2_TP2")
	)
	(segment
		(start 194.10577 129.42799)
		(end 195.50734 130.82957)
		(width 0.2032)
		(layer "In2.Cu")
		(net "M2_GPS2_TP2")
	)
	(segment
		(start 194.10577 129.42799)
		(end 194.10577 127.78647)
		(width 0.2032)
		(layer "In2.Cu")
		(net "M2_GPS2_TP2")
	)
	(segment
		(start 194.10577 127.78647)
		(end 194.93156 126.96067)
		(width 0.2032)
		(layer "In2.Cu")
		(net "M2_GPS2_TP2")
	)
	(segment
		(start 202.6966 118.5412)
		(end 204.7216 118.5412)
		(width 0.2032)
		(layer "In2.Cu")
		(net "M2_GPS2_TP2")
	)
	(segment
		(start 199.5216 118.4162)
		(end 200.7216 119.6162)
		(width 0.2032)
		(layer "In2.Cu")
		(net "M2_GPS2_TP2")
	)
	(segment
		(start 195.47713 126.96067)
		(end 195.47713 126.74633)
		(width 0.2032)
		(layer "In2.Cu")
		(net "M2_GPS2_TP2")
	)
	(segment
		(start 197.0216 125.20186)
		(end 197.0216 123.78654)
		(width 0.2032)
		(layer "In2.Cu")
		(net "M2_GPS2_TP2")
	)
	(segment
		(start 193.8716 134.4162)
		(end 195.2716 135.8162)
		(width 0.2032)
		(layer "F.Cu")
		(net "M2_GPS2_TP1")
	)
	(segment
		(start 210.5216 131.5162)
		(end 210.5216 131.5162)
		(width 0.2032)
		(layer "F.Cu")
		(net "M2_GPS2_TP1")
	)
	(segment
		(start 193.8716 134.4162)
		(end 193.8716 133.764)
		(width 0.2032)
		(layer "F.Cu")
		(net "M2_GPS2_TP1")
	)
	(segment
		(start 210.5216 131.5162)
		(end 211.5216 131.5162)
		(width 0.2032)
		(layer "F.Cu")
		(net "M2_GPS2_TP1")
	)
	(via
		(at 195.2716 135.8162)
		(size 0.4064)
		(drill 0.2032)
		(layers "F.Cu" "B.Cu")
		(net "M2_GPS2_TP1")
	)
	(via
		(at 211.5216 131.5162)
		(size 0.4064)
		(drill 0.2032)
		(layers "F.Cu" "B.Cu")
		(net "M2_GPS2_TP1")
	)
	(segment
		(start 195.2716 135.8162)
		(end 198.16389 135.8162)
		(width 0.2032)
		(layer "B.Cu")
		(net "M2_GPS2_TP1")
	)
	(segment
		(start 211.5216 134.41389)
		(end 211.5216 131.5162)
		(width 0.2032)
		(layer "B.Cu")
		(net "M2_GPS2_TP1")
	)
	(segment
		(start 198.16389 135.85849)
		(end 198.16389 135.8162)
		(width 0.2032)
		(layer "B.Cu")
		(net "M2_GPS2_TP1")
	)
	(segment
		(start 199.3527 137.0473)
		(end 211.07147 137.0473)
		(width 0.2032)
		(layer "B.Cu")
		(net "M2_GPS2_TP1")
	)
	(segment
		(start 198.16389 135.85849)
		(end 199.3527 137.0473)
		(width 0.2032)
		(layer "B.Cu")
		(net "M2_GPS2_TP1")
	)
	(segment
		(start 211.07147 137.0473)
		(end 211.1905 136.92827)
		(width 0.2032)
		(layer "B.Cu")
		(net "M2_GPS2_TP1")
	)
	(segment
		(start 211.1905 136.92827)
		(end 211.1905 134.74499)
		(width 0.2032)
		(layer "B.Cu")
		(net "M2_GPS2_TP1")
	)
	(segment
		(start 211.1905 134.74499)
		(end 211.5216 134.41389)
		(width 0.2032)
		(layer "B.Cu")
		(net "M2_GPS2_TP1")
	)
	(segment
		(start 189.3466 132.5912)
		(end 192.1488 132.5912)
		(width 0.2032)
		(layer "F.Cu")
		(net "M2_GPS2_RX")
	)
	(segment
		(start 202.2216 119.7412)
		(end 202.5216 119.7412)
		(width 0.2032)
		(layer "F.Cu")
		(net "M2_GPS2_RX")
	)
	(segment
		(start 189.3216 133.4662)
		(end 189.3216 132.6162)
		(width 0.2032)
		(layer "F.Cu")
		(net "M2_GPS2_RX")
	)
	(segment
		(start 189.3216 132.6162)
		(end 189.3466 132.5912)
		(width 0.2032)
		(layer "F.Cu")
		(net "M2_GPS2_RX")
	)
	(segment
		(start 192.1488 132.5912)
		(end 192.1738 132.5662)
		(width 0.2032)
		(layer "F.Cu")
		(net "M2_GPS2_RX")
	)
	(segment
		(start 202.2216 121.7662)
		(end 202.2216 119.7412)
		(width 0.2032)
		(layer "F.Cu")
		(net "M2_GPS2_RX")
	)
	(via
		(at 202.5216 119.7412)
		(size 0.4064)
		(drill 0.2032)
		(layers "F.Cu" "B.Cu")
		(net "M2_GPS2_RX")
	)
	(via
		(at 189.3216 132.6162)
		(size 0.4064)
		(drill 0.2032)
		(layers "F.Cu" "B.Cu")
		(net "M2_GPS2_RX")
	)
	(segment
		(start 197.61405 133.54799)
		(end 198.90045 133.54799)
		(width 0.2032)
		(layer "In2.Cu")
		(net "M2_GPS2_RX")
	)
	(segment
		(start 198.505 126.7328)
		(end 202.09488 123.14292)
		(width 0.2032)
		(layer "In2.Cu")
		(net "M2_GPS2_RX")
	)
	(segment
		(start 191.42283 133.4844)
		(end 197.55046 133.4844)
		(width 0.2032)
		(layer "In2.Cu")
		(net "M2_GPS2_RX")
	)
	(segment
		(start 197.55046 133.4844)
		(end 197.61405 133.54799)
		(width 0.2032)
		(layer "In2.Cu")
		(net "M2_GPS2_RX")
	)
	(segment
		(start 189.3216 132.6162)
		(end 190.55463 132.6162)
		(width 0.2032)
		(layer "In2.Cu")
		(net "M2_GPS2_RX")
	)
	(segment
		(start 202.09488 123.14292)
		(end 202.09488 120.16792)
		(width 0.2032)
		(layer "In2.Cu")
		(net "M2_GPS2_RX")
	)
	(segment
		(start 194.4898 128.55301)
		(end 196.31002 126.7328)
		(width 0.2032)
		(layer "In2.Cu")
		(net "M2_GPS2_RX")
	)
	(segment
		(start 196.31002 126.7328)
		(end 198.505 126.7328)
		(width 0.2032)
		(layer "In2.Cu")
		(net "M2_GPS2_RX")
	)
	(segment
		(start 190.55463 132.6162)
		(end 191.42283 133.4844)
		(width 0.2032)
		(layer "In2.Cu")
		(net "M2_GPS2_RX")
	)
	(segment
		(start 194.4898 129.34506)
		(end 195.64412 130.49937)
		(width 0.2032)
		(layer "In2.Cu")
		(net "M2_GPS2_RX")
	)
	(segment
		(start 196.96542 130.49937)
		(end 199.15339 132.68734)
		(width 0.2032)
		(layer "In2.Cu")
		(net "M2_GPS2_RX")
	)
	(segment
		(start 194.4898 129.34506)
		(end 194.4898 128.55301)
		(width 0.2032)
		(layer "In2.Cu")
		(net "M2_GPS2_RX")
	)
	(segment
		(start 199.15339 133.29505)
		(end 199.15339 132.68734)
		(width 0.2032)
		(layer "In2.Cu")
		(net "M2_GPS2_RX")
	)
	(segment
		(start 202.09488 120.16792)
		(end 202.5216 119.7412)
		(width 0.2032)
		(layer "In2.Cu")
		(net "M2_GPS2_RX")
	)
	(segment
		(start 195.64412 130.49937)
		(end 196.96542 130.49937)
		(width 0.2032)
		(layer "In2.Cu")
		(net "M2_GPS2_RX")
	)
	(segment
		(start 198.90045 133.54799)
		(end 199.15339 133.29505)
		(width 0.2032)
		(layer "In2.Cu")
		(net "M2_GPS2_RX")
	)
	(segment
		(start 192.2216 123.6162)
		(end 192.8216 123.0162)
		(width 0.2032)
		(layer "F.Cu")
		(net "M2_GPS2_PIN12")
	)
	(segment
		(start 211.8216 120.0412)
		(end 212.2216 120.0412)
		(width 0.2032)
		(layer "F.Cu")
		(net "M2_GPS2_PIN12")
	)
	(segment
		(start 192.2216 125.22217)
		(end 192.34063 125.3412)
		(width 0.2032)
		(layer "F.Cu")
		(net "M2_GPS2_PIN12")
	)
	(segment
		(start 192.8216 123.0162)
		(end 193.4716 123.0162)
		(width 0.2032)
		(layer "F.Cu")
		(net "M2_GPS2_PIN12")
	)
	(segment
		(start 192.2216 125.22217)
		(end 192.2216 123.6162)
		(width 0.2032)
		(layer "F.Cu")
		(net "M2_GPS2_PIN12")
	)
	(segment
		(start 192.34063 125.3412)
		(end 194.0216 125.3412)
		(width 0.2032)
		(layer "F.Cu")
		(net "M2_GPS2_PIN12")
	)
	(segment
		(start 212.2216 121.7662)
		(end 212.2216 120.0412)
		(width 0.2032)
		(layer "F.Cu")
		(net "M2_GPS2_PIN12")
	)
	(via
		(at 192.34063 125.3412)
		(size 0.4064)
		(drill 0.2032)
		(layers "F.Cu" "B.Cu")
		(net "M2_GPS2_PIN12")
	)
	(via
		(at 211.8216 120.0412)
		(size 0.4064)
		(drill 0.2032)
		(layers "F.Cu" "B.Cu")
		(net "M2_GPS2_PIN12")
	)
	(segment
		(start 191.0892 123.45726)
		(end 192.34063 124.70869)
		(width 0.2032)
		(layer "In2.Cu")
		(net "M2_GPS2_PIN12")
	)
	(segment
		(start 195.90725 121.0162)
		(end 196.3534 120.57006)
		(width 0.2032)
		(layer "In2.Cu")
		(net "M2_GPS2_PIN12")
	)
	(segment
		(start 191.0892 121.36979)
		(end 192.06779 120.3912)
		(width 0.2032)
		(layer "In2.Cu")
		(net "M2_GPS2_PIN12")
	)
	(segment
		(start 191.0892 123.45726)
		(end 191.0892 121.36979)
		(width 0.2032)
		(layer "In2.Cu")
		(net "M2_GPS2_PIN12")
	)
	(segment
		(start 192.34063 125.3412)
		(end 192.34063 124.70869)
		(width 0.2032)
		(layer "In2.Cu")
		(net "M2_GPS2_PIN12")
	)
	(segment
		(start 211.8216 120.0412)
		(end 211.8216 118.3162)
		(width 0.2032)
		(layer "In2.Cu")
		(net "M2_GPS2_PIN12")
	)
	(segment
		(start 196.3534 117.3844)
		(end 197.9216 115.8162)
		(width 0.2032)
		(layer "In2.Cu")
		(net "M2_GPS2_PIN12")
	)
	(segment
		(start 194.94974 120.3912)
		(end 195.57474 121.0162)
		(width 0.2032)
		(layer "In2.Cu")
		(net "M2_GPS2_PIN12")
	)
	(segment
		(start 192.06779 120.3912)
		(end 194.94974 120.3912)
		(width 0.2032)
		(layer "In2.Cu")
		(net "M2_GPS2_PIN12")
	)
	(segment
		(start 209.3216 115.8162)
		(end 211.8216 118.3162)
		(width 0.2032)
		(layer "In2.Cu")
		(net "M2_GPS2_PIN12")
	)
	(segment
		(start 195.57474 121.0162)
		(end 195.90725 121.0162)
		(width 0.2032)
		(layer "In2.Cu")
		(net "M2_GPS2_PIN12")
	)
	(segment
		(start 196.3534 120.57006)
		(end 196.3534 117.3844)
		(width 0.2032)
		(layer "In2.Cu")
		(net "M2_GPS2_PIN12")
	)
	(segment
		(start 197.9216 115.8162)
		(end 209.3216 115.8162)
		(width 0.2032)
		(layer "In2.Cu")
		(net "M2_GPS2_PIN12")
	)
	(segment
		(start 192.0466 120.3912)
		(end 192.6341 120.3912)
		(width 0.2032)
		(layer "F.Cu")
		(net "M2_GPS2_PIN11")
	)
	(segment
		(start 212.7216 121.7662)
		(end 212.7216 117.71772)
		(width 0.2032)
		(layer "F.Cu")
		(net "M2_GPS2_PIN11")
	)
	(segment
		(start 192.6341 120.3912)
		(end 193.2216 120.3912)
		(width 0.2032)
		(layer "F.Cu")
		(net "M2_GPS2_PIN11")
	)
	(segment
		(start 191.8216 120.6162)
		(end 192.0466 120.3912)
		(width 0.2032)
		(layer "F.Cu")
		(net "M2_GPS2_PIN11")
	)
	(segment
		(start 192.6341 118.6037)
		(end 193.3216 117.9162)
		(width 0.2032)
		(layer "F.Cu")
		(net "M2_GPS2_PIN11")
	)
	(segment
		(start 192.6341 120.3912)
		(end 192.6341 118.6037)
		(width 0.2032)
		(layer "F.Cu")
		(net "M2_GPS2_PIN11")
	)
	(segment
		(start 191.8216 120.92686)
		(end 191.8216 120.6162)
		(width 0.2032)
		(layer "F.Cu")
		(net "M2_GPS2_PIN11")
	)
	(segment
		(start 193.10934 122.2146)
		(end 193.47 122.2146)
		(width 0.2032)
		(layer "F.Cu")
		(net "M2_GPS2_PIN11")
	)
	(segment
		(start 191.8216 120.92686)
		(end 193.10934 122.2146)
		(width 0.2032)
		(layer "F.Cu")
		(net "M2_GPS2_PIN11")
	)
	(segment
		(start 193.47 122.2146)
		(end 193.4716 122.2162)
		(width 0.2032)
		(layer "F.Cu")
		(net "M2_GPS2_PIN11")
	)
	(segment
		(start 211.92084 116.91696)
		(end 212.7216 117.71772)
		(width 0.2032)
		(layer "F.Cu")
		(net "M2_GPS2_PIN11")
	)
	(via
		(at 211.92084 116.91696)
		(size 0.4064)
		(drill 0.2032)
		(layers "F.Cu" "B.Cu")
		(net "M2_GPS2_PIN11")
	)
	(via
		(at 193.3216 117.9162)
		(size 0.4064)
		(drill 0.2032)
		(layers "F.Cu" "B.Cu")
		(net "M2_GPS2_PIN11")
	)
	(segment
		(start 211.92084 116.91696)
		(end 211.9216 116.9162)
		(width 0.2032)
		(layer "In3.Cu")
		(net "M2_GPS2_PIN11")
	)
	(segment
		(start 194.5216 115.1162)
		(end 210.1216 115.1162)
		(width 0.2032)
		(layer "In3.Cu")
		(net "M2_GPS2_PIN11")
	)
	(segment
		(start 193.3216 117.9162)
		(end 193.3216 116.3162)
		(width 0.2032)
		(layer "In3.Cu")
		(net "M2_GPS2_PIN11")
	)
	(segment
		(start 210.1216 115.1162)
		(end 211.9216 116.9162)
		(width 0.2032)
		(layer "In3.Cu")
		(net "M2_GPS2_PIN11")
	)
	(segment
		(start 193.3216 116.3162)
		(end 194.5216 115.1162)
		(width 0.2032)
		(layer "In3.Cu")
		(net "M2_GPS2_PIN11")
	)
	(segment
		(start 110.5216 51.5162)
		(end 110.5216 51.4662)
		(width 0.2032)
		(layer "F.Cu")
		(net "M2_GPS1_TX")
	)
	(segment
		(start 110.1716 53.5684)
		(end 110.1716 51.8162)
		(width 0.2032)
		(layer "F.Cu")
		(net "M2_GPS1_TX")
	)
	(segment
		(start 123.8966 58.5162)
		(end 126.6216 58.5162)
		(width 0.2032)
		(layer "F.Cu")
		(net "M2_GPS1_TX")
	)
	(segment
		(start 110.1716 51.8162)
		(end 110.4966 51.4912)
		(width 0.2032)
		(layer "F.Cu")
		(net "M2_GPS1_TX")
	)
	(segment
		(start 126.6216 58.5162)
		(end 126.6216 58.0162)
		(width 0.2032)
		(layer "F.Cu")
		(net "M2_GPS1_TX")
	)
	(via
		(at 126.6216 58.0162)
		(size 0.4064)
		(drill 0.2032)
		(layers "F.Cu" "B.Cu")
		(net "M2_GPS1_TX")
	)
	(via
		(at 110.5216 51.5162)
		(size 0.4064)
		(drill 0.2032)
		(layers "F.Cu" "B.Cu")
		(net "M2_GPS1_TX")
	)
	(segment
		(start 115.22775 53.4162)
		(end 116.6216 53.4162)
		(width 0.2032)
		(layer "B.Cu")
		(net "M2_GPS1_TX")
	)
	(segment
		(start 116.6216 53.4162)
		(end 121.2216 58.0162)
		(width 0.2032)
		(layer "B.Cu")
		(net "M2_GPS1_TX")
	)
	(segment
		(start 110.5216 51.5162)
		(end 113.32775 51.5162)
		(width 0.2032)
		(layer "B.Cu")
		(net "M2_GPS1_TX")
	)
	(segment
		(start 121.2216 58.0162)
		(end 126.6216 58.0162)
		(width 0.2032)
		(layer "B.Cu")
		(net "M2_GPS1_TX")
	)
	(segment
		(start 113.32775 51.5162)
		(end 115.22775 53.4162)
		(width 0.2032)
		(layer "B.Cu")
		(net "M2_GPS1_TX")
	)
	(segment
		(start 111.8694 54.7662)
		(end 113.0216 54.7662)
		(width 0.2032)
		(layer "F.Cu")
		(net "M2_GPS1_TP2")
	)
	(segment
		(start 127.1216 62.5162)
		(end 127.1216 61.5162)
		(width 0.2032)
		(layer "F.Cu")
		(net "M2_GPS1_TP2")
	)
	(segment
		(start 113.0216 54.7662)
		(end 115.1216 52.6662)
		(width 0.2032)
		(layer "F.Cu")
		(net "M2_GPS1_TP2")
	)
	(segment
		(start 123.8966 62.5162)
		(end 127.1216 62.5162)
		(width 0.2032)
		(layer "F.Cu")
		(net "M2_GPS1_TP2")
	)
	(via
		(at 127.1216 61.5162)
		(size 0.4064)
		(drill 0.2032)
		(layers "F.Cu" "B.Cu")
		(net "M2_GPS1_TP2")
	)
	(via
		(at 115.1216 52.6662)
		(size 0.4064)
		(drill 0.2032)
		(layers "F.Cu" "B.Cu")
		(net "M2_GPS1_TP2")
	)
	(segment
		(start 127.1216 61.5162)
		(end 129.5216 59.1162)
		(width 0.2032)
		(layer "B.Cu")
		(net "M2_GPS1_TP2")
	)
	(segment
		(start 115.1216 52.6662)
		(end 126.3716 52.6662)
		(width 0.2032)
		(layer "B.Cu")
		(net "M2_GPS1_TP2")
	)
	(segment
		(start 129.5216 59.1162)
		(end 129.5216 55.8162)
		(width 0.2032)
		(layer "B.Cu")
		(net "M2_GPS1_TP2")
	)
	(segment
		(start 126.3716 52.6662)
		(end 129.5216 55.8162)
		(width 0.2032)
		(layer "B.Cu")
		(net "M2_GPS1_TP2")
	)
	(segment
		(start 113.10896 61.70357)
		(end 113.1216 61.7162)
		(width 0.2032)
		(layer "F.Cu")
		(net "M2_GPS1_TP1")
	)
	(segment
		(start 110.6716 57.3162)
		(end 111.1216 57.7662)
		(width 0.2032)
		(layer "F.Cu")
		(net "M2_GPS1_TP1")
	)
	(segment
		(start 112.8216 68.9162)
		(end 112.8216 61.8226)
		(width 0.2032)
		(layer "F.Cu")
		(net "M2_GPS1_TP1")
	)
	(segment
		(start 112.8216 70.1162)
		(end 112.8216 68.9162)
		(width 0.2032)
		(layer "F.Cu")
		(net "M2_GPS1_TP1")
	)
	(segment
		(start 112.8216 61.8226)
		(end 112.94063 61.70357)
		(width 0.2032)
		(layer "F.Cu")
		(net "M2_GPS1_TP1")
	)
	(segment
		(start 112.94063 61.70357)
		(end 113.10896 61.70357)
		(width 0.2032)
		(layer "F.Cu")
		(net "M2_GPS1_TP1")
	)
	(segment
		(start 110.6716 57.3162)
		(end 110.6716 56.464)
		(width 0.2032)
		(layer "F.Cu")
		(net "M2_GPS1_TP1")
	)
	(segment
		(start 112.76005 70.05465)
		(end 112.8216 70.1162)
		(width 0.2032)
		(layer "F.Cu")
		(net "M2_GPS1_TP1")
	)
	(via
		(at 111.1216 57.7662)
		(size 0.4064)
		(drill 0.2032)
		(layers "F.Cu" "B.Cu")
		(net "M2_GPS1_TP1")
	)
	(via
		(at 113.1216 61.7162)
		(size 0.4064)
		(drill 0.2032)
		(layers "F.Cu" "B.Cu")
		(net "M2_GPS1_TP1")
	)
	(segment
		(start 111.1216 57.7662)
		(end 113.1216 59.7662)
		(width 0.2032)
		(layer "B.Cu")
		(net "M2_GPS1_TP1")
	)
	(segment
		(start 113.1216 61.7162)
		(end 113.1216 59.7662)
		(width 0.2032)
		(layer "B.Cu")
		(net "M2_GPS1_TP1")
	)
	(segment
		(start 125.9216 59.3162)
		(end 125.9216 59.0162)
		(width 0.2032)
		(layer "F.Cu")
		(net "M2_GPS1_RX")
	)
	(segment
		(start 108.4962 55.2916)
		(end 108.9484 55.2916)
		(width 0.2032)
		(layer "F.Cu")
		(net "M2_GPS1_RX")
	)
	(segment
		(start 123.8966 59.0162)
		(end 125.9216 59.0162)
		(width 0.2032)
		(layer "F.Cu")
		(net "M2_GPS1_RX")
	)
	(segment
		(start 107.0716 56.7162)
		(end 108.4962 55.2916)
		(width 0.2032)
		(layer "F.Cu")
		(net "M2_GPS1_RX")
	)
	(segment
		(start 108.9484 55.2916)
		(end 108.9738 55.2662)
		(width 0.2032)
		(layer "F.Cu")
		(net "M2_GPS1_RX")
	)
	(via
		(at 125.9216 59.3162)
		(size 0.4064)
		(drill 0.2032)
		(layers "F.Cu" "B.Cu")
		(net "M2_GPS1_RX")
	)
	(via
		(at 107.0716 56.7162)
		(size 0.4064)
		(drill 0.2032)
		(layers "F.Cu" "B.Cu")
		(net "M2_GPS1_RX")
	)
	(segment
		(start 115.92669 54.6662)
		(end 116.8716 54.6662)
		(width 0.2032)
		(layer "B.Cu")
		(net "M2_GPS1_RX")
	)
	(segment
		(start 116.8716 54.6662)
		(end 121.5216 59.3162)
		(width 0.2032)
		(layer "B.Cu")
		(net "M2_GPS1_RX")
	)
	(segment
		(start 121.5216 59.3162)
		(end 125.9216 59.3162)
		(width 0.2032)
		(layer "B.Cu")
		(net "M2_GPS1_RX")
	)
	(segment
		(start 110.39529 52.03185)
		(end 113.29234 52.03185)
		(width 0.2032)
		(layer "B.Cu")
		(net "M2_GPS1_RX")
	)
	(segment
		(start 113.29234 52.03185)
		(end 115.92669 54.6662)
		(width 0.2032)
		(layer "B.Cu")
		(net "M2_GPS1_RX")
	)
	(segment
		(start 109.9216 54.7162)
		(end 109.9216 52.50554)
		(width 0.2032)
		(layer "B.Cu")
		(net "M2_GPS1_RX")
	)
	(segment
		(start 109.9216 52.50554)
		(end 110.39529 52.03185)
		(width 0.2032)
		(layer "B.Cu")
		(net "M2_GPS1_RX")
	)
	(segment
		(start 107.9216 56.7162)
		(end 109.9216 54.7162)
		(width 0.2032)
		(layer "B.Cu")
		(net "M2_GPS1_RX")
	)
	(segment
		(start 107.0716 56.7162)
		(end 107.9216 56.7162)
		(width 0.2032)
		(layer "B.Cu")
		(net "M2_GPS1_RX")
	)
	(segment
		(start 122.2216 81.2162)
		(end 122.2466 81.2162)
		(width 0.2032)
		(layer "F.Cu")
		(net "M2_GPS1_PIN12")
	)
	(segment
		(start 123.8966 69.0162)
		(end 125.6216 69.0162)
		(width 0.2032)
		(layer "F.Cu")
		(net "M2_GPS1_PIN12")
	)
	(segment
		(start 120.7216 80.3162)
		(end 120.7216 79.7662)
		(width 0.2032)
		(layer "F.Cu")
		(net "M2_GPS1_PIN12")
	)
	(segment
		(start 120.7216 80.3162)
		(end 121.6216 81.2162)
		(width 0.2032)
		(layer "F.Cu")
		(net "M2_GPS1_PIN12")
	)
	(segment
		(start 125.6216 69.0162)
		(end 125.6216 68.6162)
		(width 0.2032)
		(layer "F.Cu")
		(net "M2_GPS1_PIN12")
	)
	(segment
		(start 121.6216 81.2162)
		(end 122.2216 81.2162)
		(width 0.2032)
		(layer "F.Cu")
		(net "M2_GPS1_PIN12")
	)
	(via
		(at 125.6216 68.6162)
		(size 0.4064)
		(drill 0.2032)
		(layers "F.Cu" "B.Cu")
		(net "M2_GPS1_PIN12")
	)
	(via
		(at 122.2216 81.2162)
		(size 0.4064)
		(drill 0.2032)
		(layers "F.Cu" "B.Cu")
		(net "M2_GPS1_PIN12")
	)
	(segment
		(start 122.2216 81.2162)
		(end 129.0216 74.4162)
		(width 0.2032)
		(layer "B.Cu")
		(net "M2_GPS1_PIN12")
	)
	(segment
		(start 125.6216 68.6162)
		(end 127.6216 68.6162)
		(width 0.2032)
		(layer "B.Cu")
		(net "M2_GPS1_PIN12")
	)
	(segment
		(start 127.6216 68.6162)
		(end 129.0216 70.0162)
		(width 0.2032)
		(layer "B.Cu")
		(net "M2_GPS1_PIN12")
	)
	(segment
		(start 129.0216 74.4162)
		(end 129.0216 70.0162)
		(width 0.2032)
		(layer "B.Cu")
		(net "M2_GPS1_PIN12")
	)
	(segment
		(start 119.92 79.7678)
		(end 119.9216 79.7662)
		(width 0.2032)
		(layer "F.Cu")
		(net "M2_GPS1_PIN11")
	)
	(segment
		(start 118.0966 80.8162)
		(end 119.19489 80.8162)
		(width 0.2032)
		(layer "F.Cu")
		(net "M2_GPS1_PIN11")
	)
	(segment
		(start 119.19489 80.8162)
		(end 119.92 80.09109)
		(width 0.2032)
		(layer "F.Cu")
		(net "M2_GPS1_PIN11")
	)
	(segment
		(start 119.92 80.09109)
		(end 119.92 79.7678)
		(width 0.2032)
		(layer "F.Cu")
		(net "M2_GPS1_PIN11")
	)
	(segment
		(start 125.34508 70.02324)
		(end 125.34508 69.5162)
		(width 0.2032)
		(layer "F.Cu")
		(net "M2_GPS1_PIN11")
	)
	(segment
		(start 123.8966 69.5162)
		(end 125.34508 69.5162)
		(width 0.2032)
		(layer "F.Cu")
		(net "M2_GPS1_PIN11")
	)
	(via
		(at 118.0966 80.8162)
		(size 0.4064)
		(drill 0.2032)
		(layers "F.Cu" "B.Cu")
		(net "M2_GPS1_PIN11")
	)
	(via
		(at 125.34508 70.02324)
		(size 0.4064)
		(drill 0.2032)
		(layers "F.Cu" "B.Cu")
		(net "M2_GPS1_PIN11")
	)
	(segment
		(start 118.0966 80.8162)
		(end 118.0966 80.10186)
		(width 0.2032)
		(layer "B.Cu")
		(net "M2_GPS1_PIN11")
	)
	(segment
		(start 119.9216 73.9162)
		(end 123.81456 70.02324)
		(width 0.2032)
		(layer "B.Cu")
		(net "M2_GPS1_PIN11")
	)
	(segment
		(start 117.82317 79.82842)
		(end 117.82317 79.18963)
		(width 0.2032)
		(layer "B.Cu")
		(net "M2_GPS1_PIN11")
	)
	(segment
		(start 119.9216 77.0912)
		(end 119.9216 73.9162)
		(width 0.2032)
		(layer "B.Cu")
		(net "M2_GPS1_PIN11")
	)
	(segment
		(start 117.82317 79.82842)
		(end 118.0966 80.10186)
		(width 0.2032)
		(layer "B.Cu")
		(net "M2_GPS1_PIN11")
	)
	(segment
		(start 117.82317 79.18963)
		(end 119.9216 77.0912)
		(width 0.2032)
		(layer "B.Cu")
		(net "M2_GPS1_PIN11")
	)
	(segment
		(start 123.81456 70.02324)
		(end 125.34508 70.02324)
		(width 0.2032)
		(layer "B.Cu")
		(net "M2_GPS1_PIN11")
	)
	(segment
		(start 191.6216 117.7162)
		(end 191.6216 117.6162)
		(width 0.2032)
		(layer "F.Cu")
		(net "DIP_SW_GPS2_SEL")
	)
	(segment
		(start 193.4716 124.2662)
		(end 193.4716 123.4162)
		(width 0.2032)
		(layer "F.Cu")
		(net "DIP_SW_GPS2_SEL")
	)
	(segment
		(start 193.1216 124.6162)
		(end 193.4716 124.2662)
		(width 0.2032)
		(layer "F.Cu")
		(net "DIP_SW_GPS2_SEL")
	)
	(segment
		(start 189.2716 132.0662)
		(end 192.1738 132.0662)
		(width 0.2032)
		(layer "F.Cu")
		(net "DIP_SW_GPS2_SEL")
	)
	(segment
		(start 191.6216 117.6162)
		(end 209.9216 99.3162)
		(width 0.2032)
		(layer "F.Cu")
		(net "DIP_SW_GPS2_SEL")
	)
	(segment
		(start 195.0694 132.5662)
		(end 195.9716 132.5662)
		(width 0.2032)
		(layer "F.Cu")
		(net "DIP_SW_GPS2_SEL")
	)
	(segment
		(start 192.5216 120.9162)
		(end 193.4216 121.8162)
		(width 0.2032)
		(layer "F.Cu")
		(net "DIP_SW_GPS2_SEL")
	)
	(segment
		(start 209.9216 99.3162)
		(end 219.9216 99.3162)
		(width 0.2032)
		(layer "F.Cu")
		(net "DIP_SW_GPS2_SEL")
	)
	(segment
		(start 219.9516 99.2862)
		(end 222.1163 99.2862)
		(width 0.2032)
		(layer "F.Cu")
		(net "DIP_SW_GPS2_SEL")
	)
	(segment
		(start 219.9216 99.3162)
		(end 219.9516 99.2862)
		(width 0.2032)
		(layer "F.Cu")
		(net "DIP_SW_GPS2_SEL")
	)
	(segment
		(start 193.4216 121.8162)
		(end 193.6716 121.8162)
		(width 0.2032)
		(layer "F.Cu")
		(net "DIP_SW_GPS2_SEL")
	)
	(segment
		(start 189.2216 132.0162)
		(end 189.2716 132.0662)
		(width 0.2032)
		(layer "F.Cu")
		(net "DIP_SW_GPS2_SEL")
	)
	(segment
		(start 195.9716 132.5662)
		(end 196.5216 133.1162)
		(width 0.2032)
		(layer "F.Cu")
		(net "DIP_SW_GPS2_SEL")
	)
	(segment
		(start 192.4216 120.9162)
		(end 192.5216 120.9162)
		(width 0.2032)
		(layer "F.Cu")
		(net "DIP_SW_GPS2_SEL")
	)
	(segment
		(start 196.5216 133.1162)
		(end 198.7216 133.1162)
		(width 0.2032)
		(layer "F.Cu")
		(net "DIP_SW_GPS2_SEL")
	)
	(via
		(at 189.2216 132.0162)
		(size 0.4064)
		(drill 0.2032)
		(layers "F.Cu" "B.Cu")
		(net "DIP_SW_GPS2_SEL")
	)
	(via
		(at 191.6216 117.7162)
		(size 0.4064)
		(drill 0.2032)
		(layers "F.Cu" "B.Cu")
		(net "DIP_SW_GPS2_SEL")
	)
	(via
		(at 193.1216 124.6162)
		(size 0.4064)
		(drill 0.2032)
		(layers "F.Cu" "B.Cu")
		(net "DIP_SW_GPS2_SEL")
	)
	(via
		(at 219.9216 99.3162)
		(size 0.4064)
		(drill 0.2032)
		(layers "F.Cu" "B.Cu")
		(net "DIP_SW_GPS2_SEL")
	)
	(via
		(at 192.4216 120.9162)
		(size 0.4064)
		(drill 0.2032)
		(layers "F.Cu" "B.Cu")
		(net "DIP_SW_GPS2_SEL")
	)
	(via
		(at 198.7216 133.1162)
		(size 0.4064)
		(drill 0.2032)
		(layers "F.Cu" "B.Cu")
		(net "DIP_SW_GPS2_SEL")
	)
	(segment
		(start 195.22611 132.65906)
		(end 198.26446 132.65906)
		(width 0.2032)
		(layer "B.Cu")
		(net "DIP_SW_GPS2_SEL")
	)
	(segment
		(start 221.4966 99.3162)
		(end 221.7732 99.5928)
		(width 0.2032)
		(layer "B.Cu")
		(net "DIP_SW_GPS2_SEL")
	)
	(segment
		(start 221.7982 99.5928)
		(end 221.9216 99.7162)
		(width 0.2032)
		(layer "B.Cu")
		(net "DIP_SW_GPS2_SEL")
	)
	(segment
		(start 219.9216 99.3162)
		(end 221.4966 99.3162)
		(width 0.2032)
		(layer "B.Cu")
		(net "DIP_SW_GPS2_SEL")
	)
	(segment
		(start 219.9216 100.9662)
		(end 221.2716 102.3162)
		(width 0.2032)
		(layer "B.Cu")
		(net "DIP_SW_GPS2_SEL")
	)
	(segment
		(start 189.2216 132.0162)
		(end 190.4216 132.0162)
		(width 0.2032)
		(layer "B.Cu")
		(net "DIP_SW_GPS2_SEL")
	)
	(segment
		(start 191.5216 133.1162)
		(end 192.90883 133.1162)
		(width 0.2032)
		(layer "B.Cu")
		(net "DIP_SW_GPS2_SEL")
	)
	(segment
		(start 192.90883 133.1162)
		(end 194.76897 133.1162)
		(width 0.2032)
		(layer "B.Cu")
		(net "DIP_SW_GPS2_SEL")
	)
	(segment
		(start 198.26446 132.65906)
		(end 198.7216 133.1162)
		(width 0.2032)
		(layer "B.Cu")
		(net "DIP_SW_GPS2_SEL")
	)
	(segment
		(start 194.76897 133.1162)
		(end 195.22611 132.65906)
		(width 0.2032)
		(layer "B.Cu")
		(net "DIP_SW_GPS2_SEL")
	)
	(segment
		(start 191.6216 120.1162)
		(end 191.6216 117.7162)
		(width 0.2032)
		(layer "B.Cu")
		(net "DIP_SW_GPS2_SEL")
	)
	(segment
		(start 192.7898 132.99717)
		(end 192.7898 127.22402)
		(width 0.2032)
		(layer "B.Cu")
		(net "DIP_SW_GPS2_SEL")
	)
	(segment
		(start 192.7898 127.22402)
		(end 193.1216 126.89222)
		(width 0.2032)
		(layer "B.Cu")
		(net "DIP_SW_GPS2_SEL")
	)
	(segment
		(start 190.4216 132.0162)
		(end 191.5216 133.1162)
		(width 0.2032)
		(layer "B.Cu")
		(net "DIP_SW_GPS2_SEL")
	)
	(segment
		(start 219.9216 100.9662)
		(end 219.9216 99.3162)
		(width 0.2032)
		(layer "B.Cu")
		(net "DIP_SW_GPS2_SEL")
	)
	(segment
		(start 191.6216 120.1162)
		(end 192.4216 120.9162)
		(width 0.2032)
		(layer "B.Cu")
		(net "DIP_SW_GPS2_SEL")
	)
	(segment
		(start 221.9216 99.7412)
		(end 221.9216 99.7162)
		(width 0.2032)
		(layer "B.Cu")
		(net "DIP_SW_GPS2_SEL")
	)
	(segment
		(start 193.1216 126.89222)
		(end 193.1216 124.6162)
		(width 0.2032)
		(layer "B.Cu")
		(net "DIP_SW_GPS2_SEL")
	)
	(segment
		(start 221.7732 99.5928)
		(end 221.7982 99.5928)
		(width 0.2032)
		(layer "B.Cu")
		(net "DIP_SW_GPS2_SEL")
	)
	(segment
		(start 191.7216 123.2162)
		(end 193.1216 124.6162)
		(width 0.2032)
		(layer "In2.Cu")
		(net "DIP_SW_GPS2_SEL")
	)
	(segment
		(start 191.7216 123.2162)
		(end 191.7216 121.6162)
		(width 0.2032)
		(layer "In2.Cu")
		(net "DIP_SW_GPS2_SEL")
	)
	(segment
		(start 191.7216 121.6162)
		(end 192.4216 120.9162)
		(width 0.2032)
		(layer "In2.Cu")
		(net "DIP_SW_GPS2_SEL")
	)
	(segment
		(start 121.1216 79.9146)
		(end 121.1232 79.9162)
		(width 0.2032)
		(layer "F.Cu")
		(net "DIP_SW_GPS1_SEL")
	)
	(segment
		(start 108.0216 55.0162)
		(end 108.0216 55.0072)
		(width 0.2032)
		(layer "F.Cu")
		(net "DIP_SW_GPS1_SEL")
	)
	(segment
		(start 113.1716 55.2662)
		(end 113.4216 55.5162)
		(width 0.2032)
		(layer "F.Cu")
		(net "DIP_SW_GPS1_SEL")
	)
	(segment
		(start 222.3216 91.8162)
		(end 223.3716 91.8162)
		(width 0.2032)
		(layer "F.Cu")
		(net "DIP_SW_GPS1_SEL")
	)
	(segment
		(start 118.4216 79.8162)
		(end 118.6716 79.5662)
		(width 0.2032)
		(layer "F.Cu")
		(net "DIP_SW_GPS1_SEL")
	)
	(segment
		(start 121.1232 79.9162)
		(end 122.3216 79.9162)
		(width 0.2032)
		(layer "F.Cu")
		(net "DIP_SW_GPS1_SEL")
	)
	(segment
		(start 108.0216 55.0072)
		(end 108.2626 54.7662)
		(width 0.2032)
		(layer "F.Cu")
		(net "DIP_SW_GPS1_SEL")
	)
	(segment
		(start 121.1216 79.9146)
		(end 121.1216 79.7662)
		(width 0.2032)
		(layer "F.Cu")
		(net "DIP_SW_GPS1_SEL")
	)
	(segment
		(start 118.6716 79.5662)
		(end 119.5216 79.5662)
		(width 0.2032)
		(layer "F.Cu")
		(net "DIP_SW_GPS1_SEL")
	)
	(segment
		(start 108.2626 54.7662)
		(end 108.9738 54.7662)
		(width 0.2032)
		(layer "F.Cu")
		(net "DIP_SW_GPS1_SEL")
	)
	(segment
		(start 111.8694 55.2662)
		(end 113.1716 55.2662)
		(width 0.2032)
		(layer "F.Cu")
		(net "DIP_SW_GPS1_SEL")
	)
	(segment
		(start 219.9916 96.7462)
		(end 222.1163 96.7462)
		(width 0.2032)
		(layer "F.Cu")
		(net "DIP_SW_GPS1_SEL")
	)
	(via
		(at 108.0216 55.0162)
		(size 0.4064)
		(drill 0.2032)
		(layers "F.Cu" "B.Cu")
		(net "DIP_SW_GPS1_SEL")
	)
	(via
		(at 219.9916 96.7462)
		(size 0.4064)
		(drill 0.2032)
		(layers "F.Cu" "B.Cu")
		(net "DIP_SW_GPS1_SEL")
	)
	(via
		(at 222.3216 91.8162)
		(size 0.4064)
		(drill 0.2032)
		(layers "F.Cu" "B.Cu")
		(net "DIP_SW_GPS1_SEL")
	)
	(via
		(at 122.3216 79.9162)
		(size 0.4064)
		(drill 0.2032)
		(layers "F.Cu" "B.Cu")
		(net "DIP_SW_GPS1_SEL")
	)
	(via
		(at 113.4216 55.5162)
		(size 0.4064)
		(drill 0.2032)
		(layers "F.Cu" "B.Cu")
		(net "DIP_SW_GPS1_SEL")
	)
	(via
		(at 118.4216 79.8162)
		(size 0.4064)
		(drill 0.2032)
		(layers "F.Cu" "B.Cu")
		(net "DIP_SW_GPS1_SEL")
	)
	(segment
		(start 97.5216 60.8162)
		(end 97.5216 58.6162)
		(width 0.2032)
		(layer "B.Cu")
		(net "DIP_SW_GPS1_SEL")
	)
	(segment
		(start 117.2216 81.3162)
		(end 119.0716 81.3162)
		(width 0.2032)
		(layer "B.Cu")
		(net "DIP_SW_GPS1_SEL")
	)
	(segment
		(start 100.912 75.8258)
		(end 106.9312 75.8258)
		(width 0.2032)
		(layer "B.Cu")
		(net "DIP_SW_GPS1_SEL")
	)
	(segment
		(start 113.9216 78.0162)
		(end 117.2216 81.3162)
		(width 0.2032)
		(layer "B.Cu")
		(net "DIP_SW_GPS1_SEL")
	)
	(segment
		(start 121.2216 81.3162)
		(end 121.50216 81.03564)
		(width 0.2032)
		(layer "B.Cu")
		(net "DIP_SW_GPS1_SEL")
	)
	(segment
		(start 118.4216 79.8162)
		(end 119.0716 80.4662)
		(width 0.2032)
		(layer "B.Cu")
		(net "DIP_SW_GPS1_SEL")
	)
	(segment
		(start 221.91312 96.2124)
		(end 221.91312 96.1874)
		(width 0.2032)
		(layer "B.Cu")
		(net "DIP_SW_GPS1_SEL")
	)
	(segment
		(start 90.2216 70.7162)
		(end 91.7216 69.2162)
		(width 0.2032)
		(layer "B.Cu")
		(net "DIP_SW_GPS1_SEL")
	)
	(segment
		(start 91.7216 63.8162)
		(end 93.25505 62.28275)
		(width 0.2032)
		(layer "B.Cu")
		(net "DIP_SW_GPS1_SEL")
	)
	(segment
		(start 90.2216 74.4162)
		(end 90.2216 70.7162)
		(width 0.2032)
		(layer "B.Cu")
		(net "DIP_SW_GPS1_SEL")
	)
	(segment
		(start 108.8216 77.1162)
		(end 109.7216 78.0162)
		(width 0.2032)
		(layer "B.Cu")
		(net "DIP_SW_GPS1_SEL")
	)
	(segment
		(start 97.5216 58.6162)
		(end 99.3216 56.8162)
		(width 0.2032)
		(layer "B.Cu")
		(net "DIP_SW_GPS1_SEL")
	)
	(segment
		(start 107.1518 55.886)
		(end 108.0216 55.0162)
		(width 0.2032)
		(layer "B.Cu")
		(net "DIP_SW_GPS1_SEL")
	)
	(segment
		(start 99.3216 56.8162)
		(end 104.71191 56.8162)
		(width 0.2032)
		(layer "B.Cu")
		(net "DIP_SW_GPS1_SEL")
	)
	(segment
		(start 121.50216 80.03523)
		(end 121.62119 79.9162)
		(width 0.2032)
		(layer "B.Cu")
		(net "DIP_SW_GPS1_SEL")
	)
	(segment
		(start 106.9312 75.8258)
		(end 108.2216 77.1162)
		(width 0.2032)
		(layer "B.Cu")
		(net "DIP_SW_GPS1_SEL")
	)
	(segment
		(start 221.35432 96.7462)
		(end 221.76472 96.3358)
		(width 0.2032)
		(layer "B.Cu")
		(net "DIP_SW_GPS1_SEL")
	)
	(segment
		(start 96.05505 62.28275)
		(end 97.5216 60.8162)
		(width 0.2032)
		(layer "B.Cu")
		(net "DIP_SW_GPS1_SEL")
	)
	(segment
		(start 93.25505 62.28275)
		(end 96.05505 62.28275)
		(width 0.2032)
		(layer "B.Cu")
		(net "DIP_SW_GPS1_SEL")
	)
	(segment
		(start 221.78972 96.3358)
		(end 221.91312 96.2124)
		(width 0.2032)
		(layer "B.Cu")
		(net "DIP_SW_GPS1_SEL")
	)
	(segment
		(start 104.71191 56.8162)
		(end 105.64211 55.886)
		(width 0.2032)
		(layer "B.Cu")
		(net "DIP_SW_GPS1_SEL")
	)
	(segment
		(start 121.50216 81.03564)
		(end 121.50216 80.03523)
		(width 0.2032)
		(layer "B.Cu")
		(net "DIP_SW_GPS1_SEL")
	)
	(segment
		(start 99.5216 77.2162)
		(end 100.912 75.8258)
		(width 0.2032)
		(layer "B.Cu")
		(net "DIP_SW_GPS1_SEL")
	)
	(segment
		(start 219.9916 96.7462)
		(end 221.35432 96.7462)
		(width 0.2032)
		(layer "B.Cu")
		(net "DIP_SW_GPS1_SEL")
	)
	(segment
		(start 119.0716 81.3162)
		(end 119.0716 80.4662)
		(width 0.2032)
		(layer "B.Cu")
		(net "DIP_SW_GPS1_SEL")
	)
	(segment
		(start 109.7216 78.0162)
		(end 113.9216 78.0162)
		(width 0.2032)
		(layer "B.Cu")
		(net "DIP_SW_GPS1_SEL")
	)
	(segment
		(start 93.0216 77.2162)
		(end 99.5216 77.2162)
		(width 0.2032)
		(layer "B.Cu")
		(net "DIP_SW_GPS1_SEL")
	)
	(segment
		(start 90.2216 74.4162)
		(end 93.0216 77.2162)
		(width 0.2032)
		(layer "B.Cu")
		(net "DIP_SW_GPS1_SEL")
	)
	(segment
		(start 91.7216 69.2162)
		(end 91.7216 63.8162)
		(width 0.2032)
		(layer "B.Cu")
		(net "DIP_SW_GPS1_SEL")
	)
	(segment
		(start 108.2216 77.1162)
		(end 108.8216 77.1162)
		(width 0.2032)
		(layer "B.Cu")
		(net "DIP_SW_GPS1_SEL")
	)
	(segment
		(start 221.76472 96.3358)
		(end 221.78972 96.3358)
		(width 0.2032)
		(layer "B.Cu")
		(net "DIP_SW_GPS1_SEL")
	)
	(segment
		(start 119.0716 81.3162)
		(end 121.2216 81.3162)
		(width 0.2032)
		(layer "B.Cu")
		(net "DIP_SW_GPS1_SEL")
	)
	(segment
		(start 105.64211 55.886)
		(end 107.1518 55.886)
		(width 0.2032)
		(layer "B.Cu")
		(net "DIP_SW_GPS1_SEL")
	)
	(segment
		(start 121.62119 79.9162)
		(end 122.3216 79.9162)
		(width 0.2032)
		(layer "B.Cu")
		(net "DIP_SW_GPS1_SEL")
	)
	(segment
		(start 159.8216 82.9162)
		(end 160.3216 82.9162)
		(width 0.2032)
		(layer "In3.Cu")
		(net "DIP_SW_GPS1_SEL")
	)
	(segment
		(start 110.7785 55.8932)
		(end 111.15551 55.5162)
		(width 0.2032)
		(layer "In3.Cu")
		(net "DIP_SW_GPS1_SEL")
	)
	(segment
		(start 180.3518 98.00704)
		(end 180.9736 98.62884)
		(width 0.2032)
		(layer "In3.Cu")
		(net "DIP_SW_GPS1_SEL")
	)
	(segment
		(start 160.3216 82.9162)
		(end 162.0216 84.6162)
		(width 0.2032)
		(layer "In3.Cu")
		(net "DIP_SW_GPS1_SEL")
	)
	(segment
		(start 173.5216 93.1162)
		(end 175.7743 95.3689)
		(width 0.2032)
		(layer "In3.Cu")
		(net "DIP_SW_GPS1_SEL")
	)
	(segment
		(start 108.8986 55.8932)
		(end 110.7785 55.8932)
		(width 0.2032)
		(layer "In3.Cu")
		(net "DIP_SW_GPS1_SEL")
	)
	(segment
		(start 168.2216 93.1162)
		(end 173.5216 93.1162)
		(width 0.2032)
		(layer "In3.Cu")
		(net "DIP_SW_GPS1_SEL")
	)
	(segment
		(start 188.88251 114.37711)
		(end 214.76068 114.37711)
		(width 0.2032)
		(layer "In3.Cu")
		(net "DIP_SW_GPS1_SEL")
	)
	(segment
		(start 183.88368 113.81131)
		(end 184.37477 113.81131)
		(width 0.2032)
		(layer "In3.Cu")
		(net "DIP_SW_GPS1_SEL")
	)
	(segment
		(start 177.71366 95.3689)
		(end 178.83076 96.486)
		(width 0.2032)
		(layer "In3.Cu")
		(net "DIP_SW_GPS1_SEL")
	)
	(segment
		(start 218.35546 98.13434)
		(end 218.60346 98.13434)
		(width 0.2032)
		(layer "In3.Cu")
		(net "DIP_SW_GPS1_SEL")
	)
	(segment
		(start 128.38504 51.47963)
		(end 159.8216 82.9162)
		(width 0.2032)
		(layer "In3.Cu")
		(net "DIP_SW_GPS1_SEL")
	)
	(segment
		(start 109.9216 53.2162)
		(end 109.9216 50.50554)
		(width 0.2032)
		(layer "In3.Cu")
		(net "DIP_SW_GPS1_SEL")
	)
	(segment
		(start 181.0216 112.9162)
		(end 182.98857 112.9162)
		(width 0.2032)
		(layer "In3.Cu")
		(net "DIP_SW_GPS1_SEL")
	)
	(segment
		(start 214.76068 114.37711)
		(end 215.1216 114.0162)
		(width 0.2032)
		(layer "In3.Cu")
		(net "DIP_SW_GPS1_SEL")
	)
	(segment
		(start 219.9916 96.7462)
		(end 219.9916 94.1462)
		(width 0.2032)
		(layer "In3.Cu")
		(net "DIP_SW_GPS1_SEL")
	)
	(segment
		(start 218.60346 98.13434)
		(end 219.9916 96.7462)
		(width 0.2032)
		(layer "In3.Cu")
		(net "DIP_SW_GPS1_SEL")
	)
	(segment
		(start 109.9216 50.50554)
		(end 110.34274 50.0844)
		(width 0.2032)
		(layer "In3.Cu")
		(net "DIP_SW_GPS1_SEL")
	)
	(segment
		(start 111.15551 55.5162)
		(end 113.4216 55.5162)
		(width 0.2032)
		(layer "In3.Cu")
		(net "DIP_SW_GPS1_SEL")
	)
	(segment
		(start 182.98857 112.9162)
		(end 183.88368 113.81131)
		(width 0.2032)
		(layer "In3.Cu")
		(net "DIP_SW_GPS1_SEL")
	)
	(segment
		(start 162.0216 86.9162)
		(end 162.0216 84.6162)
		(width 0.2032)
		(layer "In3.Cu")
		(net "DIP_SW_GPS1_SEL")
	)
	(segment
		(start 215.1216 112.0162)
		(end 217.3216 109.8162)
		(width 0.2032)
		(layer "In3.Cu")
		(net "DIP_SW_GPS1_SEL")
	)
	(segment
		(start 215.1216 114.0162)
		(end 215.1216 112.0162)
		(width 0.2032)
		(layer "In3.Cu")
		(net "DIP_SW_GPS1_SEL")
	)
	(segment
		(start 219.9916 94.1462)
		(end 222.3216 91.8162)
		(width 0.2032)
		(layer "In3.Cu")
		(net "DIP_SW_GPS1_SEL")
	)
	(segment
		(start 108.0216 55.0162)
		(end 108.8986 55.8932)
		(width 0.2032)
		(layer "In3.Cu")
		(net "DIP_SW_GPS1_SEL")
	)
	(segment
		(start 180.4216 112.3162)
		(end 180.4216 109.7162)
		(width 0.2032)
		(layer "In3.Cu")
		(net "DIP_SW_GPS1_SEL")
	)
	(segment
		(start 162.0216 86.9162)
		(end 168.2216 93.1162)
		(width 0.2032)
		(layer "In3.Cu")
		(net "DIP_SW_GPS1_SEL")
	)
	(segment
		(start 175.7743 95.3689)
		(end 177.71366 95.3689)
		(width 0.2032)
		(layer "In3.Cu")
		(net "DIP_SW_GPS1_SEL")
	)
	(segment
		(start 184.37477 113.81131)
		(end 184.67965 114.1162)
		(width 0.2032)
		(layer "In3.Cu")
		(net "DIP_SW_GPS1_SEL")
	)
	(segment
		(start 180.9736 98.90123)
		(end 182.0216 99.94923)
		(width 0.2032)
		(layer "In3.Cu")
		(net "DIP_SW_GPS1_SEL")
	)
	(segment
		(start 109.9216 53.2162)
		(end 110.45238 53.74698)
		(width 0.2032)
		(layer "In3.Cu")
		(net "DIP_SW_GPS1_SEL")
	)
	(segment
		(start 128.38504 51.47963)
		(end 128.38504 50.0844)
		(width 0.2032)
		(layer "In3.Cu")
		(net "DIP_SW_GPS1_SEL")
	)
	(segment
		(start 182.0216 108.1162)
		(end 182.0216 99.94923)
		(width 0.2032)
		(layer "In3.Cu")
		(net "DIP_SW_GPS1_SEL")
	)
	(segment
		(start 110.45238 53.74698)
		(end 111.65238 53.74698)
		(width 0.2032)
		(layer "In3.Cu")
		(net "DIP_SW_GPS1_SEL")
	)
	(segment
		(start 217.3216 109.8162)
		(end 217.3216 99.1682)
		(width 0.2032)
		(layer "In3.Cu")
		(net "DIP_SW_GPS1_SEL")
	)
	(segment
		(start 111.65238 53.74698)
		(end 113.4216 55.5162)
		(width 0.2032)
		(layer "In3.Cu")
		(net "DIP_SW_GPS1_SEL")
	)
	(segment
		(start 110.34274 50.0844)
		(end 128.38504 50.0844)
		(width 0.2032)
		(layer "In3.Cu")
		(net "DIP_SW_GPS1_SEL")
	)
	(segment
		(start 179.73283 96.486)
		(end 180.3518 97.10497)
		(width 0.2032)
		(layer "In3.Cu")
		(net "DIP_SW_GPS1_SEL")
	)
	(segment
		(start 180.3518 98.00704)
		(end 180.3518 97.10497)
		(width 0.2032)
		(layer "In3.Cu")
		(net "DIP_SW_GPS1_SEL")
	)
	(segment
		(start 180.9736 98.90123)
		(end 180.9736 98.62884)
		(width 0.2032)
		(layer "In3.Cu")
		(net "DIP_SW_GPS1_SEL")
	)
	(segment
		(start 178.83076 96.486)
		(end 179.73283 96.486)
		(width 0.2032)
		(layer "In3.Cu")
		(net "DIP_SW_GPS1_SEL")
	)
	(segment
		(start 217.3216 99.1682)
		(end 218.35546 98.13434)
		(width 0.2032)
		(layer "In3.Cu")
		(net "DIP_SW_GPS1_SEL")
	)
	(segment
		(start 188.6216 114.1162)
		(end 188.88251 114.37711)
		(width 0.2032)
		(layer "In3.Cu")
		(net "DIP_SW_GPS1_SEL")
	)
	(segment
		(start 180.4216 109.7162)
		(end 182.0216 108.1162)
		(width 0.2032)
		(layer "In3.Cu")
		(net "DIP_SW_GPS1_SEL")
	)
	(segment
		(start 184.67965 114.1162)
		(end 188.6216 114.1162)
		(width 0.2032)
		(layer "In3.Cu")
		(net "DIP_SW_GPS1_SEL")
	)
	(segment
		(start 180.4216 112.3162)
		(end 181.0216 112.9162)
		(width 0.2032)
		(layer "In3.Cu")
		(net "DIP_SW_GPS1_SEL")
	)
	(segment
		(start 206.2216 121.7662)
		(end 206.2216 117.0412)
		(width 0.2032)
		(layer "F.Cu")
		(net "NetJ45_46")
	)
	(segment
		(start 212.3216 131.5162)
		(end 212.3216 130.7162)
		(width 0.2032)
		(layer "F.Cu")
		(net "NetJ45_46")
	)
	(segment
		(start 205.2216 117.0412)
		(end 206.2216 117.0412)
		(width 0.2032)
		(layer "F.Cu")
		(net "NetJ45_46")
	)
	(via
		(at 205.2216 117.0412)
		(size 0.4064)
		(drill 0.2032)
		(layers "F.Cu" "B.Cu")
		(net "NetJ45_46")
	)
	(via
		(at 212.3216 130.7162)
		(size 0.4064)
		(drill 0.2032)
		(layers "F.Cu" "B.Cu")
		(net "NetJ45_46")
	)
	(via
		(at 204.7216 123.9162)
		(size 0.4064)
		(drill 0.2032)
		(layers "F.Cu" "B.Cu")
		(net "NetJ45_46")
	)
	(segment
		(start 204.7216 127.3162)
		(end 204.9216 127.5162)
		(width 0.2032)
		(layer "B.Cu")
		(net "NetJ45_46")
	)
	(segment
		(start 211.09629 129.49089)
		(end 212.3216 130.7162)
		(width 0.2032)
		(layer "B.Cu")
		(net "NetJ45_46")
	)
	(segment
		(start 206.8963 129.49089)
		(end 211.09629 129.49089)
		(width 0.2032)
		(layer "B.Cu")
		(net "NetJ45_46")
	)
	(segment
		(start 204.93119 127.52579)
		(end 206.8963 129.49089)
		(width 0.2032)
		(layer "B.Cu")
		(net "NetJ45_46")
	)
	(segment
		(start 204.7216 127.3162)
		(end 204.7216 123.9162)
		(width 0.2032)
		(layer "B.Cu")
		(net "NetJ45_46")
	)
	(segment
		(start 205.2216 117.0412)
		(end 205.7216 117.5412)
		(width 0.2032)
		(layer "In2.Cu")
		(net "NetJ45_46")
	)
	(segment
		(start 205.7216 120.1412)
		(end 205.7216 117.5412)
		(width 0.2032)
		(layer "In2.Cu")
		(net "NetJ45_46")
	)
	(segment
		(start 204.7216 121.1412)
		(end 205.7216 120.1412)
		(width 0.2032)
		(layer "In2.Cu")
		(net "NetJ45_46")
	)
	(segment
		(start 204.7216 123.9162)
		(end 204.7216 121.1412)
		(width 0.2032)
		(layer "In2.Cu")
		(net "NetJ45_46")
	)
	(segment
		(start 208.9716 130.9662)
		(end 208.9716 129.3162)
		(width 0.2032)
		(layer "F.Cu")
		(net "NetJ45_35")
	)
	(segment
		(start 209.11529 131.10989)
		(end 209.31529 131.10989)
		(width 0.2032)
		(layer "F.Cu")
		(net "NetJ45_35")
	)
	(segment
		(start 208.9716 130.9662)
		(end 209.11529 131.10989)
		(width 0.2032)
		(layer "F.Cu")
		(net "NetJ45_35")
	)
	(segment
		(start 209.31529 131.10989)
		(end 209.7216 131.5162)
		(width 0.2032)
		(layer "F.Cu")
		(net "NetJ45_35")
	)
	(segment
		(start 123.8966 63.0162)
		(end 128.6216 63.0162)
		(width 0.2032)
		(layer "F.Cu")
		(net "NetJ44_46")
	)
	(segment
		(start 128.6216 63.0162)
		(end 128.6534 63.048)
		(width 0.2032)
		(layer "F.Cu")
		(net "NetJ44_46")
	)
	(segment
		(start 115.1216 76.8162)
		(end 126.0216 76.8162)
		(width 0.2032)
		(layer "F.Cu")
		(net "NetJ44_46")
	)
	(segment
		(start 128.6534 74.1844)
		(end 128.6534 63.048)
		(width 0.2032)
		(layer "F.Cu")
		(net "NetJ44_46")
	)
	(segment
		(start 126.0216 76.8162)
		(end 128.6534 74.1844)
		(width 0.2032)
		(layer "F.Cu")
		(net "NetJ44_46")
	)
	(segment
		(start 113.6216 75.3162)
		(end 115.1216 76.8162)
		(width 0.2032)
		(layer "F.Cu")
		(net "NetJ44_46")
	)
	(segment
		(start 113.6216 75.3162)
		(end 113.6216 70.1162)
		(width 0.2032)
		(layer "F.Cu")
		(net "NetJ44_46")
	)
	(segment
		(start 114.23401 65.7662)
		(end 116.3466 65.7662)
		(width 0.2032)
		(layer "F.Cu")
		(net "NetJ44_35")
	)
	(segment
		(start 113.6216 68.9162)
		(end 113.6216 66.37862)
		(width 0.2032)
		(layer "F.Cu")
		(net "NetJ44_35")
	)
	(segment
		(start 113.6216 66.37862)
		(end 114.23401 65.7662)
		(width 0.2032)
		(layer "F.Cu")
		(net "NetJ44_35")
	)
	(segment
		(start 167.3466 110.4162)
		(end 167.4216 110.4912)
		(width 0.2032)
		(layer "F.Cu")
		(net "SDA")
	)
	(segment
		(start 167.6466 113.6412)
		(end 168.4966 113.6412)
		(width 0.2032)
		(layer "F.Cu")
		(net "SDA")
	)
	(segment
		(start 168.8716 108.9162)
		(end 173.8216 108.9162)
		(width 0.2032)
		(layer "F.Cu")
		(net "SDA")
	)
	(segment
		(start 173.8216 108.9162)
		(end 178.68781 104.04999)
		(width 0.2032)
		(layer "F.Cu")
		(net "SDA")
	)
	(segment
		(start 167.4216 113.4162)
		(end 167.4216 111.3162)
		(width 0.2032)
		(layer "F.Cu")
		(net "SDA")
	)
	(segment
		(start 178.68781 104.04999)
		(end 179.95984 104.04999)
		(width 0.2032)
		(layer "F.Cu")
		(net "SDA")
	)
	(segment
		(start 167.96445 108.3162)
		(end 172.2754 108.3162)
		(width 0.2032)
		(layer "F.Cu")
		(net "SDA")
	)
	(segment
		(start 172.2754 108.3162)
		(end 177.6754 102.9162)
		(width 0.2032)
		(layer "F.Cu")
		(net "SDA")
	)
	(segment
		(start 166.5489 106.90064)
		(end 166.5489 103.31041)
		(width 0.2032)
		(layer "F.Cu")
		(net "SDA")
	)
	(segment
		(start 167.4216 111.3162)
		(end 167.4216 110.4912)
		(width 0.2032)
		(layer "F.Cu")
		(net "SDA")
	)
	(segment
		(start 167.3716 110.4162)
		(end 168.8716 108.9162)
		(width 0.2032)
		(layer "F.Cu")
		(net "SDA")
	)
	(segment
		(start 167.4216 113.4162)
		(end 167.6466 113.6412)
		(width 0.2032)
		(layer "F.Cu")
		(net "SDA")
	)
	(segment
		(start 166.5489 106.90064)
		(end 167.96445 108.3162)
		(width 0.2032)
		(layer "F.Cu")
		(net "SDA")
	)
	(segment
		(start 179.95984 104.04999)
		(end 179.95984 103.79691)
		(width 0.2032)
		(layer "F.Cu")
		(net "SDA")
	)
	(segment
		(start 179.07913 102.9162)
		(end 179.95984 103.79691)
		(width 0.2032)
		(layer "F.Cu")
		(net "SDA")
	)
	(segment
		(start 177.6754 102.9162)
		(end 179.07913 102.9162)
		(width 0.2032)
		(layer "F.Cu")
		(net "SDA")
	)
	(via
		(at 167.4216 111.3162)
		(size 0.4064)
		(drill 0.2032)
		(layers "F.Cu" "B.Cu")
		(net "SDA")
	)
	(segment
		(start 182.7216 106.4162)
		(end 182.7216 105.74708)
		(width 0.2032)
		(layer "F.Cu")
		(net "SCL")
	)
	(segment
		(start 169.3466 112.7912)
		(end 169.3466 111.3912)
		(width 0.2032)
		(layer "F.Cu")
		(net "SCL")
	)
	(segment
		(start 178.2216 101.7162)
		(end 181.8216 101.7162)
		(width 0.2032)
		(layer "F.Cu")
		(net "SCL")
	)
	(segment
		(start 174.78499 108.85281)
		(end 180.28499 108.85281)
		(width 0.2032)
		(layer "F.Cu")
		(net "SCL")
	)
	(segment
		(start 169.3466 111.3912)
		(end 169.3466 110.4662)
		(width 0.2032)
		(layer "F.Cu")
		(net "SCL")
	)
	(segment
		(start 169.3466 110.4662)
		(end 169.3966 110.4162)
		(width 0.2032)
		(layer "F.Cu")
		(net "SCL")
	)
	(segment
		(start 169.94733 109.3345)
		(end 174.3033 109.3345)
		(width 0.2032)
		(layer "F.Cu")
		(net "SCL")
	)
	(segment
		(start 169.3966 110.4162)
		(end 169.46563 110.34717)
		(width 0.2032)
		(layer "F.Cu")
		(net "SCL")
	)
	(segment
		(start 168.04902 107.04362)
		(end 168.04902 103.31041)
		(width 0.2032)
		(layer "F.Cu")
		(net "SCL")
	)
	(segment
		(start 172.01386 107.92394)
		(end 178.2216 101.7162)
		(width 0.2032)
		(layer "F.Cu")
		(net "SCL")
	)
	(segment
		(start 180.28499 108.85281)
		(end 182.7216 106.4162)
		(width 0.2032)
		(layer "F.Cu")
		(net "SCL")
	)
	(segment
		(start 168.04902 107.04362)
		(end 168.92934 107.92394)
		(width 0.2032)
		(layer "F.Cu")
		(net "SCL")
	)
	(segment
		(start 181.85985 103.79691)
		(end 182.3502 103.30656)
		(width 0.2032)
		(layer "F.Cu")
		(net "SCL")
	)
	(segment
		(start 181.85985 104.04999)
		(end 181.85985 103.79691)
		(width 0.2032)
		(layer "F.Cu")
		(net "SCL")
	)
	(segment
		(start 169.46563 109.8162)
		(end 169.94733 109.3345)
		(width 0.2032)
		(layer "F.Cu")
		(net "SCL")
	)
	(segment
		(start 181.8216 101.7162)
		(end 182.59538 102.48998)
		(width 0.2032)
		(layer "F.Cu")
		(net "SCL")
	)
	(segment
		(start 169.46563 110.34717)
		(end 169.46563 109.8162)
		(width 0.2032)
		(layer "F.Cu")
		(net "SCL")
	)
	(segment
		(start 182.3502 105.37568)
		(end 182.3502 103.30656)
		(width 0.2032)
		(layer "F.Cu")
		(net "SCL")
	)
	(segment
		(start 182.59538 103.06138)
		(end 182.59538 102.48998)
		(width 0.2032)
		(layer "F.Cu")
		(net "SCL")
	)
	(segment
		(start 182.3502 103.30656)
		(end 182.59538 103.06138)
		(width 0.2032)
		(layer "F.Cu")
		(net "SCL")
	)
	(segment
		(start 168.92934 107.92394)
		(end 172.01386 107.92394)
		(width 0.2032)
		(layer "F.Cu")
		(net "SCL")
	)
	(segment
		(start 182.3502 105.37568)
		(end 182.7216 105.74708)
		(width 0.2032)
		(layer "F.Cu")
		(net "SCL")
	)
	(segment
		(start 174.3033 109.3345)
		(end 174.78499 108.85281)
		(width 0.2032)
		(layer "F.Cu")
		(net "SCL")
	)
	(via
		(at 169.3466 111.3912)
		(size 0.4064)
		(drill 0.2032)
		(layers "F.Cu" "B.Cu")
		(net "SCL")
	)
	(segment
		(start 100.3048 59.4162)
		(end 102.3216 59.4162)
		(width 0.254)
		(layer "F.Cu")
		(net "P5V_MUN_VCC")
	)
	(via
		(at 102.3216 59.4162)
		(size 0.4064)
		(drill 0.2032)
		(layers "F.Cu" "B.Cu")
		(net "P5V_MUN_VCC")
	)
	(segment
		(start 101.28818 59.2162)
		(end 102.3216 59.2162)
		(width 0.254)
		(layer "B.Cu")
		(net "P5V_MUN_VCC")
	)
	(segment
		(start 102.3216 59.4162)
		(end 102.3216 59.2162)
		(width 0.254)
		(layer "B.Cu")
		(net "P5V_MUN_VCC")
	)
	(segment
		(start 101.39542 60.2162)
		(end 101.79542 60.6162)
		(width 0.254)
		(layer "F.Cu")
		(net "P5V_MUN_FB")
	)
	(segment
		(start 101.79542 60.6162)
		(end 101.8216 60.6162)
		(width 0.254)
		(layer "F.Cu")
		(net "P5V_MUN_FB")
	)
	(segment
		(start 100.3048 60.2162)
		(end 101.39542 60.2162)
		(width 0.254)
		(layer "F.Cu")
		(net "P5V_MUN_FB")
	)
	(via
		(at 101.8216 60.6162)
		(size 0.4064)
		(drill 0.2032)
		(layers "F.Cu" "B.Cu")
		(net "P5V_MUN_FB")
	)
	(segment
		(start 100.3216 60.6162)
		(end 101.8216 60.6162)
		(width 0.254)
		(layer "B.Cu")
		(net "P5V_MUN_FB")
	)
	(segment
		(start 101.8216 60.6162)
		(end 101.8216 60.6162)
		(width 0.254)
		(layer "B.Cu")
		(net "P5V_MUN_FB")
	)
	(segment
		(start 178.5216 88.07357)
		(end 178.5216 87.23282)
		(width 0.2032)
		(layer "F.Cu")
		(net "P3V3_MUN_VCC")
	)
	(via
		(at 178.5216 88.07357)
		(size 0.4064)
		(drill 0.2032)
		(layers "F.Cu" "B.Cu")
		(net "P3V3_MUN_VCC")
	)
	(segment
		(start 178.5216 88.07357)
		(end 178.5216 86.7162)
		(width 0.2032)
		(layer "B.Cu")
		(net "P3V3_MUN_VCC")
	)
	(segment
		(start 178.18817 86.7162)
		(end 178.5216 86.7162)
		(width 0.2032)
		(layer "B.Cu")
		(net "P3V3_MUN_VCC")
	)
	(segment
		(start 177.7216 88.03686)
		(end 177.7216 87.23282)
		(width 0.2032)
		(layer "F.Cu")
		(net "P3V3_MUN_FB")
	)
	(via
		(at 177.7216 88.03686)
		(size 0.4064)
		(drill 0.2032)
		(layers "F.Cu" "B.Cu")
		(net "P3V3_MUN_FB")
	)
	(segment
		(start 176.8216 88.03686)
		(end 177.7216 88.03686)
		(width 0.2032)
		(layer "B.Cu")
		(net "P3V3_MUN_FB")
	)
	(segment
		(start 176.8216 88.03686)
		(end 176.8216 88.0162)
		(width 0.2032)
		(layer "B.Cu")
		(net "P3V3_MUN_FB")
	)
	(segment
		(start 167.7152 115.0428)
		(end 167.8168 114.9412)
		(width 0.2032)
		(layer "F.Cu")
		(net "NetR128_2")
	)
	(segment
		(start 167.8168 114.9412)
		(end 168.4966 114.9412)
		(width 0.2032)
		(layer "F.Cu")
		(net "NetR128_2")
	)
	(segment
		(start 167.345 115.0428)
		(end 167.7152 115.0428)
		(width 0.2032)
		(layer "F.Cu")
		(net "NetR128_2")
	)
	(segment
		(start 167.1716 115.2162)
		(end 167.345 115.0428)
		(width 0.2032)
		(layer "F.Cu")
		(net "NetR128_2")
	)
	(segment
		(start 168.4482 115.6396)
		(end 168.4966 115.5912)
		(width 0.2032)
		(layer "F.Cu")
		(net "NetR127_2")
	)
	(segment
		(start 167.1716 116.4162)
		(end 167.9482 115.6396)
		(width 0.2032)
		(layer "F.Cu")
		(net "NetR127_2")
	)
	(segment
		(start 167.9482 115.6396)
		(end 168.4482 115.6396)
		(width 0.2032)
		(layer "F.Cu")
		(net "NetR127_2")
	)
	(segment
		(start 170.35949 111.3271)
		(end 171.4607 111.3271)
		(width 0.254)
		(layer "F.Cu")
		(net "NetR126_2")
	)
	(segment
		(start 169.9966 112.7912)
		(end 169.9966 111.68999)
		(width 0.254)
		(layer "F.Cu")
		(net "NetR126_2")
	)
	(segment
		(start 169.9966 111.68999)
		(end 170.35949 111.3271)
		(width 0.254)
		(layer "F.Cu")
		(net "NetR126_2")
	)
	(segment
		(start 171.4607 111.3271)
		(end 171.9716 110.8162)
		(width 0.254)
		(layer "F.Cu")
		(net "NetR126_2")
	)
	(segment
		(start 169.3216 117.6662)
		(end 169.3216 116.6912)
		(width 0.254)
		(layer "F.Cu")
		(net "NetR121_2")
	)
	(segment
		(start 169.3466 116.6662)
		(end 169.3466 116.4412)
		(width 0.254)
		(layer "F.Cu")
		(net "NetR121_2")
	)
	(segment
		(start 169.3216 116.6912)
		(end 169.3466 116.6662)
		(width 0.254)
		(layer "F.Cu")
		(net "NetR121_2")
	)
	(segment
		(start 152.3716 116.9162)
		(end 152.8716 116.4162)
		(width 0.2032)
		(layer "F.Cu")
		(net "NetR111_2")
	)
	(segment
		(start 152.8716 116.4162)
		(end 154.1716 116.4162)
		(width 0.2032)
		(layer "F.Cu")
		(net "NetR111_2")
	)
	(segment
		(start 155.4716 116.4162)
		(end 156.2208 116.4162)
		(width 0.2032)
		(layer "F.Cu")
		(net "NetR95_2")
	)
	(segment
		(start 157.14259 116.7872)
		(end 157.1716 116.8162)
		(width 0.2032)
		(layer "F.Cu")
		(net "NetR95_2")
	)
	(segment
		(start 156.2208 116.4162)
		(end 156.5918 116.7872)
		(width 0.2032)
		(layer "F.Cu")
		(net "NetR95_2")
	)
	(segment
		(start 156.5918 116.7872)
		(end 157.14259 116.7872)
		(width 0.2032)
		(layer "F.Cu")
		(net "NetR95_2")
	)
	(segment
		(start 153.5716 115.6162)
		(end 154.1716 115.6162)
		(width 0.2032)
		(layer "F.Cu")
		(net "NetR94_2")
	)
	(segment
		(start 153.0716 115.1162)
		(end 153.5716 115.6162)
		(width 0.2032)
		(layer "F.Cu")
		(net "NetR94_2")
	)
	(segment
		(start 156.4716 115.6162)
		(end 157.0716 115.0162)
		(width 0.2032)
		(layer "F.Cu")
		(net "NetR76_2")
	)
	(segment
		(start 155.4716 115.6162)
		(end 156.4716 115.6162)
		(width 0.2032)
		(layer "F.Cu")
		(net "NetR76_2")
	)
	(segment
		(start 178.5216 81.94962)
		(end 178.5216 80.5162)
		(width 0.2032)
		(layer "F.Cu")
		(net "NetR70_1")
	)
	(via
		(at 178.5216 80.5162)
		(size 0.4064)
		(drill 0.2032)
		(layers "F.Cu" "B.Cu")
		(net "NetR70_1")
	)
	(segment
		(start 178.5216 81.69562)
		(end 178.5216 80.5162)
		(width 0.2032)
		(layer "B.Cu")
		(net "NetR70_1")
	)
	(segment
		(start 178.3117 81.69562)
		(end 178.5216 81.69562)
		(width 0.2032)
		(layer "B.Cu")
		(net "NetR70_1")
	)
	(segment
		(start 179.3216 81.94962)
		(end 179.3216 81.0162)
		(width 0.2032)
		(layer "F.Cu")
		(net "NetR69_2")
	)
	(via
		(at 179.3216 81.0162)
		(size 0.4064)
		(drill 0.2032)
		(layers "F.Cu" "B.Cu")
		(net "NetR69_2")
	)
	(segment
		(start 179.3216 81.9162)
		(end 179.3216 81.0162)
		(width 0.2032)
		(layer "B.Cu")
		(net "NetR69_2")
	)
	(segment
		(start 179.5216 90.1662)
		(end 179.5216 88.5912)
		(width 0.2032)
		(layer "F.Cu")
		(net "NetR61_2")
	)
	(via
		(at 179.5216 88.5912)
		(size 0.4064)
		(drill 0.2032)
		(layers "F.Cu" "B.Cu")
		(net "NetR61_2")
	)
	(segment
		(start 179.5216 90.1662)
		(end 179.5216 88.5912)
		(width 0.2032)
		(layer "B.Cu")
		(net "NetR61_2")
	)
	(segment
		(start 179.5216 90.1662)
		(end 179.7966 90.1662)
		(width 0.2032)
		(layer "B.Cu")
		(net "NetR61_2")
	)
	(segment
		(start 180.7466 88.8162)
		(end 180.80809 88.8162)
		(width 0.2032)
		(layer "B.Cu")
		(net "NetR61_1")
	)
	(segment
		(start 180.7466 90.1662)
		(end 180.7466 88.8162)
		(width 0.2032)
		(layer "B.Cu")
		(net "NetR61_1")
	)
	(segment
		(start 87.7216 64.19436)
		(end 87.7216 62.0662)
		(width 0.254)
		(layer "F.Cu")
		(net "NetR26_2")
	)
	(via
		(at 87.7216 64.19436)
		(size 0.4064)
		(drill 0.2032)
		(layers "F.Cu" "B.Cu")
		(net "NetR26_2")
	)
	(segment
		(start 87.4466 62.0662)
		(end 87.7216 62.0662)
		(width 0.254)
		(layer "B.Cu")
		(net "NetR26_2")
	)
	(segment
		(start 87.7216 64.19436)
		(end 87.7216 62.0662)
		(width 0.254)
		(layer "B.Cu")
		(net "NetR26_2")
	)
	(segment
		(start 86.55491 63.1412)
		(end 86.55491 62.0662)
		(width 0.254)
		(layer "B.Cu")
		(net "NetR26_1")
	)
	(segment
		(start 86.4966 62.0662)
		(end 86.55491 62.0662)
		(width 0.254)
		(layer "B.Cu")
		(net "NetR26_1")
	)
	(segment
		(start 86.5216 56.5662)
		(end 86.5216 54.84708)
		(width 0.254)
		(layer "F.Cu")
		(net "NetR6_2")
	)
	(via
		(at 86.5216 54.84708)
		(size 0.4064)
		(drill 0.2032)
		(layers "F.Cu" "B.Cu")
		(net "NetR6_2")
	)
	(segment
		(start 85.5466 55.0162)
		(end 86.31124 55.0162)
		(width 0.254)
		(layer "B.Cu")
		(net "NetR6_2")
	)
	(segment
		(start 86.5216 56.5662)
		(end 86.5216 54.84708)
		(width 0.254)
		(layer "B.Cu")
		(net "NetR6_2")
	)
	(segment
		(start 86.48036 54.84708)
		(end 86.5216 54.84708)
		(width 0.254)
		(layer "B.Cu")
		(net "NetR6_2")
	)
	(segment
		(start 86.31124 55.0162)
		(end 86.48036 54.84708)
		(width 0.254)
		(layer "B.Cu")
		(net "NetR6_2")
	)
	(segment
		(start 86.4716 56.5662)
		(end 86.5216 56.5662)
		(width 0.254)
		(layer "B.Cu")
		(net "NetR6_2")
	)
	(segment
		(start 93.9216 59.4162)
		(end 95.0216 59.4162)
		(width 0.254)
		(layer "F.Cu")
		(net "NetR5_1")
	)
	(via
		(at 93.9216 59.4162)
		(size 0.4064)
		(drill 0.2032)
		(layers "F.Cu" "B.Cu")
		(net "NetR5_1")
	)
	(segment
		(start 93.9216 59.4162)
		(end 94.8506 59.4162)
		(width 0.254)
		(layer "B.Cu")
		(net "NetR5_1")
	)
	(segment
		(start 93.92833 58.6162)
		(end 95.0216 58.6162)
		(width 0.254)
		(layer "F.Cu")
		(net "NetR4_2")
	)
	(via
		(at 93.92833 58.6162)
		(size 0.4064)
		(drill 0.2032)
		(layers "F.Cu" "B.Cu")
		(net "NetR4_2")
	)
	(segment
		(start 93.92833 58.4511)
		(end 94.8756 58.4511)
		(width 0.254)
		(layer "B.Cu")
		(net "NetR4_2")
	)
	(segment
		(start 93.92833 58.6162)
		(end 93.92833 58.4511)
		(width 0.254)
		(layer "B.Cu")
		(net "NetR4_2")
	)
	(segment
		(start 230.1216 134.6962)
		(end 230.1657 134.7403)
		(width 0.254)
		(layer "F.Cu")
		(net "NetP4_9")
	)
	(segment
		(start 206.5416 145.61546)
		(end 207.73996 145.61546)
		(width 0.2032)
		(layer "F.Cu")
		(net "NetP4_9")
	)
	(via
		(at 230.1657 134.7403)
		(size 0.4064)
		(drill 0.2032)
		(layers "F.Cu" "B.Cu")
		(net "NetP4_9")
	)
	(via
		(at 207.73996 145.61546)
		(size 0.4064)
		(drill 0.2032)
		(layers "F.Cu" "B.Cu")
		(net "NetP4_9")
	)
	(segment
		(start 223.5316 141.5062)
		(end 223.5316 139.81611)
		(width 0.254)
		(layer "B.Cu")
		(net "NetP4_9")
	)
	(segment
		(start 226.2898 138.8162)
		(end 230.3657 134.7403)
		(width 0.254)
		(layer "B.Cu")
		(net "NetP4_9")
	)
	(segment
		(start 211.0216 143.7162)
		(end 221.3216 143.7162)
		(width 0.254)
		(layer "B.Cu")
		(net "NetP4_9")
	)
	(segment
		(start 224.53151 138.8162)
		(end 226.2898 138.8162)
		(width 0.254)
		(layer "B.Cu")
		(net "NetP4_9")
	)
	(segment
		(start 221.3216 143.7162)
		(end 223.5316 141.5062)
		(width 0.254)
		(layer "B.Cu")
		(net "NetP4_9")
	)
	(segment
		(start 223.5316 139.81611)
		(end 224.53151 138.8162)
		(width 0.254)
		(layer "B.Cu")
		(net "NetP4_9")
	)
	(segment
		(start 209.08922 144.2662)
		(end 210.4716 144.2662)
		(width 0.254)
		(layer "B.Cu")
		(net "NetP4_9")
	)
	(segment
		(start 210.4716 144.2662)
		(end 211.0216 143.7162)
		(width 0.254)
		(layer "B.Cu")
		(net "NetP4_9")
	)
	(segment
		(start 207.73996 145.61546)
		(end 209.08922 144.2662)
		(width 0.254)
		(layer "B.Cu")
		(net "NetP4_9")
	)
	(segment
		(start 230.1216 139.7762)
		(end 230.2816 139.7762)
		(width 0.254)
		(layer "F.Cu")
		(net "NetP4_5")
	)
	(segment
		(start 217.8416 145.71545)
		(end 219.20585 145.71545)
		(width 0.2032)
		(layer "F.Cu")
		(net "NetP4_5")
	)
	(via
		(at 230.2816 139.7762)
		(size 0.4064)
		(drill 0.2032)
		(layers "F.Cu" "B.Cu")
		(net "NetP4_5")
	)
	(via
		(at 219.20585 145.71545)
		(size 0.4064)
		(drill 0.2032)
		(layers "F.Cu" "B.Cu")
		(net "NetP4_5")
	)
	(segment
		(start 230.4816 141.07061)
		(end 230.4816 139.7762)
		(width 0.254)
		(layer "B.Cu")
		(net "NetP4_5")
	)
	(segment
		(start 230.4216 145.8162)
		(end 231.0788 145.159)
		(width 0.254)
		(layer "B.Cu")
		(net "NetP4_5")
	)
	(segment
		(start 231.0788 145.159)
		(end 231.0788 141.66781)
		(width 0.254)
		(layer "B.Cu")
		(net "NetP4_5")
	)
	(segment
		(start 230.4816 141.07061)
		(end 231.0788 141.66781)
		(width 0.254)
		(layer "B.Cu")
		(net "NetP4_5")
	)
	(segment
		(start 224.78397 145.71545)
		(end 224.88472 145.8162)
		(width 0.254)
		(layer "B.Cu")
		(net "NetP4_5")
	)
	(segment
		(start 224.88472 145.8162)
		(end 230.4216 145.8162)
		(width 0.254)
		(layer "B.Cu")
		(net "NetP4_5")
	)
	(segment
		(start 219.20585 145.71545)
		(end 224.78397 145.71545)
		(width 0.254)
		(layer "B.Cu")
		(net "NetP4_5")
	)
	(segment
		(start 196.40761 145.69763)
		(end 197.40303 145.69763)
		(width 0.2032)
		(layer "F.Cu")
		(net "NetP4_3")
	)
	(segment
		(start 230.1216 142.3162)
		(end 230.4216 142.3162)
		(width 0.254)
		(layer "F.Cu")
		(net "NetP4_3")
	)
	(via
		(at 230.4216 142.3162)
		(size 0.4064)
		(drill 0.2032)
		(layers "F.Cu" "B.Cu")
		(net "NetP4_3")
	)
	(via
		(at 197.40303 145.69763)
		(size 0.4064)
		(drill 0.2032)
		(layers "F.Cu" "B.Cu")
		(net "NetP4_3")
	)
	(segment
		(start 216.28511 144.59045)
		(end 216.28511 144.5162)
		(width 0.2032)
		(layer "B.Cu")
		(net "NetP4_3")
	)
	(segment
		(start 223.1216 143.3162)
		(end 229.6216 143.3162)
		(width 0.2032)
		(layer "B.Cu")
		(net "NetP4_3")
	)
	(segment
		(start 197.40303 145.69763)
		(end 205.70537 145.69763)
		(width 0.2032)
		(layer "B.Cu")
		(net "NetP4_3")
	)
	(segment
		(start 213.9216 146.0162)
		(end 214.85936 146.0162)
		(width 0.2032)
		(layer "B.Cu")
		(net "NetP4_3")
	)
	(segment
		(start 213.5216 145.6162)
		(end 213.9216 146.0162)
		(width 0.2032)
		(layer "B.Cu")
		(net "NetP4_3")
	)
	(segment
		(start 216.28511 144.5162)
		(end 221.9216 144.5162)
		(width 0.2032)
		(layer "B.Cu")
		(net "NetP4_3")
	)
	(segment
		(start 214.85936 146.0162)
		(end 216.28511 144.59045)
		(width 0.2032)
		(layer "B.Cu")
		(net "NetP4_3")
	)
	(segment
		(start 209.2216 146.2162)
		(end 209.8216 145.6162)
		(width 0.2032)
		(layer "B.Cu")
		(net "NetP4_3")
	)
	(segment
		(start 221.9216 144.5162)
		(end 223.1216 143.3162)
		(width 0.2032)
		(layer "B.Cu")
		(net "NetP4_3")
	)
	(segment
		(start 229.6216 143.3162)
		(end 230.6216 142.3162)
		(width 0.2032)
		(layer "B.Cu")
		(net "NetP4_3")
	)
	(segment
		(start 205.70537 145.69763)
		(end 206.22394 146.2162)
		(width 0.2032)
		(layer "B.Cu")
		(net "NetP4_3")
	)
	(segment
		(start 206.22394 146.2162)
		(end 209.2216 146.2162)
		(width 0.2032)
		(layer "B.Cu")
		(net "NetP4_3")
	)
	(segment
		(start 209.8216 145.6162)
		(end 213.5216 145.6162)
		(width 0.2032)
		(layer "B.Cu")
		(net "NetP4_3")
	)
	(segment
		(start 230.1216 144.8562)
		(end 230.30095 144.8562)
		(width 0.254)
		(layer "F.Cu")
		(net "NetP4_1")
	)
	(segment
		(start 185.10761 145.49763)
		(end 186.20577 145.49763)
		(width 0.2032)
		(layer "F.Cu")
		(net "NetP4_1")
	)
	(via
		(at 230.30095 144.8562)
		(size 0.4064)
		(drill 0.2032)
		(layers "F.Cu" "B.Cu")
		(net "NetP4_1")
	)
	(via
		(at 186.20577 145.49763)
		(size 0.4064)
		(drill 0.2032)
		(layers "F.Cu" "B.Cu")
		(net "NetP4_1")
	)
	(segment
		(start 226.00034 144.8562)
		(end 230.50095 144.8562)
		(width 0.254)
		(layer "B.Cu")
		(net "NetP4_1")
	)
	(segment
		(start 186.20577 145.49763)
		(end 186.24635 145.49763)
		(width 0.254)
		(layer "B.Cu")
		(net "NetP4_1")
	)
	(segment
		(start 193.33124 146.72266)
		(end 215.11514 146.72266)
		(width 0.254)
		(layer "B.Cu")
		(net "NetP4_1")
	)
	(segment
		(start 222.40762 145.13018)
		(end 223.2216 144.3162)
		(width 0.254)
		(layer "B.Cu")
		(net "NetP4_1")
	)
	(segment
		(start 215.11514 146.72266)
		(end 216.70762 145.13018)
		(width 0.254)
		(layer "B.Cu")
		(net "NetP4_1")
	)
	(segment
		(start 192.32478 145.7162)
		(end 193.33124 146.72266)
		(width 0.254)
		(layer "B.Cu")
		(net "NetP4_1")
	)
	(segment
		(start 216.70762 145.13018)
		(end 222.40762 145.13018)
		(width 0.254)
		(layer "B.Cu")
		(net "NetP4_1")
	)
	(segment
		(start 225.46034 144.3162)
		(end 226.00034 144.8562)
		(width 0.254)
		(layer "B.Cu")
		(net "NetP4_1")
	)
	(segment
		(start 186.46492 145.7162)
		(end 192.32478 145.7162)
		(width 0.254)
		(layer "B.Cu")
		(net "NetP4_1")
	)
	(segment
		(start 223.2216 144.3162)
		(end 225.46034 144.3162)
		(width 0.254)
		(layer "B.Cu")
		(net "NetP4_1")
	)
	(segment
		(start 186.24635 145.49763)
		(end 186.46492 145.7162)
		(width 0.254)
		(layer "B.Cu")
		(net "NetP4_1")
	)
	(segment
		(start 220.64778 112.3162)
		(end 221.04778 112.7162)
		(width 0.254)
		(layer "F.Cu")
		(net "NetD22_1")
	)
	(segment
		(start 221.04778 112.7162)
		(end 223.9716 112.7162)
		(width 0.254)
		(layer "F.Cu")
		(net "NetD22_1")
	)
	(segment
		(start 220.6216 112.3162)
		(end 220.64778 112.3162)
		(width 0.254)
		(layer "F.Cu")
		(net "NetD22_1")
	)
	(via
		(at 220.6216 112.3162)
		(size 0.4064)
		(drill 0.2032)
		(layers "F.Cu" "B.Cu")
		(net "NetD22_1")
	)
	(segment
		(start 220.6216 113.2662)
		(end 220.6216 112.3162)
		(width 0.254)
		(layer "B.Cu")
		(net "NetD22_1")
	)
	(segment
		(start 220.6466 114.3162)
		(end 223.9716 114.3162)
		(width 0.254)
		(layer "F.Cu")
		(net "NetD21_1")
	)
	(segment
		(start 223.8716 114.4162)
		(end 223.9716 114.3162)
		(width 0.254)
		(layer "F.Cu")
		(net "NetD21_1")
	)
	(segment
		(start 219.9216 115.0412)
		(end 220.6466 114.3162)
		(width 0.254)
		(layer "F.Cu")
		(net "NetD21_1")
	)
	(via
		(at 219.9216 115.0412)
		(size 0.4064)
		(drill 0.2032)
		(layers "F.Cu" "B.Cu")
		(net "NetD21_1")
	)
	(segment
		(start 219.9216 116.0912)
		(end 219.9216 115.0412)
		(width 0.254)
		(layer "B.Cu")
		(net "NetD21_1")
	)
	(segment
		(start 170.3216 118.3912)
		(end 170.32184 118.39096)
		(width 0.254)
		(layer "F.Cu")
		(net "MAC_I2C_SDA")
	)
	(segment
		(start 169.9966 118.0412)
		(end 169.9966 116.4412)
		(width 0.254)
		(layer "F.Cu")
		(net "MAC_I2C_SDA")
	)
	(segment
		(start 169.9966 118.0412)
		(end 170.3216 118.3662)
		(width 0.254)
		(layer "F.Cu")
		(net "MAC_I2C_SDA")
	)
	(segment
		(start 158.0716 116.8162)
		(end 158.80532 116.8162)
		(width 0.254)
		(layer "F.Cu")
		(net "MAC_I2C_SDA")
	)
	(via
		(at 170.32184 118.39096)
		(size 0.4064)
		(drill 0.2032)
		(layers "F.Cu" "B.Cu")
		(net "MAC_I2C_SDA")
	)
	(via
		(at 158.80532 116.8162)
		(size 0.4064)
		(drill 0.2032)
		(layers "F.Cu" "B.Cu")
		(net "MAC_I2C_SDA")
	)
	(segment
		(start 169.48848 118.39096)
		(end 170.32184 118.39096)
		(width 0.254)
		(layer "B.Cu")
		(net "MAC_I2C_SDA")
	)
	(segment
		(start 159.40532 117.4162)
		(end 168.51372 117.4162)
		(width 0.254)
		(layer "B.Cu")
		(net "MAC_I2C_SDA")
	)
	(segment
		(start 158.80532 116.8162)
		(end 159.40532 117.4162)
		(width 0.254)
		(layer "B.Cu")
		(net "MAC_I2C_SDA")
	)
	(segment
		(start 168.51372 117.4162)
		(end 169.48848 118.39096)
		(width 0.254)
		(layer "B.Cu")
		(net "MAC_I2C_SDA")
	)
	(segment
		(start 171.4091 118.3787)
		(end 171.4216 118.3912)
		(width 0.254)
		(layer "F.Cu")
		(net "MAC_I2C_SCL")
	)
	(segment
		(start 170.6466 117.5912)
		(end 170.6466 116.4412)
		(width 0.254)
		(layer "F.Cu")
		(net "MAC_I2C_SCL")
	)
	(segment
		(start 157.9716 115.0162)
		(end 158.68113 115.0162)
		(width 0.254)
		(layer "F.Cu")
		(net "MAC_I2C_SCL")
	)
	(segment
		(start 170.6466 117.5912)
		(end 171.4216 118.3662)
		(width 0.254)
		(layer "F.Cu")
		(net "MAC_I2C_SCL")
	)
	(via
		(at 158.68113 115.0162)
		(size 0.4064)
		(drill 0.2032)
		(layers "F.Cu" "B.Cu")
		(net "MAC_I2C_SCL")
	)
	(via
		(at 171.4091 118.3787)
		(size 0.4064)
		(drill 0.2032)
		(layers "F.Cu" "B.Cu")
		(net "MAC_I2C_SCL")
	)
	(segment
		(start 169.8466 116.8162)
		(end 171.4091 118.3787)
		(width 0.254)
		(layer "B.Cu")
		(net "MAC_I2C_SCL")
	)
	(segment
		(start 160.48113 116.8162)
		(end 169.8466 116.8162)
		(width 0.254)
		(layer "B.Cu")
		(net "MAC_I2C_SCL")
	)
	(segment
		(start 158.68113 115.0162)
		(end 160.48113 116.8162)
		(width 0.254)
		(layer "B.Cu")
		(net "MAC_I2C_SCL")
	)
	(segment
		(start 153.1982 118.6428)
		(end 153.3982 118.6428)
		(width 0.2032)
		(layer "F.Cu")
		(net "MAC_FPGA_UART_RX")
	)
	(segment
		(start 157.9216 101.06121)
		(end 158.04904 100.93377)
		(width 0.2032)
		(layer "F.Cu")
		(net "MAC_FPGA_UART_RX")
	)
	(segment
		(start 158.04904 100.93377)
		(end 158.04904 99.26063)
		(width 0.2032)
		(layer "F.Cu")
		(net "MAC_FPGA_UART_RX")
	)
	(segment
		(start 153.3982 118.6428)
		(end 153.5716 118.8162)
		(width 0.2032)
		(layer "F.Cu")
		(net "MAC_FPGA_UART_RX")
	)
	(segment
		(start 151.4716 116.9162)
		(end 153.1982 118.6428)
		(width 0.2032)
		(layer "F.Cu")
		(net "MAC_FPGA_UART_RX")
	)
	(segment
		(start 157.9216 101.1162)
		(end 157.9216 101.06121)
		(width 0.2032)
		(layer "F.Cu")
		(net "MAC_FPGA_UART_RX")
	)
	(segment
		(start 150.80631 116.9162)
		(end 151.4716 116.9162)
		(width 0.2032)
		(layer "F.Cu")
		(net "MAC_FPGA_UART_RX")
	)
	(via
		(at 150.80631 116.9162)
		(size 0.4064)
		(drill 0.2032)
		(layers "F.Cu" "B.Cu")
		(net "MAC_FPGA_UART_RX")
	)
	(via
		(at 157.9216 101.1162)
		(size 0.4064)
		(drill 0.2032)
		(layers "F.Cu" "B.Cu")
		(net "MAC_FPGA_UART_RX")
	)
	(segment
		(start 162.0216 108.68317)
		(end 162.0216 103.45504)
		(width 0.2032)
		(layer "B.Cu")
		(net "MAC_FPGA_UART_RX")
	)
	(segment
		(start 154.5034 112.7844)
		(end 157.92037 112.7844)
		(width 0.2032)
		(layer "B.Cu")
		(net "MAC_FPGA_UART_RX")
	)
	(segment
		(start 158.9216 101.1162)
		(end 160.1216 102.3162)
		(width 0.2032)
		(layer "B.Cu")
		(net "MAC_FPGA_UART_RX")
	)
	(segment
		(start 157.9216 101.1162)
		(end 158.9216 101.1162)
		(width 0.2032)
		(layer "B.Cu")
		(net "MAC_FPGA_UART_RX")
	)
	(segment
		(start 151.3709 116.35162)
		(end 151.3709 115.9169)
		(width 0.2032)
		(layer "B.Cu")
		(net "MAC_FPGA_UART_RX")
	)
	(segment
		(start 160.1216 102.3162)
		(end 160.88276 102.3162)
		(width 0.2032)
		(layer "B.Cu")
		(net "MAC_FPGA_UART_RX")
	)
	(segment
		(start 150.80631 116.9162)
		(end 151.3709 116.35162)
		(width 0.2032)
		(layer "B.Cu")
		(net "MAC_FPGA_UART_RX")
	)
	(segment
		(start 151.3709 115.9169)
		(end 154.5034 112.7844)
		(width 0.2032)
		(layer "B.Cu")
		(net "MAC_FPGA_UART_RX")
	)
	(segment
		(start 157.92037 112.7844)
		(end 162.0216 108.68317)
		(width 0.2032)
		(layer "B.Cu")
		(net "MAC_FPGA_UART_RX")
	)
	(segment
		(start 160.88276 102.3162)
		(end 162.0216 103.45504)
		(width 0.2032)
		(layer "B.Cu")
		(net "MAC_FPGA_UART_RX")
	)
	(segment
		(start 157.54891 100.38889)
		(end 157.54891 99.26063)
		(width 0.2032)
		(layer "F.Cu")
		(net "FPGA_MAC_UART_TX")
	)
	(segment
		(start 152.1716 115.1162)
		(end 152.1716 114.6162)
		(width 0.2032)
		(layer "F.Cu")
		(net "FPGA_MAC_UART_TX")
	)
	(segment
		(start 151.45144 115.1162)
		(end 152.1716 115.1162)
		(width 0.2032)
		(layer "F.Cu")
		(net "FPGA_MAC_UART_TX")
	)
	(segment
		(start 157.0216 100.9162)
		(end 157.54891 100.38889)
		(width 0.2032)
		(layer "F.Cu")
		(net "FPGA_MAC_UART_TX")
	)
	(segment
		(start 152.1716 114.6162)
		(end 153.5716 113.2162)
		(width 0.2032)
		(layer "F.Cu")
		(net "FPGA_MAC_UART_TX")
	)
	(via
		(at 157.0216 100.9162)
		(size 0.4064)
		(drill 0.2032)
		(layers "F.Cu" "B.Cu")
		(net "FPGA_MAC_UART_TX")
	)
	(via
		(at 151.45144 115.1162)
		(size 0.4064)
		(drill 0.2032)
		(layers "F.Cu" "B.Cu")
		(net "FPGA_MAC_UART_TX")
	)
	(segment
		(start 154.25144 112.3162)
		(end 157.9216 112.3162)
		(width 0.2032)
		(layer "B.Cu")
		(net "FPGA_MAC_UART_TX")
	)
	(segment
		(start 151.45144 115.1162)
		(end 154.25144 112.3162)
		(width 0.2032)
		(layer "B.Cu")
		(net "FPGA_MAC_UART_TX")
	)
	(segment
		(start 159.19002 102.67376)
		(end 161.47651 104.96025)
		(width 0.2032)
		(layer "B.Cu")
		(net "FPGA_MAC_UART_TX")
	)
	(segment
		(start 157.0216 102.13181)
		(end 157.56354 102.67376)
		(width 0.2032)
		(layer "B.Cu")
		(net "FPGA_MAC_UART_TX")
	)
	(segment
		(start 157.56354 102.67376)
		(end 159.19002 102.67376)
		(width 0.2032)
		(layer "B.Cu")
		(net "FPGA_MAC_UART_TX")
	)
	(segment
		(start 161.47651 108.76129)
		(end 161.47651 104.96025)
		(width 0.2032)
		(layer "B.Cu")
		(net "FPGA_MAC_UART_TX")
	)
	(segment
		(start 157.9216 112.3162)
		(end 161.47651 108.76129)
		(width 0.2032)
		(layer "B.Cu")
		(net "FPGA_MAC_UART_TX")
	)
	(segment
		(start 157.0216 102.13181)
		(end 157.0216 100.9162)
		(width 0.2032)
		(layer "B.Cu")
		(net "FPGA_MAC_UART_TX")
	)
	(segment
		(start 160.5216 97.9467)
		(end 160.54891 97.97401)
		(width 0.2032)
		(layer "F.Cu")
		(net "FPGA_BNO_XOUT32")
	)
	(segment
		(start 160.5216 97.9467)
		(end 160.5216 97.2162)
		(width 0.2032)
		(layer "F.Cu")
		(net "FPGA_BNO_XOUT32")
	)
	(segment
		(start 119.58072 89.4662)
		(end 119.58072 89.4662)
		(width 0.2032)
		(layer "F.Cu")
		(net "FPGA_BNO_XOUT32")
	)
	(segment
		(start 160.54891 99.26063)
		(end 160.54891 97.97401)
		(width 0.2032)
		(layer "F.Cu")
		(net "FPGA_BNO_XOUT32")
	)
	(segment
		(start 118.98073 88.8662)
		(end 119.58072 89.4662)
		(width 0.2032)
		(layer "F.Cu")
		(net "FPGA_BNO_XOUT32")
	)
	(via
		(at 119.58072 89.4662)
		(size 0.4064)
		(drill 0.2032)
		(layers "F.Cu" "B.Cu")
		(net "FPGA_BNO_XOUT32")
	)
	(via
		(at 160.5216 97.2162)
		(size 0.4064)
		(drill 0.2032)
		(layers "F.Cu" "B.Cu")
		(net "FPGA_BNO_XOUT32")
	)
	(segment
		(start 143.95259 97.58521)
		(end 150.26768 97.58521)
		(width 0.2032)
		(layer "In2.Cu")
		(net "FPGA_BNO_XOUT32")
	)
	(segment
		(start 157.55845 96.34239)
		(end 157.8096 96.59354)
		(width 0.2032)
		(layer "In2.Cu")
		(net "FPGA_BNO_XOUT32")
	)
	(segment
		(start 131.67167 115.06613)
		(end 131.67167 114.36613)
		(width 0.2032)
		(layer "In2.Cu")
		(net "FPGA_BNO_XOUT32")
	)
	(segment
		(start 155.74203 96.34239)
		(end 157.55845 96.34239)
		(width 0.2032)
		(layer "In2.Cu")
		(net "FPGA_BNO_XOUT32")
	)
	(segment
		(start 155.49088 96.59354)
		(end 155.74203 96.34239)
		(width 0.2032)
		(layer "In2.Cu")
		(net "FPGA_BNO_XOUT32")
	)
	(segment
		(start 150.44867 96.59354)
		(end 155.49088 96.59354)
		(width 0.2032)
		(layer "In2.Cu")
		(net "FPGA_BNO_XOUT32")
	)
	(segment
		(start 119.58072 96.98457)
		(end 120.16698 97.57082)
		(width 0.2032)
		(layer "In2.Cu")
		(net "FPGA_BNO_XOUT32")
	)
	(segment
		(start 157.8096 96.59354)
		(end 158.87337 96.59354)
		(width 0.2032)
		(layer "In2.Cu")
		(net "FPGA_BNO_XOUT32")
	)
	(segment
		(start 132.75882 113.27898)
		(end 132.75882 108.77898)
		(width 0.2032)
		(layer "In2.Cu")
		(net "FPGA_BNO_XOUT32")
	)
	(segment
		(start 120.16698 106.11992)
		(end 129.40497 115.35792)
		(width 0.2032)
		(layer "In2.Cu")
		(net "FPGA_BNO_XOUT32")
	)
	(segment
		(start 158.87337 96.59354)
		(end 159.49603 97.2162)
		(width 0.2032)
		(layer "In2.Cu")
		(net "FPGA_BNO_XOUT32")
	)
	(segment
		(start 150.44867 97.40421)
		(end 150.44867 96.59354)
		(width 0.2032)
		(layer "In2.Cu")
		(net "FPGA_BNO_XOUT32")
	)
	(segment
		(start 132.75882 108.77898)
		(end 143.95259 97.58521)
		(width 0.2032)
		(layer "In2.Cu")
		(net "FPGA_BNO_XOUT32")
	)
	(segment
		(start 131.37988 115.35792)
		(end 131.67167 115.06613)
		(width 0.2032)
		(layer "In2.Cu")
		(net "FPGA_BNO_XOUT32")
	)
	(segment
		(start 131.67167 114.36613)
		(end 132.75882 113.27898)
		(width 0.2032)
		(layer "In2.Cu")
		(net "FPGA_BNO_XOUT32")
	)
	(segment
		(start 129.40497 115.35792)
		(end 131.37988 115.35792)
		(width 0.2032)
		(layer "In2.Cu")
		(net "FPGA_BNO_XOUT32")
	)
	(segment
		(start 150.26768 97.58521)
		(end 150.44867 97.40421)
		(width 0.2032)
		(layer "In2.Cu")
		(net "FPGA_BNO_XOUT32")
	)
	(segment
		(start 159.49603 97.2162)
		(end 160.5216 97.2162)
		(width 0.2032)
		(layer "In2.Cu")
		(net "FPGA_BNO_XOUT32")
	)
	(segment
		(start 120.16698 106.11992)
		(end 120.16698 97.57082)
		(width 0.2032)
		(layer "In2.Cu")
		(net "FPGA_BNO_XOUT32")
	)
	(segment
		(start 119.58072 96.98457)
		(end 119.58072 89.4662)
		(width 0.2032)
		(layer "In2.Cu")
		(net "FPGA_BNO_XOUT32")
	)
	(segment
		(start 118.98073 83.9662)
		(end 119.88072 83.9662)
		(width 0.2032)
		(layer "F.Cu")
		(net "FPGA_BNO_XIN32")
	)
	(segment
		(start 159.19485 97.52567)
		(end 160.02567 98.35649)
		(width 0.2032)
		(layer "F.Cu")
		(net "FPGA_BNO_XIN32")
	)
	(segment
		(start 160.02567 99.23726)
		(end 160.04904 99.26063)
		(width 0.2032)
		(layer "F.Cu")
		(net "FPGA_BNO_XIN32")
	)
	(segment
		(start 160.02567 99.23726)
		(end 160.02567 98.35649)
		(width 0.2032)
		(layer "F.Cu")
		(net "FPGA_BNO_XIN32")
	)
	(via
		(at 119.88072 83.9662)
		(size 0.4064)
		(drill 0.2032)
		(layers "F.Cu" "B.Cu")
		(net "FPGA_BNO_XIN32")
	)
	(via
		(at 159.19485 97.52567)
		(size 0.4064)
		(drill 0.2032)
		(layers "F.Cu" "B.Cu")
		(net "FPGA_BNO_XIN32")
	)
	(segment
		(start 119.5216 85.9162)
		(end 124.32028 85.9162)
		(width 0.2032)
		(layer "B.Cu")
		(net "FPGA_BNO_XIN32")
	)
	(segment
		(start 128.82028 81.4162)
		(end 132.9216 81.4162)
		(width 0.2032)
		(layer "B.Cu")
		(net "FPGA_BNO_XIN32")
	)
	(segment
		(start 152.5216 106.17278)
		(end 152.5216 99.98158)
		(width 0.2032)
		(layer "B.Cu")
		(net "FPGA_BNO_XIN32")
	)
	(segment
		(start 132.7216 86.0162)
		(end 134.8216 88.1162)
		(width 0.2032)
		(layer "B.Cu")
		(net "FPGA_BNO_XIN32")
	)
	(segment
		(start 124.32028 85.9162)
		(end 128.82028 81.4162)
		(width 0.2032)
		(layer "B.Cu")
		(net "FPGA_BNO_XIN32")
	)
	(segment
		(start 132.7216 86.0162)
		(end 132.7216 83.3162)
		(width 0.2032)
		(layer "B.Cu")
		(net "FPGA_BNO_XIN32")
	)
	(segment
		(start 154.97751 97.52567)
		(end 159.19485 97.52567)
		(width 0.2032)
		(layer "B.Cu")
		(net "FPGA_BNO_XIN32")
	)
	(segment
		(start 132.9216 81.4162)
		(end 133.35636 81.85096)
		(width 0.2032)
		(layer "B.Cu")
		(net "FPGA_BNO_XIN32")
	)
	(segment
		(start 149.05826 105.42951)
		(end 149.05826 101.31416)
		(width 0.2032)
		(layer "B.Cu")
		(net "FPGA_BNO_XIN32")
	)
	(segment
		(start 149.05826 105.42951)
		(end 149.93436 106.30561)
		(width 0.2032)
		(layer "B.Cu")
		(net "FPGA_BNO_XIN32")
	)
	(segment
		(start 119.1216 85.5162)
		(end 119.5216 85.9162)
		(width 0.2032)
		(layer "B.Cu")
		(net "FPGA_BNO_XIN32")
	)
	(segment
		(start 119.1216 85.5162)
		(end 119.1216 84.72532)
		(width 0.2032)
		(layer "B.Cu")
		(net "FPGA_BNO_XIN32")
	)
	(segment
		(start 132.7216 83.3162)
		(end 133.35636 82.68144)
		(width 0.2032)
		(layer "B.Cu")
		(net "FPGA_BNO_XIN32")
	)
	(segment
		(start 140.9216 100.2162)
		(end 147.96031 100.2162)
		(width 0.2032)
		(layer "B.Cu")
		(net "FPGA_BNO_XIN32")
	)
	(segment
		(start 133.35636 82.68144)
		(end 133.35636 81.85096)
		(width 0.2032)
		(layer "B.Cu")
		(net "FPGA_BNO_XIN32")
	)
	(segment
		(start 134.8216 94.1162)
		(end 140.9216 100.2162)
		(width 0.2032)
		(layer "B.Cu")
		(net "FPGA_BNO_XIN32")
	)
	(segment
		(start 152.5216 99.98158)
		(end 154.97751 97.52567)
		(width 0.2032)
		(layer "B.Cu")
		(net "FPGA_BNO_XIN32")
	)
	(segment
		(start 119.1216 84.72532)
		(end 119.88072 83.9662)
		(width 0.2032)
		(layer "B.Cu")
		(net "FPGA_BNO_XIN32")
	)
	(segment
		(start 149.93436 106.30561)
		(end 152.38877 106.30561)
		(width 0.2032)
		(layer "B.Cu")
		(net "FPGA_BNO_XIN32")
	)
	(segment
		(start 152.38877 106.30561)
		(end 152.5216 106.17278)
		(width 0.2032)
		(layer "B.Cu")
		(net "FPGA_BNO_XIN32")
	)
	(segment
		(start 134.8216 94.1162)
		(end 134.8216 88.1162)
		(width 0.2032)
		(layer "B.Cu")
		(net "FPGA_BNO_XIN32")
	)
	(segment
		(start 147.96031 100.2162)
		(end 149.05826 101.31416)
		(width 0.2032)
		(layer "B.Cu")
		(net "FPGA_BNO_XIN32")
	)
	(segment
		(start 158.09877 120.71464)
		(end 158.80033 121.4162)
		(width 0.2032)
		(layer "F.Cu")
		(net "DIP_SW_MACSER_SEL")
	)
	(segment
		(start 153.52148 119.8162)
		(end 153.52148 119.71609)
		(width 0.2032)
		(layer "F.Cu")
		(net "DIP_SW_MACSER_SEL")
	)
	(segment
		(start 153.3216 117.0162)
		(end 153.5216 116.8162)
		(width 0.2032)
		(layer "F.Cu")
		(net "DIP_SW_MACSER_SEL")
	)
	(segment
		(start 221.8216 106.3162)
		(end 221.8216 102.8662)
		(width 0.2032)
		(layer "F.Cu")
		(net "DIP_SW_MACSER_SEL")
	)
	(segment
		(start 181.7216 116.8162)
		(end 182.06888 117.16348)
		(width 0.2032)
		(layer "F.Cu")
		(net "DIP_SW_MACSER_SEL")
	)
	(segment
		(start 180.24208 116.8162)
		(end 181.7216 116.8162)
		(width 0.2032)
		(layer "F.Cu")
		(net "DIP_SW_MACSER_SEL")
	)
	(segment
		(start 181.0216 119.58567)
		(end 182.06888 118.53838)
		(width 0.2032)
		(layer "F.Cu")
		(net "DIP_SW_MACSER_SEL")
	)
	(segment
		(start 221.87785 106.25995)
		(end 223.26084 106.25995)
		(width 0.2032)
		(layer "F.Cu")
		(net "DIP_SW_MACSER_SEL")
	)
	(segment
		(start 188.30787 131.62993)
		(end 188.30787 131.46296)
		(width 0.2032)
		(layer "F.Cu")
		(net "DIP_SW_MACSER_SEL")
	)
	(segment
		(start 206.4914 103.7464)
		(end 206.4914 103.5464)
		(width 0.2032)
		(layer "F.Cu")
		(net "DIP_SW_MACSER_SEL")
	)
	(segment
		(start 153.14472 119.3844)
		(end 153.47641 119.71609)
		(width 0.2032)
		(layer "F.Cu")
		(net "DIP_SW_MACSER_SEL")
	)
	(segment
		(start 153.8216 114.81633)
		(end 153.8216 114.2162)
		(width 0.2032)
		(layer "F.Cu")
		(net "DIP_SW_MACSER_SEL")
	)
	(segment
		(start 204.6216 105.6162)
		(end 206.4914 103.7464)
		(width 0.2032)
		(layer "F.Cu")
		(net "DIP_SW_MACSER_SEL")
	)
	(segment
		(start 153.5216 116.8162)
		(end 154.1716 116.8162)
		(width 0.2032)
		(layer "F.Cu")
		(net "DIP_SW_MACSER_SEL")
	)
	(segment
		(start 191.15278 116.20752)
		(end 201.6441 105.7162)
		(width 0.2032)
		(layer "F.Cu")
		(net "DIP_SW_MACSER_SEL")
	)
	(segment
		(start 158.80033 121.4162)
		(end 175.64208 121.4162)
		(width 0.2032)
		(layer "F.Cu")
		(net "DIP_SW_MACSER_SEL")
	)
	(segment
		(start 189.5898 130.18103)
		(end 189.5898 127.75499)
		(width 0.2032)
		(layer "F.Cu")
		(net "DIP_SW_MACSER_SEL")
	)
	(segment
		(start 187.9216 132.0162)
		(end 188.30787 131.62993)
		(width 0.2032)
		(layer "F.Cu")
		(net "DIP_SW_MACSER_SEL")
	)
	(segment
		(start 187.4216 133.1162)
		(end 187.9216 132.6162)
		(width 0.2032)
		(layer "F.Cu")
		(net "DIP_SW_MACSER_SEL")
	)
	(segment
		(start 181.0216 131.7162)
		(end 181.0216 119.58567)
		(width 0.2032)
		(layer "F.Cu")
		(net "DIP_SW_MACSER_SEL")
	)
	(segment
		(start 201.6441 105.7162)
		(end 202.5216 105.7162)
		(width 0.2032)
		(layer "F.Cu")
		(net "DIP_SW_MACSER_SEL")
	)
	(segment
		(start 218.73299 99.77759)
		(end 221.8216 102.8662)
		(width 0.2032)
		(layer "F.Cu")
		(net "DIP_SW_MACSER_SEL")
	)
	(segment
		(start 153.52148 119.8162)
		(end 154.41992 120.71464)
		(width 0.2032)
		(layer "F.Cu")
		(net "DIP_SW_MACSER_SEL")
	)
	(segment
		(start 153.3216 117.4162)
		(end 153.3216 117.0162)
		(width 0.2032)
		(layer "F.Cu")
		(net "DIP_SW_MACSER_SEL")
	)
	(segment
		(start 206.4914 103.5464)
		(end 210.26021 99.77759)
		(width 0.2032)
		(layer "F.Cu")
		(net "DIP_SW_MACSER_SEL")
	)
	(segment
		(start 191.15278 126.89717)
		(end 191.15278 116.20752)
		(width 0.2032)
		(layer "F.Cu")
		(net "DIP_SW_MACSER_SEL")
	)
	(segment
		(start 221.8216 106.3162)
		(end 221.87785 106.25995)
		(width 0.2032)
		(layer "F.Cu")
		(net "DIP_SW_MACSER_SEL")
	)
	(segment
		(start 154.41992 120.71464)
		(end 158.09877 120.71464)
		(width 0.2032)
		(layer "F.Cu")
		(net "DIP_SW_MACSER_SEL")
	)
	(segment
		(start 190.32859 127.0162)
		(end 191.03375 127.0162)
		(width 0.2032)
		(layer "F.Cu")
		(net "DIP_SW_MACSER_SEL")
	)
	(segment
		(start 182.06888 118.53838)
		(end 182.06888 117.16348)
		(width 0.2032)
		(layer "F.Cu")
		(net "DIP_SW_MACSER_SEL")
	)
	(segment
		(start 181.0216 131.7162)
		(end 182.4216 133.1162)
		(width 0.2032)
		(layer "F.Cu")
		(net "DIP_SW_MACSER_SEL")
	)
	(segment
		(start 187.9216 132.6162)
		(end 187.9216 132.0162)
		(width 0.2032)
		(layer "F.Cu")
		(net "DIP_SW_MACSER_SEL")
	)
	(segment
		(start 210.26021 99.77759)
		(end 218.73299 99.77759)
		(width 0.2032)
		(layer "F.Cu")
		(net "DIP_SW_MACSER_SEL")
	)
	(segment
		(start 153.47641 119.71609)
		(end 153.52148 119.71609)
		(width 0.2032)
		(layer "F.Cu")
		(net "DIP_SW_MACSER_SEL")
	)
	(segment
		(start 191.03375 127.0162)
		(end 191.15278 126.89717)
		(width 0.2032)
		(layer "F.Cu")
		(net "DIP_SW_MACSER_SEL")
	)
	(segment
		(start 189.5898 127.75499)
		(end 190.32859 127.0162)
		(width 0.2032)
		(layer "F.Cu")
		(net "DIP_SW_MACSER_SEL")
	)
	(segment
		(start 182.4216 133.1162)
		(end 187.4216 133.1162)
		(width 0.2032)
		(layer "F.Cu")
		(net "DIP_SW_MACSER_SEL")
	)
	(segment
		(start 153.8216 114.81633)
		(end 154.22283 115.21756)
		(width 0.2032)
		(layer "F.Cu")
		(net "DIP_SW_MACSER_SEL")
	)
	(segment
		(start 175.64208 121.4162)
		(end 180.24208 116.8162)
		(width 0.2032)
		(layer "F.Cu")
		(net "DIP_SW_MACSER_SEL")
	)
	(segment
		(start 188.30787 131.46296)
		(end 189.5898 130.18103)
		(width 0.2032)
		(layer "F.Cu")
		(net "DIP_SW_MACSER_SEL")
	)
	(via
		(at 153.8216 114.2162)
		(size 0.4064)
		(drill 0.2032)
		(layers "F.Cu" "B.Cu")
		(net "DIP_SW_MACSER_SEL")
	)
	(via
		(at 221.8216 106.3162)
		(size 0.4064)
		(drill 0.2032)
		(layers "F.Cu" "B.Cu")
		(net "DIP_SW_MACSER_SEL")
	)
	(via
		(at 204.6216 105.6162)
		(size 0.4064)
		(drill 0.2032)
		(layers "F.Cu" "B.Cu")
		(net "DIP_SW_MACSER_SEL")
	)
	(via
		(at 153.14472 119.3844)
		(size 0.4064)
		(drill 0.2032)
		(layers "F.Cu" "B.Cu")
		(net "DIP_SW_MACSER_SEL")
	)
	(via
		(at 153.3216 117.4162)
		(size 0.4064)
		(drill 0.2032)
		(layers "F.Cu" "B.Cu")
		(net "DIP_SW_MACSER_SEL")
	)
	(via
		(at 202.5216 105.7162)
		(size 0.4064)
		(drill 0.2032)
		(layers "F.Cu" "B.Cu")
		(net "DIP_SW_MACSER_SEL")
	)
	(segment
		(start 221.8216 106.3162)
		(end 222.8392 107.3338)
		(width 0.2032)
		(layer "B.Cu")
		(net "DIP_SW_MACSER_SEL")
	)
	(segment
		(start 221.2216 112.1912)
		(end 222.0216 112.9912)
		(width 0.2032)
		(layer "B.Cu")
		(net "DIP_SW_MACSER_SEL")
	)
	(segment
		(start 153.3216 117.47119)
		(end 153.3216 117.4162)
		(width 0.2032)
		(layer "B.Cu")
		(net "DIP_SW_MACSER_SEL")
	)
	(segment
		(start 221.2216 112.1912)
		(end 221.2216 111.1162)
		(width 0.2032)
		(layer "B.Cu")
		(net "DIP_SW_MACSER_SEL")
	)
	(segment
		(start 152.0966 116.94462)
		(end 152.0966 115.9412)
		(width 0.2032)
		(layer "B.Cu")
		(net "DIP_SW_MACSER_SEL")
	)
	(segment
		(start 152.56818 117.4162)
		(end 153.3216 117.4162)
		(width 0.2032)
		(layer "B.Cu")
		(net "DIP_SW_MACSER_SEL")
	)
	(segment
		(start 152.0966 116.94462)
		(end 152.56818 117.4162)
		(width 0.2032)
		(layer "B.Cu")
		(net "DIP_SW_MACSER_SEL")
	)
	(segment
		(start 221.1966 105.6912)
		(end 221.8216 106.3162)
		(width 0.2032)
		(layer "B.Cu")
		(net "DIP_SW_MACSER_SEL")
	)
	(segment
		(start 222.8392 109.4986)
		(end 222.8392 107.3338)
		(width 0.2032)
		(layer "B.Cu")
		(net "DIP_SW_MACSER_SEL")
	)
	(segment
		(start 153.14472 119.3844)
		(end 153.14472 117.64806)
		(width 0.2032)
		(layer "B.Cu")
		(net "DIP_SW_MACSER_SEL")
	)
	(segment
		(start 221.2216 111.1162)
		(end 222.8392 109.4986)
		(width 0.2032)
		(layer "B.Cu")
		(net "DIP_SW_MACSER_SEL")
	)
	(segment
		(start 152.0966 115.9412)
		(end 153.8216 114.2162)
		(width 0.2032)
		(layer "B.Cu")
		(net "DIP_SW_MACSER_SEL")
	)
	(segment
		(start 202.5216 105.7162)
		(end 204.46661 105.7162)
		(width 0.2032)
		(layer "B.Cu")
		(net "DIP_SW_MACSER_SEL")
	)
	(segment
		(start 221.1966 105.6912)
		(end 221.1966 105.1162)
		(width 0.2032)
		(layer "B.Cu")
		(net "DIP_SW_MACSER_SEL")
	)
	(segment
		(start 153.14472 117.64806)
		(end 153.3216 117.47119)
		(width 0.2032)
		(layer "B.Cu")
		(net "DIP_SW_MACSER_SEL")
	)
	(segment
		(start 204.46661 105.7162)
		(end 204.56661 105.6162)
		(width 0.2032)
		(layer "In2.Cu")
		(net "DIP_SW_MACSER_SEL")
	)
	(segment
		(start 204.56661 105.6162)
		(end 204.6216 105.6162)
		(width 0.2032)
		(layer "In2.Cu")
		(net "DIP_SW_MACSER_SEL")
	)
	(segment
		(start 171.2966 112.7912)
		(end 171.345 112.7428)
		(width 0.2032)
		(layer "F.Cu")
		(net "DC_I2C_SDA")
	)
	(segment
		(start 174.8289 112.0839)
		(end 174.86275 112.05005)
		(width 0.2032)
		(layer "F.Cu")
		(net "DC_I2C_SDA")
	)
	(segment
		(start 171.345 112.7428)
		(end 171.345 112.31183)
		(width 0.2032)
		(layer "F.Cu")
		(net "DC_I2C_SDA")
	)
	(segment
		(start 174.86275 112.05005)
		(end 174.8966 112.0162)
		(width 0.2032)
		(layer "F.Cu")
		(net "DC_I2C_SDA")
	)
	(segment
		(start 171.57293 112.0839)
		(end 174.8289 112.0839)
		(width 0.2032)
		(layer "F.Cu")
		(net "DC_I2C_SDA")
	)
	(segment
		(start 171.345 112.31183)
		(end 171.57293 112.0839)
		(width 0.2032)
		(layer "F.Cu")
		(net "DC_I2C_SDA")
	)
	(segment
		(start 171.57293 112.0839)
		(end 171.57293 112.0839)
		(width 0.2032)
		(layer "F.Cu")
		(net "DC_I2C_SDA")
	)
	(via
		(at 174.86275 112.05005)
		(size 0.4064)
		(drill 0.254)
		(layers "F.Cu" "B.Cu")
		(net "DC_I2C_SDA")
	)
	(segment
		(start 165.4216 102.44892)
		(end 165.4216 100.9162)
		(width 0.2032)
		(layer "In2.Cu")
		(net "DC_I2C_SDA")
	)
	(segment
		(start 153.7216 87.0362)
		(end 156.4216 89.7362)
		(width 0.2032)
		(layer "In2.Cu")
		(net "DC_I2C_SDA")
	)
	(segment
		(start 171.6983 112.05005)
		(end 174.86275 112.05005)
		(width 0.2032)
		(layer "In2.Cu")
		(net "DC_I2C_SDA")
	)
	(segment
		(start 166.25826 102.65671)
		(end 168.228 104.62645)
		(width 0.2032)
		(layer "In2.Cu")
		(net "DC_I2C_SDA")
	)
	(segment
		(start 165.62938 102.65671)
		(end 166.25826 102.65671)
		(width 0.2032)
		(layer "In2.Cu")
		(net "DC_I2C_SDA")
	)
	(segment
		(start 156.4216 91.9162)
		(end 165.4216 100.9162)
		(width 0.2032)
		(layer "In2.Cu")
		(net "DC_I2C_SDA")
	)
	(segment
		(start 156.4216 91.9162)
		(end 156.4216 89.7362)
		(width 0.2032)
		(layer "In2.Cu")
		(net "DC_I2C_SDA")
	)
	(segment
		(start 168.228 108.57975)
		(end 171.6983 112.05005)
		(width 0.2032)
		(layer "In2.Cu")
		(net "DC_I2C_SDA")
	)
	(segment
		(start 165.4216 102.44892)
		(end 165.62938 102.65671)
		(width 0.2032)
		(layer "In2.Cu")
		(net "DC_I2C_SDA")
	)
	(segment
		(start 168.228 108.57975)
		(end 168.228 104.62645)
		(width 0.2032)
		(layer "In2.Cu")
		(net "DC_I2C_SDA")
	)
	(segment
		(start 174.23226 110.9162)
		(end 174.8966 110.9162)
		(width 0.2032)
		(layer "F.Cu")
		(net "DC_I2C_SCL")
	)
	(segment
		(start 171.0841 111.7537)
		(end 173.39476 111.7537)
		(width 0.2032)
		(layer "F.Cu")
		(net "DC_I2C_SCL")
	)
	(segment
		(start 170.6466 112.1912)
		(end 171.0841 111.7537)
		(width 0.2032)
		(layer "F.Cu")
		(net "DC_I2C_SCL")
	)
	(segment
		(start 174.8966 110.9162)
		(end 174.8966 110.9162)
		(width 0.2032)
		(layer "F.Cu")
		(net "DC_I2C_SCL")
	)
	(segment
		(start 170.6466 112.7912)
		(end 170.6466 112.1912)
		(width 0.2032)
		(layer "F.Cu")
		(net "DC_I2C_SCL")
	)
	(segment
		(start 173.39476 111.7537)
		(end 174.23226 110.9162)
		(width 0.2032)
		(layer "F.Cu")
		(net "DC_I2C_SCL")
	)
	(via
		(at 174.8966 110.9162)
		(size 0.4064)
		(drill 0.254)
		(layers "F.Cu" "B.Cu")
		(net "DC_I2C_SCL")
	)
	(segment
		(start 174.83226 112.6912)
		(end 175.38839 112.13507)
		(width 0.2032)
		(layer "In2.Cu")
		(net "DC_I2C_SCL")
	)
	(segment
		(start 159.63226 95.7162)
		(end 165.04903 101.13297)
		(width 0.2032)
		(layer "In2.Cu")
		(net "DC_I2C_SCL")
	)
	(segment
		(start 158.82024 95.7162)
		(end 159.63226 95.7162)
		(width 0.2032)
		(layer "In2.Cu")
		(net "DC_I2C_SCL")
	)
	(segment
		(start 165.04903 103.74363)
		(end 167.6693 106.3639)
		(width 0.2032)
		(layer "In2.Cu")
		(net "DC_I2C_SCL")
	)
	(segment
		(start 167.6693 108.7389)
		(end 167.6693 106.3639)
		(width 0.2032)
		(layer "In2.Cu")
		(net "DC_I2C_SCL")
	)
	(segment
		(start 165.04903 103.74363)
		(end 165.04903 101.13297)
		(width 0.2032)
		(layer "In2.Cu")
		(net "DC_I2C_SCL")
	)
	(segment
		(start 167.6693 108.7389)
		(end 171.6216 112.6912)
		(width 0.2032)
		(layer "In2.Cu")
		(net "DC_I2C_SCL")
	)
	(segment
		(start 155.3216 92.21756)
		(end 158.82024 95.7162)
		(width 0.2032)
		(layer "In2.Cu")
		(net "DC_I2C_SCL")
	)
	(segment
		(start 153.7216 89.5762)
		(end 155.3216 91.1762)
		(width 0.2032)
		(layer "In2.Cu")
		(net "DC_I2C_SCL")
	)
	(segment
		(start 171.6216 112.6912)
		(end 174.83226 112.6912)
		(width 0.2032)
		(layer "In2.Cu")
		(net "DC_I2C_SCL")
	)
	(segment
		(start 174.8966 110.9162)
		(end 175.38839 111.40799)
		(width 0.2032)
		(layer "In2.Cu")
		(net "DC_I2C_SCL")
	)
	(segment
		(start 175.38839 112.13507)
		(end 175.38839 111.40799)
		(width 0.2032)
		(layer "In2.Cu")
		(net "DC_I2C_SCL")
	)
	(segment
		(start 155.3216 92.21756)
		(end 155.3216 91.1762)
		(width 0.2032)
		(layer "In2.Cu")
		(net "DC_I2C_SCL")
	)
	(segment
		(start 115.14322 85.5162)
		(end 115.19122 85.4682)
		(width 0.254)
		(layer "F.Cu")
		(net "BNO_P3V3")
	)
	(segment
		(start 111.0216 80.43764)
		(end 111.22405 80.64009)
		(width 0.254)
		(layer "F.Cu")
		(net "BNO_P3V3")
	)
	(segment
		(start 112.5556 80.51363)
		(end 112.6066 80.51363)
		(width 0.254)
		(layer "F.Cu")
		(net "BNO_P3V3")
	)
	(segment
		(start 115.5696 85.4682)
		(end 116.1216 84.9162)
		(width 0.254)
		(layer "F.Cu")
		(net "BNO_P3V3")
	)
	(segment
		(start 115.19122 85.4682)
		(end 115.5696 85.4682)
		(width 0.254)
		(layer "F.Cu")
		(net "BNO_P3V3")
	)
	(segment
		(start 112.01238 80.91363)
		(end 112.6066 80.91363)
		(width 0.254)
		(layer "F.Cu")
		(net "BNO_P3V3")
	)
	(segment
		(start 111.0216 80.4162)
		(end 111.23084 80.20696)
		(width 0.254)
		(layer "F.Cu")
		(net "BNO_P3V3")
	)
	(segment
		(start 111.25228 80.20696)
		(end 111.37928 80.07996)
		(width 0.254)
		(layer "F.Cu")
		(net "BNO_P3V3")
	)
	(segment
		(start 111.23084 80.20696)
		(end 111.25228 80.20696)
		(width 0.254)
		(layer "F.Cu")
		(net "BNO_P3V3")
	)
	(segment
		(start 112.12194 80.07996)
		(end 112.5556 80.51363)
		(width 0.254)
		(layer "F.Cu")
		(net "BNO_P3V3")
	)
	(segment
		(start 110.81236 80.2162)
		(end 111.0216 80.42544)
		(width 0.254)
		(layer "F.Cu")
		(net "BNO_P3V3")
	)
	(segment
		(start 111.0216 80.43764)
		(end 111.0216 80.42544)
		(width 0.254)
		(layer "F.Cu")
		(net "BNO_P3V3")
	)
	(segment
		(start 109.8216 80.2162)
		(end 110.81236 80.2162)
		(width 0.254)
		(layer "F.Cu")
		(net "BNO_P3V3")
	)
	(segment
		(start 111.37928 80.07996)
		(end 112.12194 80.07996)
		(width 0.254)
		(layer "F.Cu")
		(net "BNO_P3V3")
	)
	(segment
		(start 113.83072 84.9537)
		(end 113.83072 84.28443)
		(width 0.254)
		(layer "F.Cu")
		(net "BNO_P3V3")
	)
	(segment
		(start 111.73884 80.64009)
		(end 112.01238 80.91363)
		(width 0.254)
		(layer "F.Cu")
		(net "BNO_P3V3")
	)
	(segment
		(start 111.0216 80.42544)
		(end 111.0216 80.4162)
		(width 0.254)
		(layer "F.Cu")
		(net "BNO_P3V3")
	)
	(segment
		(start 111.22405 80.64009)
		(end 111.73884 80.64009)
		(width 0.254)
		(layer "F.Cu")
		(net "BNO_P3V3")
	)
	(via
		(at 111.0216 83.9162)
		(size 0.4064)
		(drill 0.2032)
		(layers "F.Cu" "B.Cu")
		(net "BNO_P3V3")
	)
	(via
		(at 116.1216 84.9162)
		(size 0.4064)
		(drill 0.2032)
		(layers "F.Cu" "B.Cu")
		(net "BNO_P3V3")
	)
	(via
		(at 113.99168 84.08224)
		(size 0.4064)
		(drill 0.2032)
		(layers "F.Cu" "B.Cu")
		(net "BNO_P3V3")
	)
	(via
		(at 111.0216 80.43764)
		(size 0.4064)
		(drill 0.2032)
		(layers "F.Cu" "B.Cu")
		(net "BNO_P3V3")
	)
	(segment
		(start 115.71536 85.2812)
		(end 116.04815 84.94841)
		(width 0.254)
		(layer "B.Cu")
		(net "BNO_P3V3")
	)
	(segment
		(start 111.23084 80.69229)
		(end 111.59766 80.69229)
		(width 0.254)
		(layer "B.Cu")
		(net "BNO_P3V3")
	)
	(segment
		(start 111.78453 80.87916)
		(end 112.4216 80.87916)
		(width 0.254)
		(layer "B.Cu")
		(net "BNO_P3V3")
	)
	(segment
		(start 114.08272 89.6682)
		(end 114.18073 89.7662)
		(width 0.254)
		(layer "B.Cu")
		(net "BNO_P3V3")
	)
	(segment
		(start 114.90572 85.2812)
		(end 114.90572 85.2612)
		(width 0.254)
		(layer "B.Cu")
		(net "BNO_P3V3")
	)
	(segment
		(start 114.90572 85.3012)
		(end 114.90572 85.2812)
		(width 0.254)
		(layer "B.Cu")
		(net "BNO_P3V3")
	)
	(segment
		(start 111.0216 80.48305)
		(end 111.23084 80.69229)
		(width 0.254)
		(layer "B.Cu")
		(net "BNO_P3V3")
	)
	(segment
		(start 112.65572 88.6912)
		(end 113.55572 88.6912)
		(width 0.254)
		(layer "B.Cu")
		(net "BNO_P3V3")
	)
	(segment
		(start 110.65969 82.25183)
		(end 111.67333 82.25183)
		(width 0.254)
		(layer "B.Cu")
		(net "BNO_P3V3")
	)
	(segment
		(start 114.90572 85.2812)
		(end 115.71536 85.2812)
		(width 0.254)
		(layer "B.Cu")
		(net "BNO_P3V3")
	)
	(segment
		(start 114.18073 89.7662)
		(end 114.78072 90.3662)
		(width 0.254)
		(layer "B.Cu")
		(net "BNO_P3V3")
	)
	(segment
		(start 109.2216 90.4162)
		(end 110.2216 91.4162)
		(width 0.254)
		(layer "B.Cu")
		(net "BNO_P3V3")
	)
	(segment
		(start 109.2216 90.4162)
		(end 109.2216 85.1162)
		(width 0.254)
		(layer "B.Cu")
		(net "BNO_P3V3")
	)
	(segment
		(start 114.33072 91.4162)
		(end 114.78072 90.9662)
		(width 0.254)
		(layer "B.Cu")
		(net "BNO_P3V3")
	)
	(segment
		(start 110.2216 91.4162)
		(end 114.33072 91.4162)
		(width 0.254)
		(layer "B.Cu")
		(net "BNO_P3V3")
	)
	(segment
		(start 114.55351 85.0682)
		(end 114.71272 85.0682)
		(width 0.254)
		(layer "B.Cu")
		(net "BNO_P3V3")
	)
	(segment
		(start 110.0216 82.88992)
		(end 110.65969 82.25183)
		(width 0.254)
		(layer "B.Cu")
		(net "BNO_P3V3")
	)
	(segment
		(start 113.96707 84.98575)
		(end 113.9739 84.97892)
		(width 0.254)
		(layer "B.Cu")
		(net "BNO_P3V3")
	)
	(segment
		(start 116.04815 85.80239)
		(end 116.04815 84.94841)
		(width 0.254)
		(layer "B.Cu")
		(net "BNO_P3V3")
	)
	(segment
		(start 111.67333 82.25183)
		(end 112.4216 81.50356)
		(width 0.254)
		(layer "B.Cu")
		(net "BNO_P3V3")
	)
	(segment
		(start 113.9739 84.11303)
		(end 113.98072 84.1062)
		(width 0.254)
		(layer "B.Cu")
		(net "BNO_P3V3")
	)
	(segment
		(start 111.59766 80.69229)
		(end 111.78453 80.87916)
		(width 0.254)
		(layer "B.Cu")
		(net "BNO_P3V3")
	)
	(segment
		(start 114.24073 85.9662)
		(end 114.90572 85.3012)
		(width 0.254)
		(layer "B.Cu")
		(net "BNO_P3V3")
	)
	(segment
		(start 116.04815 84.9162)
		(end 116.1216 84.9162)
		(width 0.254)
		(layer "B.Cu")
		(net "BNO_P3V3")
	)
	(segment
		(start 113.9739 84.97892)
		(end 113.9739 84.11303)
		(width 0.254)
		(layer "B.Cu")
		(net "BNO_P3V3")
	)
	(segment
		(start 113.96707 84.98575)
		(end 114.47105 84.98575)
		(width 0.254)
		(layer "B.Cu")
		(net "BNO_P3V3")
	)
	(segment
		(start 111.0216 83.9162)
		(end 111.5466 84.4412)
		(width 0.254)
		(layer "B.Cu")
		(net "BNO_P3V3")
	)
	(segment
		(start 110.0216 84.3162)
		(end 110.0216 82.88992)
		(width 0.254)
		(layer "B.Cu")
		(net "BNO_P3V3")
	)
	(segment
		(start 116.04815 84.94841)
		(end 116.04815 84.9162)
		(width 0.254)
		(layer "B.Cu")
		(net "BNO_P3V3")
	)
	(segment
		(start 114.47105 84.98575)
		(end 114.55351 85.0682)
		(width 0.254)
		(layer "B.Cu")
		(net "BNO_P3V3")
	)
	(segment
		(start 113.78072 89.0722)
		(end 113.78072 88.4662)
		(width 0.254)
		(layer "B.Cu")
		(net "BNO_P3V3")
	)
	(segment
		(start 111.5466 84.4412)
		(end 112.25573 84.4412)
		(width 0.254)
		(layer "B.Cu")
		(net "BNO_P3V3")
	)
	(segment
		(start 114.08272 89.6682)
		(end 114.08272 89.3742)
		(width 0.254)
		(layer "B.Cu")
		(net "BNO_P3V3")
	)
	(segment
		(start 109.2216 85.1162)
		(end 110.0216 84.3162)
		(width 0.254)
		(layer "B.Cu")
		(net "BNO_P3V3")
	)
	(segment
		(start 114.71272 85.0682)
		(end 114.90572 85.2612)
		(width 0.254)
		(layer "B.Cu")
		(net "BNO_P3V3")
	)
	(segment
		(start 113.55572 88.6912)
		(end 113.78072 88.4662)
		(width 0.254)
		(layer "B.Cu")
		(net "BNO_P3V3")
	)
	(segment
		(start 114.78072 90.9662)
		(end 114.78072 90.3662)
		(width 0.254)
		(layer "B.Cu")
		(net "BNO_P3V3")
	)
	(segment
		(start 113.78072 89.0722)
		(end 114.08272 89.3742)
		(width 0.254)
		(layer "B.Cu")
		(net "BNO_P3V3")
	)
	(segment
		(start 112.98072 85.9662)
		(end 114.24073 85.9662)
		(width 0.254)
		(layer "B.Cu")
		(net "BNO_P3V3")
	)
	(segment
		(start 112.4216 81.50356)
		(end 112.4216 80.87916)
		(width 0.254)
		(layer "B.Cu")
		(net "BNO_P3V3")
	)
	(segment
		(start 112.12007 84.1234)
		(end 113.90928 84.1234)
		(width 0.254)
		(layer "In3.Cu")
		(net "BNO_P3V3")
	)
	(segment
		(start 113.95044 84.08224)
		(end 113.99168 84.08224)
		(width 0.254)
		(layer "In3.Cu")
		(net "BNO_P3V3")
	)
	(segment
		(start 113.99168 84.08224)
		(end 113.99168 82.6397)
		(width 0.254)
		(layer "In3.Cu")
		(net "BNO_P3V3")
	)
	(segment
		(start 111.92007 83.9234)
		(end 112.12007 84.1234)
		(width 0.254)
		(layer "In3.Cu")
		(net "BNO_P3V3")
	)
	(segment
		(start 111.0216 80.43764)
		(end 112.50016 81.9162)
		(width 0.254)
		(layer "In3.Cu")
		(net "BNO_P3V3")
	)
	(segment
		(start 113.90928 84.1234)
		(end 113.95044 84.08224)
		(width 0.254)
		(layer "In3.Cu")
		(net "BNO_P3V3")
	)
	(segment
		(start 113.26818 81.9162)
		(end 113.99168 82.6397)
		(width 0.254)
		(layer "In3.Cu")
		(net "BNO_P3V3")
	)
	(segment
		(start 111.0288 83.9234)
		(end 111.92007 83.9234)
		(width 0.254)
		(layer "In3.Cu")
		(net "BNO_P3V3")
	)
	(segment
		(start 112.50016 81.9162)
		(end 113.26818 81.9162)
		(width 0.254)
		(layer "In3.Cu")
		(net "BNO_P3V3")
	)
	(segment
		(start 111.0216 83.9162)
		(end 111.0288 83.9234)
		(width 0.254)
		(layer "In3.Cu")
		(net "BNO_P3V3")
	)
	(segment
		(start 175.1216 115.6162)
		(end 175.32 115.8146)
		(width 0.2032)
		(layer "F.Cu")
		(net "ANADC_I2C_SDA")
	)
	(segment
		(start 175.07785 115.63495)
		(end 175.0966 115.6162)
		(width 0.2032)
		(layer "F.Cu")
		(net "ANADC_I2C_SDA")
	)
	(segment
		(start 151.84139 108.3162)
		(end 154.4216 108.3162)
		(width 0.2032)
		(layer "F.Cu")
		(net "ANADC_I2C_SDA")
	)
	(segment
		(start 175.32 115.93789)
		(end 176.6647 117.28259)
		(width 0.2032)
		(layer "F.Cu")
		(net "ANADC_I2C_SDA")
	)
	(segment
		(start 166.3216 120.2162)
		(end 175.05463 120.2162)
		(width 0.2032)
		(layer "F.Cu")
		(net "ANADC_I2C_SDA")
	)
	(segment
		(start 147.8216 86.9962)
		(end 151.4016 83.4162)
		(width 0.2032)
		(layer "F.Cu")
		(net "ANADC_I2C_SDA")
	)
	(segment
		(start 174.2591 114.80371)
		(end 174.2591 114.2537)
		(width 0.2032)
		(layer "F.Cu")
		(net "ANADC_I2C_SDA")
	)
	(segment
		(start 172.1466 114.2912)
		(end 172.1841 114.2537)
		(width 0.2032)
		(layer "F.Cu")
		(net "ANADC_I2C_SDA")
	)
	(segment
		(start 175.32 115.93789)
		(end 175.32 115.8146)
		(width 0.2032)
		(layer "F.Cu")
		(net "ANADC_I2C_SDA")
	)
	(segment
		(start 176.87237 117.28259)
		(end 176.9914 117.40162)
		(width 0.2032)
		(layer "F.Cu")
		(net "ANADC_I2C_SDA")
	)
	(segment
		(start 176.6647 117.28259)
		(end 176.87237 117.28259)
		(width 0.2032)
		(layer "F.Cu")
		(net "ANADC_I2C_SDA")
	)
	(segment
		(start 151.24139 108.9162)
		(end 151.84139 108.3162)
		(width 0.2032)
		(layer "F.Cu")
		(net "ANADC_I2C_SDA")
	)
	(segment
		(start 176.9914 118.27943)
		(end 176.9914 117.40162)
		(width 0.2032)
		(layer "F.Cu")
		(net "ANADC_I2C_SDA")
	)
	(segment
		(start 150.7216 108.9162)
		(end 151.24139 108.9162)
		(width 0.2032)
		(layer "F.Cu")
		(net "ANADC_I2C_SDA")
	)
	(segment
		(start 152.8216 83.4162)
		(end 153.7216 84.3162)
		(width 0.2032)
		(layer "F.Cu")
		(net "ANADC_I2C_SDA")
	)
	(segment
		(start 175.0966 115.6162)
		(end 175.1216 115.6162)
		(width 0.2032)
		(layer "F.Cu")
		(net "ANADC_I2C_SDA")
	)
	(segment
		(start 172.1841 114.2537)
		(end 174.2591 114.2537)
		(width 0.2032)
		(layer "F.Cu")
		(net "ANADC_I2C_SDA")
	)
	(segment
		(start 175.07785 115.63495)
		(end 175.07785 115.62245)
		(width 0.2032)
		(layer "F.Cu")
		(net "ANADC_I2C_SDA")
	)
	(segment
		(start 174.2591 114.80371)
		(end 175.07785 115.62245)
		(width 0.2032)
		(layer "F.Cu")
		(net "ANADC_I2C_SDA")
	)
	(segment
		(start 154.4216 108.3162)
		(end 166.3216 120.2162)
		(width 0.2032)
		(layer "F.Cu")
		(net "ANADC_I2C_SDA")
	)
	(segment
		(start 175.05463 120.2162)
		(end 176.9914 118.27943)
		(width 0.2032)
		(layer "F.Cu")
		(net "ANADC_I2C_SDA")
	)
	(segment
		(start 151.4016 83.4162)
		(end 152.8216 83.4162)
		(width 0.2032)
		(layer "F.Cu")
		(net "ANADC_I2C_SDA")
	)
	(via
		(at 153.7216 84.3162)
		(size 0.4064)
		(drill 0.2032)
		(layers "F.Cu" "B.Cu")
		(net "ANADC_I2C_SDA")
	)
	(via
		(at 150.7216 108.9162)
		(size 0.4064)
		(drill 0.2032)
		(layers "F.Cu" "B.Cu")
		(net "ANADC_I2C_SDA")
	)
	(segment
		(start 155.47077 85.3162)
		(end 155.5898 85.43523)
		(width 0.2032)
		(layer "B.Cu")
		(net "ANADC_I2C_SDA")
	)
	(segment
		(start 154.14789 99.98157)
		(end 154.92408 99.20538)
		(width 0.2032)
		(layer "B.Cu")
		(net "ANADC_I2C_SDA")
	)
	(segment
		(start 155.2216 107.86414)
		(end 155.2216 103.83866)
		(width 0.2032)
		(layer "B.Cu")
		(net "ANADC_I2C_SDA")
	)
	(segment
		(start 153.7216 84.3162)
		(end 154.7216 85.3162)
		(width 0.2032)
		(layer "B.Cu")
		(net "ANADC_I2C_SDA")
	)
	(segment
		(start 150.7216 108.9162)
		(end 151.3534 109.548)
		(width 0.2032)
		(layer "B.Cu")
		(net "ANADC_I2C_SDA")
	)
	(segment
		(start 159.9216 98.27156)
		(end 159.9216 98.09671)
		(width 0.2032)
		(layer "B.Cu")
		(net "ANADC_I2C_SDA")
	)
	(segment
		(start 154.14789 102.76495)
		(end 155.2216 103.83866)
		(width 0.2032)
		(layer "B.Cu")
		(net "ANADC_I2C_SDA")
	)
	(segment
		(start 153.53774 109.548)
		(end 155.2216 107.86414)
		(width 0.2032)
		(layer "B.Cu")
		(net "ANADC_I2C_SDA")
	)
	(segment
		(start 157.5216 93.5162)
		(end 159.95685 95.95145)
		(width 0.2032)
		(layer "B.Cu")
		(net "ANADC_I2C_SDA")
	)
	(segment
		(start 157.5216 93.5162)
		(end 157.5216 88.5555)
		(width 0.2032)
		(layer "B.Cu")
		(net "ANADC_I2C_SDA")
	)
	(segment
		(start 155.5898 86.6237)
		(end 157.5216 88.5555)
		(width 0.2032)
		(layer "B.Cu")
		(net "ANADC_I2C_SDA")
	)
	(segment
		(start 154.7216 85.3162)
		(end 155.47077 85.3162)
		(width 0.2032)
		(layer "B.Cu")
		(net "ANADC_I2C_SDA")
	)
	(segment
		(start 151.3534 109.548)
		(end 153.53774 109.548)
		(width 0.2032)
		(layer "B.Cu")
		(net "ANADC_I2C_SDA")
	)
	(segment
		(start 155.5898 86.6237)
		(end 155.5898 85.43523)
		(width 0.2032)
		(layer "B.Cu")
		(net "ANADC_I2C_SDA")
	)
	(segment
		(start 158.98779 99.20538)
		(end 159.9216 98.27156)
		(width 0.2032)
		(layer "B.Cu")
		(net "ANADC_I2C_SDA")
	)
	(segment
		(start 159.95685 98.06146)
		(end 159.95685 95.95145)
		(width 0.2032)
		(layer "B.Cu")
		(net "ANADC_I2C_SDA")
	)
	(segment
		(start 154.92408 99.20538)
		(end 158.98779 99.20538)
		(width 0.2032)
		(layer "B.Cu")
		(net "ANADC_I2C_SDA")
	)
	(segment
		(start 154.14789 102.76495)
		(end 154.14789 99.98157)
		(width 0.2032)
		(layer "B.Cu")
		(net "ANADC_I2C_SDA")
	)
	(segment
		(start 159.9216 98.09671)
		(end 159.95685 98.06146)
		(width 0.2032)
		(layer "B.Cu")
		(net "ANADC_I2C_SDA")
	)
	(segment
		(start 177.3216 118.4162)
		(end 177.3216 113.53523)
		(width 0.2032)
		(layer "F.Cu")
		(net "ANADC_I2C_SCL")
	)
	(segment
		(start 175.42 113.8178)
		(end 175.8216 113.4162)
		(width 0.2032)
		(layer "F.Cu")
		(net "ANADC_I2C_SCL")
	)
	(segment
		(start 152.05448 108.78332)
		(end 153.98872 108.78332)
		(width 0.2032)
		(layer "F.Cu")
		(net "ANADC_I2C_SCL")
	)
	(segment
		(start 177.20257 113.4162)
		(end 177.3216 113.53523)
		(width 0.2032)
		(layer "F.Cu")
		(net "ANADC_I2C_SCL")
	)
	(segment
		(start 175.1716 114.3162)
		(end 175.1966 114.3162)
		(width 0.2032)
		(layer "F.Cu")
		(net "ANADC_I2C_SCL")
	)
	(segment
		(start 175.2216 114.3162)
		(end 175.42 114.1178)
		(width 0.2032)
		(layer "F.Cu")
		(net "ANADC_I2C_SCL")
	)
	(segment
		(start 165.7716 120.5662)
		(end 175.1716 120.5662)
		(width 0.2032)
		(layer "F.Cu")
		(net "ANADC_I2C_SCL")
	)
	(segment
		(start 153.98872 108.78332)
		(end 165.7716 120.5662)
		(width 0.2032)
		(layer "F.Cu")
		(net "ANADC_I2C_SCL")
	)
	(segment
		(start 175.8216 113.4162)
		(end 177.20257 113.4162)
		(width 0.2032)
		(layer "F.Cu")
		(net "ANADC_I2C_SCL")
	)
	(segment
		(start 174.4966 113.6412)
		(end 175.1716 114.3162)
		(width 0.2032)
		(layer "F.Cu")
		(net "ANADC_I2C_SCL")
	)
	(segment
		(start 151.7216 109.1162)
		(end 152.05448 108.78332)
		(width 0.2032)
		(layer "F.Cu")
		(net "ANADC_I2C_SCL")
	)
	(segment
		(start 175.1966 114.3162)
		(end 175.2216 114.3162)
		(width 0.2032)
		(layer "F.Cu")
		(net "ANADC_I2C_SCL")
	)
	(segment
		(start 175.42 114.1178)
		(end 175.42 113.8178)
		(width 0.2032)
		(layer "F.Cu")
		(net "ANADC_I2C_SCL")
	)
	(segment
		(start 175.1716 120.5662)
		(end 177.3216 118.4162)
		(width 0.2032)
		(layer "F.Cu")
		(net "ANADC_I2C_SCL")
	)
	(segment
		(start 152.7216 84.37119)
		(end 152.7216 84.3162)
		(width 0.2032)
		(layer "F.Cu")
		(net "ANADC_I2C_SCL")
	)
	(segment
		(start 147.8216 89.5362)
		(end 147.8216 89.27118)
		(width 0.2032)
		(layer "F.Cu")
		(net "ANADC_I2C_SCL")
	)
	(segment
		(start 147.8216 89.27118)
		(end 152.7216 84.37119)
		(width 0.2032)
		(layer "F.Cu")
		(net "ANADC_I2C_SCL")
	)
	(segment
		(start 172.1466 113.6412)
		(end 174.4966 113.6412)
		(width 0.2032)
		(layer "F.Cu")
		(net "ANADC_I2C_SCL")
	)
	(via
		(at 151.7216 109.1162)
		(size 0.4064)
		(drill 0.2032)
		(layers "F.Cu" "B.Cu")
		(net "ANADC_I2C_SCL")
	)
	(via
		(at 152.7216 84.3162)
		(size 0.4064)
		(drill 0.2032)
		(layers "F.Cu" "B.Cu")
		(net "ANADC_I2C_SCL")
	)
	(segment
		(start 159.61026 97.72092)
		(end 159.62665 97.70453)
		(width 0.2032)
		(layer "B.Cu")
		(net "ANADC_I2C_SCL")
	)
	(segment
		(start 159.61026 97.94108)
		(end 159.61026 97.72092)
		(width 0.2032)
		(layer "B.Cu")
		(net "ANADC_I2C_SCL")
	)
	(segment
		(start 152.7216 108.1162)
		(end 154.50257 108.1162)
		(width 0.2032)
		(layer "B.Cu")
		(net "ANADC_I2C_SCL")
	)
	(segment
		(start 154.1216 85.7162)
		(end 155.10257 85.7162)
		(width 0.2032)
		(layer "B.Cu")
		(net "ANADC_I2C_SCL")
	)
	(segment
		(start 153.08988 103.24758)
		(end 153.08988 100.43302)
		(width 0.2032)
		(layer "B.Cu")
		(net "ANADC_I2C_SCL")
	)
	(segment
		(start 155.2216 86.8162)
		(end 155.2216 85.83523)
		(width 0.2032)
		(layer "B.Cu")
		(net "ANADC_I2C_SCL")
	)
	(segment
		(start 151.7216 109.1162)
		(end 152.7216 108.1162)
		(width 0.2032)
		(layer "B.Cu")
		(net "ANADC_I2C_SCL")
	)
	(segment
		(start 153.08988 103.24758)
		(end 154.6216 104.7793)
		(width 0.2032)
		(layer "B.Cu")
		(net "ANADC_I2C_SCL")
	)
	(segment
		(start 154.75119 98.77171)
		(end 158.77963 98.77171)
		(width 0.2032)
		(layer "B.Cu")
		(net "ANADC_I2C_SCL")
	)
	(segment
		(start 155.2216 86.8162)
		(end 157.0216 88.6162)
		(width 0.2032)
		(layer "B.Cu")
		(net "ANADC_I2C_SCL")
	)
	(segment
		(start 157.0216 93.5326)
		(end 159.62665 96.13765)
		(width 0.2032)
		(layer "B.Cu")
		(net "ANADC_I2C_SCL")
	)
	(segment
		(start 155.10257 85.7162)
		(end 155.2216 85.83523)
		(width 0.2032)
		(layer "B.Cu")
		(net "ANADC_I2C_SCL")
	)
	(segment
		(start 152.7216 84.3162)
		(end 154.1216 85.7162)
		(width 0.2032)
		(layer "B.Cu")
		(net "ANADC_I2C_SCL")
	)
	(segment
		(start 153.08988 100.43302)
		(end 154.75119 98.77171)
		(width 0.2032)
		(layer "B.Cu")
		(net "ANADC_I2C_SCL")
	)
	(segment
		(start 159.62665 97.70453)
		(end 159.62665 96.13765)
		(width 0.2032)
		(layer "B.Cu")
		(net "ANADC_I2C_SCL")
	)
	(segment
		(start 158.77963 98.77171)
		(end 159.61026 97.94108)
		(width 0.2032)
		(layer "B.Cu")
		(net "ANADC_I2C_SCL")
	)
	(segment
		(start 154.6216 107.99717)
		(end 154.6216 104.7793)
		(width 0.2032)
		(layer "B.Cu")
		(net "ANADC_I2C_SCL")
	)
	(segment
		(start 154.50257 108.1162)
		(end 154.6216 107.99717)
		(width 0.2032)
		(layer "B.Cu")
		(net "ANADC_I2C_SCL")
	)
	(segment
		(start 157.0216 93.5326)
		(end 157.0216 88.6162)
		(width 0.2032)
		(layer "B.Cu")
		(net "ANADC_I2C_SCL")
	)
	(segment
		(start 85.05686 84.46371)
		(end 85.05686 83.46371)
		(width 0.2032)
		(layer "F.Cu")
		(net "NetR108_2")
	)
	(segment
		(start 89.85686 85.56371)
		(end 89.85686 83.46371)
		(width 0.2032)
		(layer "F.Cu")
		(net "NetR108_2")
	)
	(segment
		(start 89.85686 85.56371)
		(end 91.38187 85.56371)
		(width 0.2032)
		(layer "F.Cu")
		(net "NetR108_2")
	)
	(segment
		(start 85.05686 83.46371)
		(end 85.05687 83.46371)
		(width 0.2032)
		(layer "F.Cu")
		(net "NetR108_2")
	)
	(segment
		(start 85.05687 83.46371)
		(end 89.85686 83.46371)
		(width 0.2032)
		(layer "F.Cu")
		(net "NetR108_2")
	)
	(segment
		(start 85.05687 81.46371)
		(end 88.60686 81.46371)
		(width 0.254)
		(layer "F.Cu")
		(net "NetR40_2")
	)
	(segment
		(start 90.35686 85.06371)
		(end 90.35686 82.56371)
		(width 0.254)
		(layer "F.Cu")
		(net "NetR40_2")
	)
	(segment
		(start 88.60686 82.56371)
		(end 90.35686 82.56371)
		(width 0.254)
		(layer "F.Cu")
		(net "NetR40_2")
	)
	(segment
		(start 90.35686 85.06371)
		(end 91.38187 85.06371)
		(width 0.254)
		(layer "F.Cu")
		(net "NetR40_2")
	)
	(segment
		(start 88.60686 82.56371)
		(end 88.60686 81.46371)
		(width 0.254)
		(layer "F.Cu")
		(net "NetR40_2")
	)
	(segment
		(start 85.05687 82.56371)
		(end 85.05687 81.46371)
		(width 0.254)
		(layer "F.Cu")
		(net "NetR40_2")
	)
	(segment
		(start 224.5216 131.14012)
		(end 224.5216 129.3162)
		(width 0.254)
		(layer "F.Cu")
		(net "USB_VBUS")
	)
	(segment
		(start 224.5216 128.5162)
		(end 225.4966 127.5412)
		(width 0.254)
		(layer "F.Cu")
		(net "USB_VBUS")
	)
	(segment
		(start 224.34552 131.3162)
		(end 224.5216 131.14012)
		(width 0.254)
		(layer "F.Cu")
		(net "USB_VBUS")
	)
	(segment
		(start 224.5216 129.3162)
		(end 224.5216 128.5162)
		(width 0.254)
		(layer "F.Cu")
		(net "USB_VBUS")
	)
	(segment
		(start 225.4966 127.5412)
		(end 226.9466 127.5412)
		(width 0.254)
		(layer "F.Cu")
		(net "USB_VBUS")
	)
	(segment
		(start 144.2216 107.0412)
		(end 144.2216 106.00147)
		(width 0.2032)
		(layer "F.Cu")
		(net "NetR99_2")
	)
	(segment
		(start 144.1216 105.90146)
		(end 144.2216 106.00147)
		(width 0.2032)
		(layer "F.Cu")
		(net "NetR99_2")
	)
	(segment
		(start 144.1216 105.90146)
		(end 144.1216 105.3662)
		(width 0.2032)
		(layer "F.Cu")
		(net "NetR99_2")
	)
	(segment
		(start 144.1216 103.2162)
		(end 144.7216 102.6162)
		(width 0.2032)
		(layer "F.Cu")
		(net "NetR98_2")
	)
	(segment
		(start 144.1216 104.0662)
		(end 144.1216 103.2162)
		(width 0.2032)
		(layer "F.Cu")
		(net "NetR98_2")
	)
	(segment
		(start 144.7216 102.6162)
		(end 144.7216 102.5912)
		(width 0.2032)
		(layer "F.Cu")
		(net "NetR98_2")
	)
	(segment
		(start 143.3216 105.90146)
		(end 143.3216 105.3662)
		(width 0.2032)
		(layer "F.Cu")
		(net "NetR97_2")
	)
	(segment
		(start 143.1216 107.0412)
		(end 143.1216 106.10146)
		(width 0.2032)
		(layer "F.Cu")
		(net "NetR97_2")
	)
	(segment
		(start 143.1216 106.10146)
		(end 143.3216 105.90146)
		(width 0.2032)
		(layer "F.Cu")
		(net "NetR97_2")
	)
	(segment
		(start 142.8216 103.146)
		(end 142.8216 102.5912)
		(width 0.2032)
		(layer "F.Cu")
		(net "NetR96_2")
	)
	(segment
		(start 143.32 104.0646)
		(end 143.3216 104.0662)
		(width 0.2032)
		(layer "F.Cu")
		(net "NetR96_2")
	)
	(segment
		(start 143.32 104.0646)
		(end 143.32 103.6444)
		(width 0.2032)
		(layer "F.Cu")
		(net "NetR96_2")
	)
	(segment
		(start 142.8216 103.146)
		(end 143.32 103.6444)
		(width 0.2032)
		(layer "F.Cu")
		(net "NetR96_2")
	)
	(segment
		(start 152.03226 130.4162)
		(end 152.33226 130.1162)
		(width 0.2032)
		(layer "F.Cu")
		(net "NetR93_2")
	)
	(segment
		(start 152.33226 130.1162)
		(end 152.8716 130.1162)
		(width 0.2032)
		(layer "F.Cu")
		(net "NetR93_2")
	)
	(segment
		(start 151.0716 130.4162)
		(end 152.03226 130.4162)
		(width 0.2032)
		(layer "F.Cu")
		(net "NetR93_2")
	)
	(segment
		(start 154.65806 130.1162)
		(end 155.02135 130.4795)
		(width 0.2032)
		(layer "F.Cu")
		(net "NetR92_2")
	)
	(segment
		(start 155.02135 130.4795)
		(end 155.0849 130.4795)
		(width 0.2032)
		(layer "F.Cu")
		(net "NetR92_2")
	)
	(segment
		(start 154.1716 130.1162)
		(end 154.65806 130.1162)
		(width 0.2032)
		(layer "F.Cu")
		(net "NetR92_2")
	)
	(segment
		(start 155.0849 130.4795)
		(end 155.6216 131.0162)
		(width 0.2032)
		(layer "F.Cu")
		(net "NetR92_2")
	)
	(segment
		(start 151.2716 128.6162)
		(end 151.73237 129.07697)
		(width 0.2032)
		(layer "F.Cu")
		(net "NetR91_2")
	)
	(segment
		(start 151.73237 129.07697)
		(end 152.09303 129.07697)
		(width 0.2032)
		(layer "F.Cu")
		(net "NetR91_2")
	)
	(segment
		(start 152.33226 129.3162)
		(end 152.8716 129.3162)
		(width 0.2032)
		(layer "F.Cu")
		(net "NetR91_2")
	)
	(segment
		(start 152.09303 129.07697)
		(end 152.33226 129.3162)
		(width 0.2032)
		(layer "F.Cu")
		(net "NetR91_2")
	)
	(segment
		(start 154.87234 128.31546)
		(end 155.4216 127.7662)
		(width 0.2032)
		(layer "F.Cu")
		(net "NetR90_2")
	)
	(segment
		(start 154.1716 129.3162)
		(end 154.1732 129.3146)
		(width 0.2032)
		(layer "F.Cu")
		(net "NetR90_2")
	)
	(segment
		(start 154.1732 129.3146)
		(end 154.49649 129.3146)
		(width 0.2032)
		(layer "F.Cu")
		(net "NetR90_2")
	)
	(segment
		(start 154.49649 129.3146)
		(end 154.87234 128.93874)
		(width 0.2032)
		(layer "F.Cu")
		(net "NetR90_2")
	)
	(segment
		(start 154.87234 128.93874)
		(end 154.87234 128.31546)
		(width 0.2032)
		(layer "F.Cu")
		(net "NetR90_2")
	)
	(segment
		(start 157.12 129.9178)
		(end 157.67 129.9178)
		(width 0.2032)
		(layer "F.Cu")
		(net "NetR87_2")
	)
	(segment
		(start 156.7216 131.0662)
		(end 156.7216 130.3162)
		(width 0.2032)
		(layer "F.Cu")
		(net "NetR87_2")
	)
	(segment
		(start 157.67 129.9178)
		(end 157.6716 129.9162)
		(width 0.2032)
		(layer "F.Cu")
		(net "NetR87_2")
	)
	(segment
		(start 156.7216 130.3162)
		(end 157.12 129.9178)
		(width 0.2032)
		(layer "F.Cu")
		(net "NetR87_2")
	)
	(segment
		(start 160.48161 130.27621)
		(end 160.5216 130.3162)
		(width 0.2032)
		(layer "F.Cu")
		(net "NetR86_2")
	)
	(segment
		(start 158.9716 129.9162)
		(end 159.58179 129.9162)
		(width 0.2032)
		(layer "F.Cu")
		(net "NetR86_2")
	)
	(segment
		(start 159.9418 130.27621)
		(end 160.48161 130.27621)
		(width 0.2032)
		(layer "F.Cu")
		(net "NetR86_2")
	)
	(segment
		(start 159.58179 129.9162)
		(end 159.9418 130.27621)
		(width 0.2032)
		(layer "F.Cu")
		(net "NetR86_2")
	)
	(segment
		(start 157.34671 129.1146)
		(end 157.67 129.1146)
		(width 0.2032)
		(layer "F.Cu")
		(net "NetR85_2")
	)
	(segment
		(start 156.7216 128.48949)
		(end 156.7216 127.7662)
		(width 0.2032)
		(layer "F.Cu")
		(net "NetR85_2")
	)
	(segment
		(start 156.7216 128.48949)
		(end 157.34671 129.1146)
		(width 0.2032)
		(layer "F.Cu")
		(net "NetR85_2")
	)
	(segment
		(start 157.67 129.1146)
		(end 157.6716 129.1162)
		(width 0.2032)
		(layer "F.Cu")
		(net "NetR85_2")
	)
	(segment
		(start 158.9716 129.1162)
		(end 159.58179 129.1162)
		(width 0.2032)
		(layer "F.Cu")
		(net "NetR84_2")
	)
	(segment
		(start 160.58161 128.55619)
		(end 160.7216 128.4162)
		(width 0.2032)
		(layer "F.Cu")
		(net "NetR84_2")
	)
	(segment
		(start 160.1418 128.55619)
		(end 160.58161 128.55619)
		(width 0.2032)
		(layer "F.Cu")
		(net "NetR84_2")
	)
	(segment
		(start 159.58179 129.1162)
		(end 160.1418 128.55619)
		(width 0.2032)
		(layer "F.Cu")
		(net "NetR84_2")
	)
	(segment
		(start 228.16791 114.91251)
		(end 228.16791 113.21251)
		(width 0.2032)
		(layer "F.Cu")
		(net "NetR42_1")
	)
	(segment
		(start 228.1216 113.1662)
		(end 228.16791 113.21251)
		(width 0.2032)
		(layer "F.Cu")
		(net "NetR42_1")
	)
	(segment
		(start 228.16791 114.91251)
		(end 228.1716 114.9162)
		(width 0.2032)
		(layer "F.Cu")
		(net "NetR42_1")
	)
	(segment
		(start 222.02938 111.2912)
		(end 222.07062 111.2912)
		(width 0.254)
		(layer "F.Cu")
		(net "NetD24_1")
	)
	(segment
		(start 222.24562 111.1162)
		(end 223.9716 111.1162)
		(width 0.254)
		(layer "F.Cu")
		(net "NetD24_1")
	)
	(segment
		(start 222.07062 111.2912)
		(end 222.24562 111.1162)
		(width 0.254)
		(layer "F.Cu")
		(net "NetD24_1")
	)
	(via
		(at 222.02938 111.2912)
		(size 0.4064)
		(drill 0.2032)
		(layers "F.Cu" "B.Cu")
		(net "NetD24_1")
	)
	(segment
		(start 222.0216 112.0912)
		(end 222.02549 112.08731)
		(width 0.254)
		(layer "B.Cu")
		(net "NetD24_1")
	)
	(segment
		(start 222.02549 112.08731)
		(end 222.02549 111.29509)
		(width 0.254)
		(layer "B.Cu")
		(net "NetD24_1")
	)
	(segment
		(start 222.02549 111.29509)
		(end 222.02938 111.2912)
		(width 0.254)
		(layer "B.Cu")
		(net "NetD24_1")
	)
	(segment
		(start 228.8216 112.6162)
		(end 228.8216 112.6162)
		(width 0.2032)
		(layer "F.Cu")
		(net "NetC92_1")
	)
	(segment
		(start 228.6216 114.07118)
		(end 228.8216 113.87118)
		(width 0.2032)
		(layer "F.Cu")
		(net "NetC92_1")
	)
	(segment
		(start 228.28653 118.65636)
		(end 228.28653 118.60138)
		(width 0.2032)
		(layer "F.Cu")
		(net "NetC92_1")
	)
	(segment
		(start 228.1716 118.48645)
		(end 228.1716 117.7472)
		(width 0.2032)
		(layer "F.Cu")
		(net "NetC92_1")
	)
	(segment
		(start 228.8216 113.87118)
		(end 228.8216 112.6162)
		(width 0.2032)
		(layer "F.Cu")
		(net "NetC92_1")
	)
	(segment
		(start 228.6216 114.9162)
		(end 228.6216 114.07118)
		(width 0.2032)
		(layer "F.Cu")
		(net "NetC92_1")
	)
	(segment
		(start 228.8216 112.6162)
		(end 228.8216 112.5162)
		(width 0.2032)
		(layer "F.Cu")
		(net "NetC92_1")
	)
	(segment
		(start 228.1716 118.48645)
		(end 228.28653 118.60138)
		(width 0.2032)
		(layer "F.Cu")
		(net "NetC92_1")
	)
	(via
		(at 228.8216 112.5162)
		(size 0.4064)
		(drill 0.2032)
		(layers "F.Cu" "B.Cu")
		(net "NetC92_1")
	)
	(via
		(at 228.28653 118.65636)
		(size 0.4064)
		(drill 0.2032)
		(layers "F.Cu" "B.Cu")
		(net "NetC92_1")
	)
	(segment
		(start 227.98376 113.66173)
		(end 227.98376 113.35404)
		(width 0.2032)
		(layer "B.Cu")
		(net "NetC92_1")
	)
	(segment
		(start 227.6059 114.00513)
		(end 227.6059 113.97067)
		(width 0.2032)
		(layer "B.Cu")
		(net "NetC92_1")
	)
	(segment
		(start 227.45606 114.15496)
		(end 227.6059 114.00513)
		(width 0.2032)
		(layer "B.Cu")
		(net "NetC92_1")
	)
	(segment
		(start 227.76036 113.8162)
		(end 227.79483 113.8162)
		(width 0.2032)
		(layer "B.Cu")
		(net "NetC92_1")
	)
	(segment
		(start 227.6059 113.97067)
		(end 227.76036 113.8162)
		(width 0.2032)
		(layer "B.Cu")
		(net "NetC92_1")
	)
	(segment
		(start 227.91387 118.2837)
		(end 228.28653 118.65636)
		(width 0.2032)
		(layer "B.Cu")
		(net "NetC92_1")
	)
	(segment
		(start 227.82929 113.8162)
		(end 227.98376 113.66173)
		(width 0.2032)
		(layer "B.Cu")
		(net "NetC92_1")
	)
	(segment
		(start 227.45606 117.94993)
		(end 227.45606 115.7162)
		(width 0.2032)
		(layer "B.Cu")
		(net "NetC92_1")
	)
	(segment
		(start 227.45606 117.94993)
		(end 227.78984 118.2837)
		(width 0.2032)
		(layer "B.Cu")
		(net "NetC92_1")
	)
	(segment
		(start 227.98376 113.35404)
		(end 228.8216 112.5162)
		(width 0.2032)
		(layer "B.Cu")
		(net "NetC92_1")
	)
	(segment
		(start 227.78984 118.2837)
		(end 227.91387 118.2837)
		(width 0.2032)
		(layer "B.Cu")
		(net "NetC92_1")
	)
	(segment
		(start 227.79483 113.8162)
		(end 227.82929 113.8162)
		(width 0.2032)
		(layer "B.Cu")
		(net "NetC92_1")
	)
	(segment
		(start 227.45606 115.7162)
		(end 227.45606 114.15496)
		(width 0.2032)
		(layer "B.Cu")
		(net "NetC92_1")
	)
	(segment
		(start 227.71791 119.29489)
		(end 227.71791 117.75089)
		(width 0.2032)
		(layer "F.Cu")
		(net "NetC91_1")
	)
	(segment
		(start 227.72785 120.32245)
		(end 227.7341 120.3162)
		(width 0.2032)
		(layer "F.Cu")
		(net "NetC91_1")
	)
	(segment
		(start 227.71791 117.75089)
		(end 227.7216 117.7472)
		(width 0.2032)
		(layer "F.Cu")
		(net "NetC91_1")
	)
	(segment
		(start 227.7216 121.4162)
		(end 227.72785 121.40995)
		(width 0.2032)
		(layer "F.Cu")
		(net "NetC91_1")
	)
	(segment
		(start 227.6966 119.3162)
		(end 227.71535 119.33495)
		(width 0.2032)
		(layer "F.Cu")
		(net "NetC91_1")
	)
	(segment
		(start 227.71535 120.29745)
		(end 227.7341 120.3162)
		(width 0.2032)
		(layer "F.Cu")
		(net "NetC91_1")
	)
	(segment
		(start 227.6966 119.3162)
		(end 227.71791 119.29489)
		(width 0.2032)
		(layer "F.Cu")
		(net "NetC91_1")
	)
	(segment
		(start 227.72785 121.40995)
		(end 227.72785 120.32245)
		(width 0.2032)
		(layer "F.Cu")
		(net "NetC91_1")
	)
	(segment
		(start 227.71535 120.29745)
		(end 227.71535 119.33495)
		(width 0.2032)
		(layer "F.Cu")
		(net "NetC91_1")
	)
	(segment
		(start 143.34668 129.73687)
		(end 143.34668 129.72068)
		(width 0.2032)
		(layer "F.Cu")
		(net "GPS2_TX_FPGA")
	)
	(segment
		(start 151.7216 127.1162)
		(end 152.9716 127.1162)
		(width 0.2032)
		(layer "F.Cu")
		(net "GPS2_TX_FPGA")
	)
	(segment
		(start 151.1216 127.1162)
		(end 151.7216 127.1162)
		(width 0.2032)
		(layer "F.Cu")
		(net "GPS2_TX_FPGA")
	)
	(segment
		(start 140.46126 129.72068)
		(end 143.34668 129.72068)
		(width 0.2032)
		(layer "F.Cu")
		(net "GPS2_TX_FPGA")
	)
	(segment
		(start 150.3716 128.6162)
		(end 150.3716 127.8662)
		(width 0.2032)
		(layer "F.Cu")
		(net "GPS2_TX_FPGA")
	)
	(segment
		(start 150.3716 127.8662)
		(end 151.1216 127.1162)
		(width 0.2032)
		(layer "F.Cu")
		(net "GPS2_TX_FPGA")
	)
	(via
		(at 143.34668 129.73687)
		(size 0.4064)
		(drill 0.2032)
		(layers "F.Cu" "B.Cu")
		(tenting
			(front yes)
			(back yes)
		)
		(net "GPS2_TX_FPGA")
	)
	(via
		(at 151.7216 127.1162)
		(size 0.4064)
		(drill 0.2032)
		(layers "F.Cu" "B.Cu")
		(net "GPS2_TX_FPGA")
	)
	(segment
		(start 147.70092 129.73687)
		(end 150.3216 127.1162)
		(width 0.2032)
		(layer "B.Cu")
		(net "GPS2_TX_FPGA")
	)
	(segment
		(start 143.34668 129.73687)
		(end 147.70092 129.73687)
		(width 0.2032)
		(layer "B.Cu")
		(net "GPS2_TX_FPGA")
	)
	(segment
		(start 150.3216 127.1162)
		(end 151.7216 127.1162)
		(width 0.2032)
		(layer "B.Cu")
		(net "GPS2_TX_FPGA")
	)
	(segment
		(start 151.3216 132.2162)
		(end 152.8716 132.2162)
		(width 0.2032)
		(layer "F.Cu")
		(net "GPS2_RX_FPGA")
	)
	(segment
		(start 134.64667 129.72447)
		(end 134.64667 129.72068)
		(width 0.2032)
		(layer "F.Cu")
		(net "GPS2_RX_FPGA")
	)
	(segment
		(start 150.4216 131.3162)
		(end 150.4216 131.26121)
		(width 0.2032)
		(layer "F.Cu")
		(net "GPS2_RX_FPGA")
	)
	(segment
		(start 150.1716 131.01121)
		(end 150.4216 131.26121)
		(width 0.2032)
		(layer "F.Cu")
		(net "GPS2_RX_FPGA")
	)
	(segment
		(start 134.64667 129.72068)
		(end 136.41149 129.72068)
		(width 0.2032)
		(layer "F.Cu")
		(net "GPS2_RX_FPGA")
	)
	(segment
		(start 150.1716 131.01121)
		(end 150.1716 130.4162)
		(width 0.2032)
		(layer "F.Cu")
		(net "GPS2_RX_FPGA")
	)
	(segment
		(start 150.4216 131.3162)
		(end 151.3216 132.2162)
		(width 0.2032)
		(layer "F.Cu")
		(net "GPS2_RX_FPGA")
	)
	(via
		(at 150.4216 131.3162)
		(size 0.4064)
		(drill 0.2032)
		(layers "F.Cu" "B.Cu")
		(net "GPS2_RX_FPGA")
	)
	(via
		(at 134.64667 129.72447)
		(size 0.4064)
		(drill 0.2032)
		(layers "F.Cu" "B.Cu")
		(tenting
			(front yes)
			(back yes)
		)
		(net "GPS2_RX_FPGA")
	)
	(segment
		(start 136.2384 131.3162)
		(end 150.4216 131.3162)
		(width 0.2032)
		(layer "B.Cu")
		(net "GPS2_RX_FPGA")
	)
	(segment
		(start 134.64667 129.72447)
		(end 136.2384 131.3162)
		(width 0.2032)
		(layer "B.Cu")
		(net "GPS2_RX_FPGA")
	)
	(segment
		(start 229.2216 119.2162)
		(end 229.2216 118.9162)
		(width 0.2032)
		(layer "F.Cu")
		(net "FTDI_VBUS")
	)
	(segment
		(start 227.8216 132.0162)
		(end 227.85606 132.0162)
		(width 0.2032)
		(layer "F.Cu")
		(net "FTDI_VBUS")
	)
	(segment
		(start 225.87216 119.3162)
		(end 226.9466 119.3162)
		(width 0.2032)
		(layer "F.Cu")
		(net "FTDI_VBUS")
	)
	(segment
		(start 225.89768 131.3162)
		(end 227.1216 131.3162)
		(width 0.2032)
		(layer "F.Cu")
		(net "FTDI_VBUS")
	)
	(segment
		(start 227.1216 131.3162)
		(end 227.8216 132.0162)
		(width 0.2032)
		(layer "F.Cu")
		(net "FTDI_VBUS")
	)
	(segment
		(start 228.62529 118.31989)
		(end 228.62529 117.75089)
		(width 0.2032)
		(layer "F.Cu")
		(net "FTDI_VBUS")
	)
	(segment
		(start 228.62529 118.31989)
		(end 229.2216 118.9162)
		(width 0.2032)
		(layer "F.Cu")
		(net "FTDI_VBUS")
	)
	(segment
		(start 228.6216 117.7472)
		(end 228.62529 117.75089)
		(width 0.2032)
		(layer "F.Cu")
		(net "FTDI_VBUS")
	)
	(via
		(at 227.1216 131.3162)
		(size 0.4064)
		(drill 0.2032)
		(layers "F.Cu" "B.Cu")
		(net "FTDI_VBUS")
	)
	(via
		(at 229.2216 119.2162)
		(size 0.4064)
		(drill 0.2032)
		(layers "F.Cu" "B.Cu")
		(net "FTDI_VBUS")
	)
	(via
		(at 225.87216 119.3162)
		(size 0.4064)
		(drill 0.2032)
		(layers "F.Cu" "B.Cu")
		(net "FTDI_VBUS")
	)
	(segment
		(start 222.4083 126.63428)
		(end 223.50318 126.63428)
		(width 0.254)
		(layer "B.Cu")
		(net "FTDI_VBUS")
	)
	(segment
		(start 227.1216 131.71862)
		(end 227.1216 131.3162)
		(width 0.508)
		(layer "B.Cu")
		(net "FTDI_VBUS")
	)
	(segment
		(start 217.07331 125.86791)
		(end 217.10631 125.83492)
		(width 0.254)
		(layer "B.Cu")
		(net "FTDI_VBUS")
	)
	(segment
		(start 217.07331 125.86791)
		(end 218.19354 125.86791)
		(width 0.254)
		(layer "B.Cu")
		(net "FTDI_VBUS")
	)
	(segment
		(start 224.9216 126.1316)
		(end 224.9216 124.12341)
		(width 0.508)
		(layer "B.Cu")
		(net "FTDI_VBUS")
	)
	(segment
		(start 221.8216 124.6162)
		(end 223.5216 124.6162)
		(width 0.254)
		(layer "B.Cu")
		(net "FTDI_VBUS")
	)
	(segment
		(start 219.1216 124.93985)
		(end 219.1216 124.0162)
		(width 0.254)
		(layer "B.Cu")
		(net "FTDI_VBUS")
	)
	(segment
		(start 224.9216 120.26676)
		(end 225.87216 119.3162)
		(width 0.508)
		(layer "B.Cu")
		(net "FTDI_VBUS")
	)
	(segment
		(start 227.41918 132.0162)
		(end 227.76803 132.0162)
		(width 0.508)
		(layer "B.Cu")
		(net "FTDI_VBUS")
	)
	(segment
		(start 218.19354 125.86791)
		(end 219.1216 124.93985)
		(width 0.254)
		(layer "B.Cu")
		(net "FTDI_VBUS")
	)
	(segment
		(start 222.4083 125.83428)
		(end 222.90352 125.83428)
		(width 0.254)
		(layer "B.Cu")
		(net "FTDI_VBUS")
	)
	(segment
		(start 217.10631 125.83492)
		(end 217.60288 125.83492)
		(width 0.254)
		(layer "B.Cu")
		(net "FTDI_VBUS")
	)
	(segment
		(start 223.43248 126.00116)
		(end 223.56155 126.13023)
		(width 0.254)
		(layer "B.Cu")
		(net "FTDI_VBUS")
	)
	(segment
		(start 225.87216 119.3162)
		(end 229.06661 119.3162)
		(width 0.508)
		(layer "B.Cu")
		(net "FTDI_VBUS")
	)
	(segment
		(start 223.0704 126.00116)
		(end 223.43248 126.00116)
		(width 0.254)
		(layer "B.Cu")
		(net "FTDI_VBUS")
	)
	(segment
		(start 223.56155 126.16469)
		(end 223.56155 126.13023)
		(width 0.254)
		(layer "B.Cu")
		(net "FTDI_VBUS")
	)
	(segment
		(start 222.90352 125.83428)
		(end 223.0704 126.00116)
		(width 0.254)
		(layer "B.Cu")
		(net "FTDI_VBUS")
	)
	(segment
		(start 223.56155 126.16469)
		(end 224.88851 126.16469)
		(width 0.508)
		(layer "B.Cu")
		(net "FTDI_VBUS")
	)
	(segment
		(start 223.5216 124.6162)
		(end 224.01439 124.12341)
		(width 0.254)
		(layer "B.Cu")
		(net "FTDI_VBUS")
	)
	(segment
		(start 224.01439 124.12341)
		(end 224.9216 124.12341)
		(width 0.254)
		(layer "B.Cu")
		(net "FTDI_VBUS")
	)
	(segment
		(start 224.9216 124.12341)
		(end 224.9216 120.26676)
		(width 0.508)
		(layer "B.Cu")
		(net "FTDI_VBUS")
	)
	(segment
		(start 220.8216 123.6162)
		(end 221.8216 124.6162)
		(width 0.254)
		(layer "B.Cu")
		(net "FTDI_VBUS")
	)
	(segment
		(start 224.9216 129.1162)
		(end 227.1216 131.3162)
		(width 0.508)
		(layer "B.Cu")
		(net "FTDI_VBUS")
	)
	(segment
		(start 227.1216 131.71862)
		(end 227.41918 132.0162)
		(width 0.508)
		(layer "B.Cu")
		(net "FTDI_VBUS")
	)
	(segment
		(start 229.16661 119.2162)
		(end 229.2216 119.2162)
		(width 0.508)
		(layer "B.Cu")
		(net "FTDI_VBUS")
	)
	(segment
		(start 219.5216 123.6162)
		(end 220.8216 123.6162)
		(width 0.254)
		(layer "B.Cu")
		(net "FTDI_VBUS")
	)
	(segment
		(start 219.1216 124.0162)
		(end 219.5216 123.6162)
		(width 0.254)
		(layer "B.Cu")
		(net "FTDI_VBUS")
	)
	(segment
		(start 229.06661 119.3162)
		(end 229.16661 119.2162)
		(width 0.508)
		(layer "B.Cu")
		(net "FTDI_VBUS")
	)
	(segment
		(start 224.9216 129.1162)
		(end 224.9216 126.1316)
		(width 0.508)
		(layer "B.Cu")
		(net "FTDI_VBUS")
	)
	(segment
		(start 223.50318 126.63428)
		(end 223.56155 126.69264)
		(width 0.254)
		(layer "B.Cu")
		(net "FTDI_VBUS")
	)
	(segment
		(start 223.56155 127.22059)
		(end 223.56155 126.69264)
		(width 0.508)
		(layer "B.Cu")
		(net "FTDI_VBUS")
	)
	(segment
		(start 224.88851 126.16469)
		(end 224.9216 126.1316)
		(width 0.508)
		(layer "B.Cu")
		(net "FTDI_VBUS")
	)
	(segment
		(start 223.56155 126.69264)
		(end 223.56155 126.16469)
		(width 0.508)
		(layer "B.Cu")
		(net "FTDI_VBUS")
	)
	(segment
		(start 224.4978 116.015)
		(end 224.6966 115.8162)
		(width 0.1524)
		(layer "F.Cu")
		(net "FTDI_USB_R_P")
	)
	(segment
		(start 223.61087 125.10547)
		(end 223.61087 122.89511)
		(width 0.1524)
		(layer "F.Cu")
		(net "FTDI_USB_R_P")
	)
	(segment
		(start 226.299 126.4138)
		(end 226.4716 126.2412)
		(width 0.1524)
		(layer "F.Cu")
		(net "FTDI_USB_R_P")
	)
	(segment
		(start 223.61087 122.89511)
		(end 223.72517 122.78081)
		(width 0.1524)
		(layer "F.Cu")
		(net "FTDI_USB_R_P")
	)
	(segment
		(start 223.6216 125.1162)
		(end 224.9192 126.4138)
		(width 0.1524)
		(layer "F.Cu")
		(net "FTDI_USB_R_P")
	)
	(segment
		(start 223.70463 116.1638)
		(end 224.40852 116.1638)
		(width 0.1524)
		(layer "F.Cu")
		(net "FTDI_USB_R_P")
	)
	(segment
		(start 224.40852 116.1638)
		(end 224.4978 116.07453)
		(width 0.1524)
		(layer "F.Cu")
		(net "FTDI_USB_R_P")
	)
	(segment
		(start 224.4978 116.07453)
		(end 224.4978 116.015)
		(width 0.1524)
		(layer "F.Cu")
		(net "FTDI_USB_R_P")
	)
	(segment
		(start 224.9192 126.4138)
		(end 226.299 126.4138)
		(width 0.1524)
		(layer "F.Cu")
		(net "FTDI_USB_R_P")
	)
	(segment
		(start 226.4716 126.2412)
		(end 226.9466 126.2412)
		(width 0.1524)
		(layer "F.Cu")
		(net "FTDI_USB_R_P")
	)
	(segment
		(start 223.61087 125.10547)
		(end 223.6216 125.1162)
		(width 0.1524)
		(layer "F.Cu")
		(net "FTDI_USB_R_P")
	)
	(via
		(at 223.5216 116.0495)
		(size 0.4064)
		(drill 0.2032)
		(layers "F.Cu" "B.Cu")
		(net "FTDI_USB_R_P")
	)
	(via
		(at 223.72517 122.78081)
		(size 0.4064)
		(drill 0.2032)
		(layers "F.Cu" "B.Cu")
		(net "FTDI_USB_R_P")
	)
	(segment
		(start 222.91332 116.3035)
		(end 223.19887 116.3035)
		(width 0.1524)
		(layer "B.Cu")
		(net "FTDI_USB_R_P")
	)
	(segment
		(start 221.5168 123.54245)
		(end 221.5168 117.70002)
		(width 0.1524)
		(layer "B.Cu")
		(net "FTDI_USB_R_P")
	)
	(segment
		(start 223.5866 116.06932)
		(end 224.5883 116.06932)
		(width 0.1524)
		(layer "B.Cu")
		(net "FTDI_USB_R_P")
	)
	(segment
		(start 223.72517 122.84955)
		(end 223.72517 122.78081)
		(width 0.1524)
		(layer "B.Cu")
		(net "FTDI_USB_R_P")
	)
	(segment
		(start 223.61087 122.96385)
		(end 223.72517 122.84955)
		(width 0.1524)
		(layer "B.Cu")
		(net "FTDI_USB_R_P")
	)
	(segment
		(start 221.5168 117.70002)
		(end 222.91332 116.3035)
		(width 0.1524)
		(layer "B.Cu")
		(net "FTDI_USB_R_P")
	)
	(segment
		(start 223.45287 116.0495)
		(end 223.5216 116.0495)
		(width 0.1524)
		(layer "B.Cu")
		(net "FTDI_USB_R_P")
	)
	(segment
		(start 221.5168 123.54245)
		(end 222.09535 124.121)
		(width 0.1524)
		(layer "B.Cu")
		(net "FTDI_USB_R_P")
	)
	(segment
		(start 222.94785 124.121)
		(end 223.61087 123.45798)
		(width 0.1524)
		(layer "B.Cu")
		(net "FTDI_USB_R_P")
	)
	(segment
		(start 223.61087 123.45798)
		(end 223.61087 122.96385)
		(width 0.1524)
		(layer "B.Cu")
		(net "FTDI_USB_R_P")
	)
	(segment
		(start 224.5883 116.06932)
		(end 224.8216 115.83602)
		(width 0.1524)
		(layer "B.Cu")
		(net "FTDI_USB_R_P")
	)
	(segment
		(start 223.19887 116.3035)
		(end 223.45287 116.0495)
		(width 0.1524)
		(layer "B.Cu")
		(net "FTDI_USB_R_P")
	)
	(segment
		(start 222.09535 124.121)
		(end 222.94785 124.121)
		(width 0.1524)
		(layer "B.Cu")
		(net "FTDI_USB_R_P")
	)
	(segment
		(start 224.4978 116.6174)
		(end 224.4978 116.55788)
		(width 0.1524)
		(layer "F.Cu")
		(net "FTDI_USB_R_N")
	)
	(segment
		(start 223.70463 116.4686)
		(end 224.40853 116.4686)
		(width 0.1524)
		(layer "F.Cu")
		(net "FTDI_USB_R_N")
	)
	(segment
		(start 224.4978 116.6174)
		(end 224.6966 116.8162)
		(width 0.1524)
		(layer "F.Cu")
		(net "FTDI_USB_R_N")
	)
	(segment
		(start 223.30607 125.23172)
		(end 224.79295 126.7186)
		(width 0.1524)
		(layer "F.Cu")
		(net "FTDI_USB_R_N")
	)
	(segment
		(start 223.19177 122.78081)
		(end 223.30607 122.89511)
		(width 0.1524)
		(layer "F.Cu")
		(net "FTDI_USB_R_N")
	)
	(segment
		(start 226.299 126.7186)
		(end 226.4716 126.8912)
		(width 0.1524)
		(layer "F.Cu")
		(net "FTDI_USB_R_N")
	)
	(segment
		(start 223.30607 125.23172)
		(end 223.30607 122.89511)
		(width 0.1524)
		(layer "F.Cu")
		(net "FTDI_USB_R_N")
	)
	(segment
		(start 224.79295 126.7186)
		(end 226.299 126.7186)
		(width 0.1524)
		(layer "F.Cu")
		(net "FTDI_USB_R_N")
	)
	(segment
		(start 226.4716 126.8912)
		(end 226.9466 126.8912)
		(width 0.1524)
		(layer "F.Cu")
		(net "FTDI_USB_R_N")
	)
	(segment
		(start 224.40853 116.4686)
		(end 224.4978 116.55788)
		(width 0.1524)
		(layer "F.Cu")
		(net "FTDI_USB_R_N")
	)
	(via
		(at 223.19177 122.78081)
		(size 0.4064)
		(drill 0.2032)
		(layers "F.Cu" "B.Cu")
		(net "FTDI_USB_R_N")
	)
	(via
		(at 223.5216 116.5829)
		(size 0.4064)
		(drill 0.2032)
		(layers "F.Cu" "B.Cu")
		(net "FTDI_USB_R_N")
	)
	(segment
		(start 223.02905 116.5829)
		(end 223.5216 116.5829)
		(width 0.1524)
		(layer "B.Cu")
		(net "FTDI_USB_R_N")
	)
	(segment
		(start 223.30607 123.33173)
		(end 223.30607 122.96385)
		(width 0.1524)
		(layer "B.Cu")
		(net "FTDI_USB_R_N")
	)
	(segment
		(start 221.9994 120.71639)
		(end 222.02483 120.71639)
		(width 0.1524)
		(layer "B.Cu")
		(net "FTDI_USB_R_N")
	)
	(segment
		(start 221.8216 120.10679)
		(end 221.8216 118.14393)
		(width 0.1524)
		(layer "B.Cu")
		(net "FTDI_USB_R_N")
	)
	(segment
		(start 222.0248 120.30999)
		(end 222.02483 120.30999)
		(width 0.1524)
		(layer "B.Cu")
		(net "FTDI_USB_R_N")
	)
	(segment
		(start 221.8216 123.4162)
		(end 221.8216 122.215)
		(width 0.1524)
		(layer "B.Cu")
		(net "FTDI_USB_R_N")
	)
	(segment
		(start 221.8216 123.4162)
		(end 222.2216 123.8162)
		(width 0.1524)
		(layer "B.Cu")
		(net "FTDI_USB_R_N")
	)
	(segment
		(start 221.8216 122.215)
		(end 221.8216 121.73239)
		(width 0.1524)
		(layer "B.Cu")
		(net "FTDI_USB_R_N")
	)
	(segment
		(start 222.2216 123.8162)
		(end 222.8216 123.8162)
		(width 0.1524)
		(layer "B.Cu")
		(net "FTDI_USB_R_N")
	)
	(segment
		(start 223.5866 116.60272)
		(end 224.5883 116.60272)
		(width 0.1524)
		(layer "B.Cu")
		(net "FTDI_USB_R_N")
	)
	(segment
		(start 221.8216 117.79035)
		(end 223.02905 116.5829)
		(width 0.1524)
		(layer "B.Cu")
		(net "FTDI_USB_R_N")
	)
	(segment
		(start 222.8216 123.8162)
		(end 223.30607 123.33173)
		(width 0.1524)
		(layer "B.Cu")
		(net "FTDI_USB_R_N")
	)
	(segment
		(start 221.9994 121.12279)
		(end 222.07726 121.12279)
		(width 0.1524)
		(layer "B.Cu")
		(net "FTDI_USB_R_N")
	)
	(segment
		(start 223.19177 122.84955)
		(end 223.19177 122.78081)
		(width 0.1524)
		(layer "B.Cu")
		(net "FTDI_USB_R_N")
	)
	(segment
		(start 224.5883 116.60272)
		(end 224.8216 116.83603)
		(width 0.1524)
		(layer "B.Cu")
		(net "FTDI_USB_R_N")
	)
	(segment
		(start 221.8216 118.14393)
		(end 221.8216 117.79035)
		(width 0.1524)
		(layer "B.Cu")
		(net "FTDI_USB_R_N")
	)
	(segment
		(start 223.19177 122.84955)
		(end 223.30607 122.96385)
		(width 0.1524)
		(layer "B.Cu")
		(net "FTDI_USB_R_N")
	)
	(segment
		(start 222.0248 121.52919)
		(end 222.07726 121.52919)
		(width 0.1524)
		(layer "B.Cu")
		(net "FTDI_USB_R_N")
	)
	(arc
		(start 222.02483 120.30999)
		(mid 222.22803 120.51319)
		(end 222.02483 120.71639)
		(width 0.1524)
		(layer "B.Cu")
		(net "FTDI_USB_R_N")
	)
	(arc
		(start 221.9994 121.12279)
		(mid 221.7962 120.91959)
		(end 221.9994 120.71639)
		(width 0.1524)
		(layer "B.Cu")
		(net "FTDI_USB_R_N")
	)
	(arc
		(start 222.0248 120.30999)
		(mid 221.881116 120.250474)
		(end 221.8216 120.10679)
		(width 0.1524)
		(layer "B.Cu")
		(net "FTDI_USB_R_N")
	)
	(arc
		(start 222.07726 121.12279)
		(mid 222.28046 121.32599)
		(end 222.07726 121.52919)
		(width 0.1524)
		(layer "B.Cu")
		(net "FTDI_USB_R_N")
	)
	(arc
		(start 221.8216 121.73239)
		(mid 221.881116 121.588706)
		(end 222.0248 121.52919)
		(width 0.1524)
		(layer "B.Cu")
		(net "FTDI_USB_R_N")
	)
	(segment
		(start 226.4966 114.9162)
		(end 227.2716 114.9162)
		(width 0.2032)
		(layer "F.Cu")
		(net "FTDI_USB_P")
	)
	(segment
		(start 225.5966 115.8162)
		(end 226.4966 114.9162)
		(width 0.2032)
		(layer "F.Cu")
		(net "FTDI_USB_P")
	)
	(segment
		(start 225.5966 116.8162)
		(end 226.5276 117.7472)
		(width 0.2032)
		(layer "F.Cu")
		(net "FTDI_USB_N")
	)
	(segment
		(start 226.5276 117.7472)
		(end 227.2716 117.7472)
		(width 0.2032)
		(layer "F.Cu")
		(net "FTDI_USB_N")
	)
	(segment
		(start 156.7216 131.9662)
		(end 156.7966 132.0412)
		(width 0.2032)
		(layer "F.Cu")
		(net "FTDI_TX")
	)
	(segment
		(start 157.8966 132.0412)
		(end 157.9716 132.1162)
		(width 0.2032)
		(layer "F.Cu")
		(net "FTDI_TX")
	)
	(segment
		(start 155.6216 131.9162)
		(end 155.6466 131.9412)
		(width 0.2032)
		(layer "F.Cu")
		(net "FTDI_TX")
	)
	(segment
		(start 156.7966 132.0412)
		(end 157.8966 132.0412)
		(width 0.2032)
		(layer "F.Cu")
		(net "FTDI_TX")
	)
	(segment
		(start 157.9716 133.07813)
		(end 167.85967 133.07813)
		(width 0.2032)
		(layer "F.Cu")
		(net "FTDI_TX")
	)
	(segment
		(start 167.85967 133.07813)
		(end 174.4216 126.5162)
		(width 0.2032)
		(layer "F.Cu")
		(net "FTDI_TX")
	)
	(segment
		(start 156.6966 131.9412)
		(end 156.7216 131.9662)
		(width 0.2032)
		(layer "F.Cu")
		(net "FTDI_TX")
	)
	(segment
		(start 230.6716 113.1162)
		(end 231.37636 113.1162)
		(width 0.2032)
		(layer "F.Cu")
		(net "FTDI_TX")
	)
	(segment
		(start 155.6466 131.9412)
		(end 156.6966 131.9412)
		(width 0.2032)
		(layer "F.Cu")
		(net "FTDI_TX")
	)
	(segment
		(start 157.9716 133.07813)
		(end 157.9716 132.1162)
		(width 0.2032)
		(layer "F.Cu")
		(net "FTDI_TX")
	)
	(via
		(at 174.4216 126.5162)
		(size 0.4064)
		(drill 0.2032)
		(layers "F.Cu" "B.Cu")
		(net "FTDI_TX")
	)
	(via
		(at 231.37636 113.1162)
		(size 0.4064)
		(drill 0.2032)
		(layers "F.Cu" "B.Cu")
		(net "FTDI_TX")
	)
	(segment
		(start 219.5914 118.7464)
		(end 226.2534 112.0844)
		(width 0.2032)
		(layer "B.Cu")
		(net "FTDI_TX")
	)
	(segment
		(start 199.1518 117.16363)
		(end 199.1518 114.65297)
		(width 0.2032)
		(layer "B.Cu")
		(net "FTDI_TX")
	)
	(segment
		(start 199.41668 114.38809)
		(end 211.09349 114.38809)
		(width 0.2032)
		(layer "B.Cu")
		(net "FTDI_TX")
	)
	(segment
		(start 230.32758 113.1162)
		(end 231.37636 113.1162)
		(width 0.2032)
		(layer "B.Cu")
		(net "FTDI_TX")
	)
	(segment
		(start 226.2534 112.0844)
		(end 229.29578 112.0844)
		(width 0.2032)
		(layer "B.Cu")
		(net "FTDI_TX")
	)
	(segment
		(start 194.2216 118.0162)
		(end 198.3216 118.0162)
		(width 0.2032)
		(layer "B.Cu")
		(net "FTDI_TX")
	)
	(segment
		(start 199.0216 117.3162)
		(end 199.0216 117.29383)
		(width 0.2032)
		(layer "B.Cu")
		(net "FTDI_TX")
	)
	(segment
		(start 191.1216 117.1162)
		(end 193.3216 117.1162)
		(width 0.2032)
		(layer "B.Cu")
		(net "FTDI_TX")
	)
	(segment
		(start 174.4216 126.5162)
		(end 181.7216 119.2162)
		(width 0.2032)
		(layer "B.Cu")
		(net "FTDI_TX")
	)
	(segment
		(start 199.1518 114.65297)
		(end 199.41668 114.38809)
		(width 0.2032)
		(layer "B.Cu")
		(net "FTDI_TX")
	)
	(segment
		(start 181.7216 119.2162)
		(end 189.56309 119.2162)
		(width 0.2032)
		(layer "B.Cu")
		(net "FTDI_TX")
	)
	(segment
		(start 193.3216 117.1162)
		(end 194.2216 118.0162)
		(width 0.2032)
		(layer "B.Cu")
		(net "FTDI_TX")
	)
	(segment
		(start 229.29578 112.0844)
		(end 230.32758 113.1162)
		(width 0.2032)
		(layer "B.Cu")
		(net "FTDI_TX")
	)
	(segment
		(start 199.0216 117.29383)
		(end 199.1518 117.16363)
		(width 0.2032)
		(layer "B.Cu")
		(net "FTDI_TX")
	)
	(segment
		(start 190.58402 118.19527)
		(end 190.58402 117.65378)
		(width 0.2032)
		(layer "B.Cu")
		(net "FTDI_TX")
	)
	(segment
		(start 211.09349 114.38809)
		(end 215.4518 118.7464)
		(width 0.2032)
		(layer "B.Cu")
		(net "FTDI_TX")
	)
	(segment
		(start 215.4518 118.7464)
		(end 219.5914 118.7464)
		(width 0.2032)
		(layer "B.Cu")
		(net "FTDI_TX")
	)
	(segment
		(start 189.56309 119.2162)
		(end 190.58402 118.19527)
		(width 0.2032)
		(layer "B.Cu")
		(net "FTDI_TX")
	)
	(segment
		(start 190.58402 117.65378)
		(end 191.1216 117.1162)
		(width 0.2032)
		(layer "B.Cu")
		(net "FTDI_TX")
	)
	(segment
		(start 198.3216 118.0162)
		(end 199.0216 117.3162)
		(width 0.2032)
		(layer "B.Cu")
		(net "FTDI_TX")
	)
	(segment
		(start 227.1716 111.68462)
		(end 227.5216 111.33462)
		(width 0.2032)
		(layer "F.Cu")
		(net "FTDI_RX")
	)
	(segment
		(start 157.8716 125.4662)
		(end 158.27937 125.05843)
		(width 0.2032)
		(layer "F.Cu")
		(net "FTDI_RX")
	)
	(segment
		(start 227.5216 111.33462)
		(end 227.5216 111.3162)
		(width 0.2032)
		(layer "F.Cu")
		(net "FTDI_RX")
	)
	(segment
		(start 158.27937 125.05843)
		(end 158.9684 125.05843)
		(width 0.2032)
		(layer "F.Cu")
		(net "FTDI_RX")
	)
	(segment
		(start 155.4216 126.8662)
		(end 156.7216 126.8662)
		(width 0.2032)
		(layer "F.Cu")
		(net "FTDI_RX")
	)
	(segment
		(start 156.7216 126.8662)
		(end 157.5216 126.8662)
		(width 0.2032)
		(layer "F.Cu")
		(net "FTDI_RX")
	)
	(segment
		(start 157.8716 126.5162)
		(end 157.8716 125.4662)
		(width 0.2032)
		(layer "F.Cu")
		(net "FTDI_RX")
	)
	(segment
		(start 159.32616 125.4162)
		(end 169.4216 125.4162)
		(width 0.2032)
		(layer "F.Cu")
		(net "FTDI_RX")
	)
	(segment
		(start 157.5216 126.8662)
		(end 157.8716 126.5162)
		(width 0.2032)
		(layer "F.Cu")
		(net "FTDI_RX")
	)
	(segment
		(start 227.1716 113.2162)
		(end 227.1716 111.68462)
		(width 0.2032)
		(layer "F.Cu")
		(net "FTDI_RX")
	)
	(segment
		(start 158.9684 125.05843)
		(end 159.32616 125.4162)
		(width 0.2032)
		(layer "F.Cu")
		(net "FTDI_RX")
	)
	(via
		(at 169.4216 125.4162)
		(size 0.4064)
		(drill 0.2032)
		(layers "F.Cu" "B.Cu")
		(net "FTDI_RX")
	)
	(via
		(at 227.5216 111.3162)
		(size 0.4064)
		(drill 0.2032)
		(layers "F.Cu" "B.Cu")
		(net "FTDI_RX")
	)
	(segment
		(start 223.05216 114.73393)
		(end 223.05216 113.48564)
		(width 0.2032)
		(layer "B.Cu")
		(net "FTDI_RX")
	)
	(segment
		(start 215.7216 118.4162)
		(end 219.36989 118.4162)
		(width 0.2032)
		(layer "B.Cu")
		(net "FTDI_RX")
	)
	(segment
		(start 223.05216 113.48564)
		(end 226.2216 110.3162)
		(width 0.2032)
		(layer "B.Cu")
		(net "FTDI_RX")
	)
	(segment
		(start 226.2216 110.3162)
		(end 227.2216 110.3162)
		(width 0.2032)
		(layer "B.Cu")
		(net "FTDI_RX")
	)
	(segment
		(start 188.6518 116.786)
		(end 193.8914 116.786)
		(width 0.2032)
		(layer "B.Cu")
		(net "FTDI_RX")
	)
	(segment
		(start 198.30046 117.548)
		(end 198.8216 117.02686)
		(width 0.2032)
		(layer "B.Cu")
		(net "FTDI_RX")
	)
	(segment
		(start 211.3216 114.0162)
		(end 215.7216 118.4162)
		(width 0.2032)
		(layer "B.Cu")
		(net "FTDI_RX")
	)
	(segment
		(start 199.3216 114.0162)
		(end 211.3216 114.0162)
		(width 0.2032)
		(layer "B.Cu")
		(net "FTDI_RX")
	)
	(segment
		(start 169.4216 125.4162)
		(end 170.4216 126.4162)
		(width 0.2032)
		(layer "B.Cu")
		(net "FTDI_RX")
	)
	(segment
		(start 193.8914 116.786)
		(end 194.73725 117.63185)
		(width 0.2032)
		(layer "B.Cu")
		(net "FTDI_RX")
	)
	(segment
		(start 181.4216 118.3162)
		(end 187.1216 118.3162)
		(width 0.2032)
		(layer "B.Cu")
		(net "FTDI_RX")
	)
	(segment
		(start 173.3216 126.4162)
		(end 181.4216 118.3162)
		(width 0.2032)
		(layer "B.Cu")
		(net "FTDI_RX")
	)
	(segment
		(start 198.8216 117.02686)
		(end 198.8216 114.5162)
		(width 0.2032)
		(layer "B.Cu")
		(net "FTDI_RX")
	)
	(segment
		(start 197.6898 117.548)
		(end 198.30046 117.548)
		(width 0.2032)
		(layer "B.Cu")
		(net "FTDI_RX")
	)
	(segment
		(start 194.73725 117.63185)
		(end 197.60595 117.63185)
		(width 0.2032)
		(layer "B.Cu")
		(net "FTDI_RX")
	)
	(segment
		(start 227.2216 110.3162)
		(end 227.5216 110.6162)
		(width 0.2032)
		(layer "B.Cu")
		(net "FTDI_RX")
	)
	(segment
		(start 219.36989 118.4162)
		(end 223.05216 114.73393)
		(width 0.2032)
		(layer "B.Cu")
		(net "FTDI_RX")
	)
	(segment
		(start 198.8216 114.5162)
		(end 199.3216 114.0162)
		(width 0.2032)
		(layer "B.Cu")
		(net "FTDI_RX")
	)
	(segment
		(start 197.60595 117.63185)
		(end 197.6898 117.548)
		(width 0.2032)
		(layer "B.Cu")
		(net "FTDI_RX")
	)
	(segment
		(start 187.1216 118.3162)
		(end 188.6518 116.786)
		(width 0.2032)
		(layer "B.Cu")
		(net "FTDI_RX")
	)
	(segment
		(start 170.4216 126.4162)
		(end 173.3216 126.4162)
		(width 0.2032)
		(layer "B.Cu")
		(net "FTDI_RX")
	)
	(segment
		(start 227.5216 111.3162)
		(end 227.5216 110.6162)
		(width 0.2032)
		(layer "B.Cu")
		(net "FTDI_RX")
	)
	(segment
		(start 134.52501 101.2196)
		(end 138.3216 105.0162)
		(width 0.2032)
		(layer "F.Cu")
		(net "FPGA_MAC_PPSDIFF_OUT")
	)
	(segment
		(start 134.52501 101.2196)
		(end 134.52501 88.45263)
		(width 0.2032)
		(layer "F.Cu")
		(net "FPGA_MAC_PPSDIFF_OUT")
	)
	(segment
		(start 140.6466 105.78621)
		(end 140.6466 105.0162)
		(width 0.2032)
		(layer "F.Cu")
		(net "FPGA_MAC_PPSDIFF_OUT")
	)
	(segment
		(start 133.5216 87.44923)
		(end 134.52501 88.45263)
		(width 0.2032)
		(layer "F.Cu")
		(net "FPGA_MAC_PPSDIFF_OUT")
	)
	(segment
		(start 123.9866 82.40116)
		(end 125.57156 80.8162)
		(width 0.2032)
		(layer "F.Cu")
		(net "FPGA_MAC_PPSDIFF_OUT")
	)
	(segment
		(start 125.57156 80.8162)
		(end 133.40257 80.8162)
		(width 0.2032)
		(layer "F.Cu")
		(net "FPGA_MAC_PPSDIFF_OUT")
	)
	(segment
		(start 133.5216 87.44923)
		(end 133.5216 80.93523)
		(width 0.2032)
		(layer "F.Cu")
		(net "FPGA_MAC_PPSDIFF_OUT")
	)
	(segment
		(start 138.3216 105.0162)
		(end 140.6466 105.0162)
		(width 0.2032)
		(layer "F.Cu")
		(net "FPGA_MAC_PPSDIFF_OUT")
	)
	(segment
		(start 133.40257 80.8162)
		(end 133.5216 80.93523)
		(width 0.2032)
		(layer "F.Cu")
		(net "FPGA_MAC_PPSDIFF_OUT")
	)
	(segment
		(start 140.6466 105.78621)
		(end 142.65159 107.7912)
		(width 0.2032)
		(layer "F.Cu")
		(net "FPGA_MAC_PPSDIFF_OUT")
	)
	(segment
		(start 123.9866 83.7662)
		(end 123.9866 82.40116)
		(width 0.254)
		(layer "F.Cu")
		(net "FPGA_MAC_PPSDIFF_OUT")
	)
	(segment
		(start 142.65159 107.7912)
		(end 143.1216 107.7912)
		(width 0.2032)
		(layer "F.Cu")
		(net "FPGA_MAC_PPSDIFF_OUT")
	)
	(segment
		(start 146.4966 103.3162)
		(end 146.4966 102.6412)
		(width 0.2032)
		(layer "F.Cu")
		(net "FPGA_MAC_PPS_DIFF_IN0")
	)
	(segment
		(start 131.7916 90.9162)
		(end 133.71103 90.9162)
		(width 0.2032)
		(layer "F.Cu")
		(net "FPGA_MAC_PPS_DIFF_IN0")
	)
	(segment
		(start 133.9518 101.5464)
		(end 133.9518 91.15697)
		(width 0.2032)
		(layer "F.Cu")
		(net "FPGA_MAC_PPS_DIFF_IN0")
	)
	(segment
		(start 131.3566 90.4812)
		(end 131.3566 88.7162)
		(width 0.2032)
		(layer "F.Cu")
		(net "FPGA_MAC_PPS_DIFF_IN0")
	)
	(segment
		(start 131.3566 90.4812)
		(end 131.7916 90.9162)
		(width 0.2032)
		(layer "F.Cu")
		(net "FPGA_MAC_PPS_DIFF_IN0")
	)
	(segment
		(start 133.71103 90.9162)
		(end 133.9518 91.15697)
		(width 0.2032)
		(layer "F.Cu")
		(net "FPGA_MAC_PPS_DIFF_IN0")
	)
	(segment
		(start 144.2216 107.7412)
		(end 145.2966 107.7412)
		(width 0.2032)
		(layer "F.Cu")
		(net "FPGA_MAC_PPS_DIFF_IN0")
	)
	(segment
		(start 145.2966 107.7412)
		(end 145.6216 107.4162)
		(width 0.2032)
		(layer "F.Cu")
		(net "FPGA_MAC_PPS_DIFF_IN0")
	)
	(segment
		(start 133.9518 101.5464)
		(end 138.4216 106.0162)
		(width 0.2032)
		(layer "F.Cu")
		(net "FPGA_MAC_PPS_DIFF_IN0")
	)
	(via
		(at 131.3566 90.4812)
		(size 0.4064)
		(drill 0.2032)
		(layers "F.Cu" "B.Cu")
		(net "FPGA_MAC_PPS_DIFF_IN0")
	)
	(via
		(at 146.4966 102.6412)
		(size 0.4064)
		(drill 0.2032)
		(layers "F.Cu" "B.Cu")
		(net "FPGA_MAC_PPS_DIFF_IN0")
	)
	(via
		(at 138.4216 106.0162)
		(size 0.4064)
		(drill 0.2032)
		(layers "F.Cu" "B.Cu")
		(net "FPGA_MAC_PPS_DIFF_IN0")
	)
	(via
		(at 145.6216 107.4162)
		(size 0.4064)
		(drill 0.2032)
		(layers "F.Cu" "B.Cu")
		(net "FPGA_MAC_PPS_DIFF_IN0")
	)
	(segment
		(start 131.3641 90.4737)
		(end 131.3641 88.6237)
		(width 0.2032)
		(layer "B.Cu")
		(net "FPGA_MAC_PPS_DIFF_IN0")
	)
	(segment
		(start 138.4216 106.0162)
		(end 139.8216 107.4162)
		(width 0.2032)
		(layer "B.Cu")
		(net "FPGA_MAC_PPS_DIFF_IN0")
	)
	(segment
		(start 131.3641 88.6237)
		(end 131.3716 88.6162)
		(width 0.2032)
		(layer "B.Cu")
		(net "FPGA_MAC_PPS_DIFF_IN0")
	)
	(segment
		(start 131.3566 90.4812)
		(end 131.3641 90.4737)
		(width 0.2032)
		(layer "B.Cu")
		(net "FPGA_MAC_PPS_DIFF_IN0")
	)
	(segment
		(start 146.8216 106.2162)
		(end 146.8216 104.55872)
		(width 0.2032)
		(layer "B.Cu")
		(net "FPGA_MAC_PPS_DIFF_IN0")
	)
	(segment
		(start 145.6216 107.4162)
		(end 146.8216 106.2162)
		(width 0.2032)
		(layer "B.Cu")
		(net "FPGA_MAC_PPS_DIFF_IN0")
	)
	(segment
		(start 146.4966 104.23372)
		(end 146.8216 104.55872)
		(width 0.2032)
		(layer "B.Cu")
		(net "FPGA_MAC_PPS_DIFF_IN0")
	)
	(segment
		(start 146.4966 104.23372)
		(end 146.4966 102.6412)
		(width 0.2032)
		(layer "B.Cu")
		(net "FPGA_MAC_PPS_DIFF_IN0")
	)
	(segment
		(start 139.8216 107.4162)
		(end 145.6216 107.4162)
		(width 0.2032)
		(layer "B.Cu")
		(net "FPGA_MAC_PPS_DIFF_IN0")
	)
	(segment
		(start 220.74519 107.55822)
		(end 221.8216 108.63462)
		(width 0.2032)
		(layer "F.Cu")
		(net "DIP_SW_UART_SEL")
	)
	(segment
		(start 210.4914 100.5464)
		(end 218.1518 100.5464)
		(width 0.2032)
		(layer "F.Cu")
		(net "DIP_SW_UART_SEL")
	)
	(segment
		(start 207.9216 106.1162)
		(end 207.9216 105.4162)
		(width 0.2032)
		(layer "F.Cu")
		(net "DIP_SW_UART_SEL")
	)
	(segment
		(start 220.8534 105.69368)
		(end 220.8534 103.248)
		(width 0.2032)
		(layer "F.Cu")
		(net "DIP_SW_UART_SEL")
	)
	(segment
		(start 207.2216 104.7162)
		(end 207.2216 103.8162)
		(width 0.2032)
		(layer "F.Cu")
		(net "DIP_SW_UART_SEL")
	)
	(segment
		(start 218.1518 100.5464)
		(end 220.8534 103.248)
		(width 0.2032)
		(layer "F.Cu")
		(net "DIP_SW_UART_SEL")
	)
	(segment
		(start 152.21629 131.17151)
		(end 152.8716 130.5162)
		(width 0.2032)
		(layer "F.Cu")
		(net "DIP_SW_UART_SEL")
	)
	(segment
		(start 157.6716 131.16345)
		(end 157.6716 130.3162)
		(width 0.2032)
		(layer "F.Cu")
		(net "DIP_SW_UART_SEL")
	)
	(segment
		(start 220.74519 105.80188)
		(end 220.8534 105.69368)
		(width 0.2032)
		(layer "F.Cu")
		(net "DIP_SW_UART_SEL")
	)
	(segment
		(start 205.6216 108.4162)
		(end 207.9216 106.1162)
		(width 0.2032)
		(layer "F.Cu")
		(net "DIP_SW_UART_SEL")
	)
	(segment
		(start 220.74519 107.55822)
		(end 220.74519 105.80188)
		(width 0.2032)
		(layer "F.Cu")
		(net "DIP_SW_UART_SEL")
	)
	(segment
		(start 158.38899 121.88359)
		(end 177.0542 121.88359)
		(width 0.2032)
		(layer "F.Cu")
		(net "DIP_SW_UART_SEL")
	)
	(segment
		(start 221.8216 109.2162)
		(end 222.23785 108.79995)
		(width 0.2032)
		(layer "F.Cu")
		(net "DIP_SW_UART_SEL")
	)
	(segment
		(start 195.01472 116.4162)
		(end 203.01472 108.4162)
		(width 0.2032)
		(layer "F.Cu")
		(net "DIP_SW_UART_SEL")
	)
	(segment
		(start 152.3716 128.2162)
		(end 153.0716 128.9162)
		(width 0.2032)
		(layer "F.Cu")
		(net "DIP_SW_UART_SEL")
	)
	(segment
		(start 157.6216 128.4662)
		(end 157.6216 127.8162)
		(width 0.2032)
		(layer "F.Cu")
		(net "DIP_SW_UART_SEL")
	)
	(segment
		(start 203.01472 108.4162)
		(end 205.6216 108.4162)
		(width 0.2032)
		(layer "F.Cu")
		(net "DIP_SW_UART_SEL")
	)
	(segment
		(start 207.2216 104.7162)
		(end 207.9216 105.4162)
		(width 0.2032)
		(layer "F.Cu")
		(net "DIP_SW_UART_SEL")
	)
	(segment
		(start 157.6216 128.4662)
		(end 157.8716 128.7162)
		(width 0.2032)
		(layer "F.Cu")
		(net "DIP_SW_UART_SEL")
	)
	(segment
		(start 157.8216 121.3162)
		(end 158.38899 121.88359)
		(width 0.2032)
		(layer "F.Cu")
		(net "DIP_SW_UART_SEL")
	)
	(segment
		(start 207.2216 103.8162)
		(end 210.4914 100.5464)
		(width 0.2032)
		(layer "F.Cu")
		(net "DIP_SW_UART_SEL")
	)
	(segment
		(start 221.8216 109.2162)
		(end 221.8216 108.63462)
		(width 0.2032)
		(layer "F.Cu")
		(net "DIP_SW_UART_SEL")
	)
	(segment
		(start 177.0542 121.88359)
		(end 181.1216 117.8162)
		(width 0.2032)
		(layer "F.Cu")
		(net "DIP_SW_UART_SEL")
	)
	(segment
		(start 222.23785 108.79995)
		(end 223.26084 108.79995)
		(width 0.2032)
		(layer "F.Cu")
		(net "DIP_SW_UART_SEL")
	)
	(via
		(at 157.8216 121.3162)
		(size 0.4064)
		(drill 0.2032)
		(layers "F.Cu" "B.Cu")
		(net "DIP_SW_UART_SEL")
	)
	(via
		(at 157.6216 127.8162)
		(size 0.4064)
		(drill 0.2032)
		(layers "F.Cu" "B.Cu")
		(net "DIP_SW_UART_SEL")
	)
	(via
		(at 157.6716 131.16345)
		(size 0.4064)
		(drill 0.2032)
		(layers "F.Cu" "B.Cu")
		(net "DIP_SW_UART_SEL")
	)
	(via
		(at 152.21629 131.17151)
		(size 0.4064)
		(drill 0.2032)
		(layers "F.Cu" "B.Cu")
		(net "DIP_SW_UART_SEL")
	)
	(via
		(at 181.1216 117.8162)
		(size 0.4064)
		(drill 0.2032)
		(layers "F.Cu" "B.Cu")
		(net "DIP_SW_UART_SEL")
	)
	(via
		(at 195.01472 116.4162)
		(size 0.4064)
		(drill 0.2032)
		(layers "F.Cu" "B.Cu")
		(net "DIP_SW_UART_SEL")
	)
	(via
		(at 152.3716 128.2162)
		(size 0.4064)
		(drill 0.2032)
		(layers "F.Cu" "B.Cu")
		(net "DIP_SW_UART_SEL")
	)
	(via
		(at 221.8216 109.2162)
		(size 0.4064)
		(drill 0.2032)
		(layers "F.Cu" "B.Cu")
		(net "DIP_SW_UART_SEL")
	)
	(segment
		(start 220.7966 110.0412)
		(end 220.7966 109.5162)
		(width 0.2032)
		(layer "B.Cu")
		(net "DIP_SW_UART_SEL")
	)
	(segment
		(start 157.6716 131.16345)
		(end 158.05132 131.54317)
		(width 0.2032)
		(layer "B.Cu")
		(net "DIP_SW_UART_SEL")
	)
	(segment
		(start 218.8216 116.7162)
		(end 219.0966 116.9912)
		(width 0.2032)
		(layer "B.Cu")
		(net "DIP_SW_UART_SEL")
	)
	(segment
		(start 182.5216 116.4162)
		(end 195.01472 116.4162)
		(width 0.2032)
		(layer "B.Cu")
		(net "DIP_SW_UART_SEL")
	)
	(segment
		(start 152.19461 131.17151)
		(end 152.19461 131.14983)
		(width 0.2032)
		(layer "B.Cu")
		(net "DIP_SW_UART_SEL")
	)
	(segment
		(start 155.68123 130.60915)
		(end 156.23553 131.16345)
		(width 0.2032)
		(layer "B.Cu")
		(net "DIP_SW_UART_SEL")
	)
	(segment
		(start 221.46661 109.5162)
		(end 221.76661 109.2162)
		(width 0.2032)
		(layer "B.Cu")
		(net "DIP_SW_UART_SEL")
	)
	(segment
		(start 156.23553 131.16345)
		(end 157.6716 131.16345)
		(width 0.2032)
		(layer "B.Cu")
		(net "DIP_SW_UART_SEL")
	)
	(segment
		(start 151.59911 130.55433)
		(end 151.59911 128.98869)
		(width 0.2032)
		(layer "B.Cu")
		(net "DIP_SW_UART_SEL")
	)
	(segment
		(start 151.59911 128.98869)
		(end 152.3716 128.2162)
		(width 0.2032)
		(layer "B.Cu")
		(net "DIP_SW_UART_SEL")
	)
	(segment
		(start 218.8216 112.0162)
		(end 220.7966 110.0412)
		(width 0.2032)
		(layer "B.Cu")
		(net "DIP_SW_UART_SEL")
	)
	(segment
		(start 159.88279 132.73203)
		(end 160.18674 132.73203)
		(width 0.2032)
		(layer "B.Cu")
		(net "DIP_SW_UART_SEL")
	)
	(segment
		(start 161.1466 131.77217)
		(end 161.1466 128.98119)
		(width 0.2032)
		(layer "B.Cu")
		(net "DIP_SW_UART_SEL")
	)
	(segment
		(start 160.18674 132.73203)
		(end 161.1466 131.77217)
		(width 0.2032)
		(layer "B.Cu")
		(net "DIP_SW_UART_SEL")
	)
	(segment
		(start 151.59911 130.55433)
		(end 152.19461 131.14983)
		(width 0.2032)
		(layer "B.Cu")
		(net "DIP_SW_UART_SEL")
	)
	(segment
		(start 152.19461 131.17151)
		(end 152.21629 131.17151)
		(width 0.2032)
		(layer "B.Cu")
		(net "DIP_SW_UART_SEL")
	)
	(segment
		(start 152.77864 130.60915)
		(end 155.68123 130.60915)
		(width 0.2032)
		(layer "B.Cu")
		(net "DIP_SW_UART_SEL")
	)
	(segment
		(start 157.6216 127.76121)
		(end 157.8216 127.56121)
		(width 0.2032)
		(layer "B.Cu")
		(net "DIP_SW_UART_SEL")
	)
	(segment
		(start 152.21629 131.17151)
		(end 152.77864 130.60915)
		(width 0.2032)
		(layer "B.Cu")
		(net "DIP_SW_UART_SEL")
	)
	(segment
		(start 218.8216 116.7162)
		(end 218.8216 112.0162)
		(width 0.2032)
		(layer "B.Cu")
		(net "DIP_SW_UART_SEL")
	)
	(segment
		(start 158.06414 128.25874)
		(end 160.42415 128.25874)
		(width 0.2032)
		(layer "B.Cu")
		(net "DIP_SW_UART_SEL")
	)
	(segment
		(start 219.0966 116.9912)
		(end 219.9216 116.9912)
		(width 0.2032)
		(layer "B.Cu")
		(net "DIP_SW_UART_SEL")
	)
	(segment
		(start 157.6216 127.8162)
		(end 158.06414 128.25874)
		(width 0.2032)
		(layer "B.Cu")
		(net "DIP_SW_UART_SEL")
	)
	(segment
		(start 181.1216 117.8162)
		(end 182.5216 116.4162)
		(width 0.2032)
		(layer "B.Cu")
		(net "DIP_SW_UART_SEL")
	)
	(segment
		(start 157.6216 127.8162)
		(end 157.6216 127.76121)
		(width 0.2032)
		(layer "B.Cu")
		(net "DIP_SW_UART_SEL")
	)
	(segment
		(start 158.69392 131.54317)
		(end 159.88279 132.73203)
		(width 0.2032)
		(layer "B.Cu")
		(net "DIP_SW_UART_SEL")
	)
	(segment
		(start 158.05132 131.54317)
		(end 158.69392 131.54317)
		(width 0.2032)
		(layer "B.Cu")
		(net "DIP_SW_UART_SEL")
	)
	(segment
		(start 221.76661 109.2162)
		(end 221.8216 109.2162)
		(width 0.2032)
		(layer "B.Cu")
		(net "DIP_SW_UART_SEL")
	)
	(segment
		(start 220.7966 109.5162)
		(end 221.46661 109.5162)
		(width 0.2032)
		(layer "B.Cu")
		(net "DIP_SW_UART_SEL")
	)
	(segment
		(start 160.42415 128.25874)
		(end 161.1466 128.98119)
		(width 0.2032)
		(layer "B.Cu")
		(net "DIP_SW_UART_SEL")
	)
	(segment
		(start 157.8216 127.56121)
		(end 157.8216 121.3162)
		(width 0.2032)
		(layer "B.Cu")
		(net "DIP_SW_UART_SEL")
	)
	(segment
		(start 158.4216 118.23248)
		(end 159.3216 117.33248)
		(width 0.2032)
		(layer "F.Cu")
		(net "DIP_SW_PPS_SEL")
	)
	(segment
		(start 157.2898 112.7844)
		(end 159.3216 114.8162)
		(width 0.2032)
		(layer "F.Cu")
		(net "DIP_SW_PPS_SEL")
	)
	(segment
		(start 148.85449 110.84909)
		(end 153.98199 110.84909)
		(width 0.2032)
		(layer "F.Cu")
		(net "DIP_SW_PPS_SEL")
	)
	(segment
		(start 155.9173 112.7844)
		(end 157.2898 112.7844)
		(width 0.2032)
		(layer "F.Cu")
		(net "DIP_SW_PPS_SEL")
	)
	(segment
		(start 221.70785 107.55751)
		(end 221.70785 107.52995)
		(width 0.2032)
		(layer "F.Cu")
		(net "DIP_SW_PPS_SEL")
	)
	(segment
		(start 142.1216 105.8162)
		(end 142.7716 105.1662)
		(width 0.2032)
		(layer "F.Cu")
		(net "DIP_SW_PPS_SEL")
	)
	(segment
		(start 144.9716 105.3662)
		(end 145.6216 106.0162)
		(width 0.2032)
		(layer "F.Cu")
		(net "DIP_SW_PPS_SEL")
	)
	(segment
		(start 202.78029 107.55751)
		(end 205.89982 107.55751)
		(width 0.2032)
		(layer "F.Cu")
		(net "DIP_SW_PPS_SEL")
	)
	(segment
		(start 142.7716 105.1662)
		(end 142.9216 105.1662)
		(width 0.2032)
		(layer "F.Cu")
		(net "DIP_SW_PPS_SEL")
	)
	(segment
		(start 179.78843 115.9162)
		(end 182.4216 115.9162)
		(width 0.2032)
		(layer "F.Cu")
		(net "DIP_SW_PPS_SEL")
	)
	(segment
		(start 153.98199 110.84909)
		(end 155.9173 112.7844)
		(width 0.2032)
		(layer "F.Cu")
		(net "DIP_SW_PPS_SEL")
	)
	(segment
		(start 158.4216 120.1162)
		(end 159.3216 121.0162)
		(width 0.2032)
		(layer "F.Cu")
		(net "DIP_SW_PPS_SEL")
	)
	(segment
		(start 181.3518 125.43523)
		(end 181.47083 125.3162)
		(width 0.2032)
		(layer "F.Cu")
		(net "DIP_SW_PPS_SEL")
	)
	(segment
		(start 206.8216 103.7162)
		(end 210.3216 100.2162)
		(width 0.2032)
		(layer "F.Cu")
		(net "DIP_SW_PPS_SEL")
	)
	(segment
		(start 210.3216 100.2162)
		(end 218.4216 100.2162)
		(width 0.2032)
		(layer "F.Cu")
		(net "DIP_SW_PPS_SEL")
	)
	(segment
		(start 221.70785 107.52995)
		(end 223.26084 107.52995)
		(width 0.2032)
		(layer "F.Cu")
		(net "DIP_SW_PPS_SEL")
	)
	(segment
		(start 187.5914 132.46663)
		(end 187.5914 131.51962)
		(width 0.2032)
		(layer "F.Cu")
		(net "DIP_SW_PPS_SEL")
	)
	(segment
		(start 206.8216 104.9162)
		(end 206.8216 103.7162)
		(width 0.2032)
		(layer "F.Cu")
		(net "DIP_SW_PPS_SEL")
	)
	(segment
		(start 207.5216 105.93573)
		(end 207.5216 105.6162)
		(width 0.2032)
		(layer "F.Cu")
		(net "DIP_SW_PPS_SEL")
	)
	(segment
		(start 190.6216 126.1162)
		(end 190.6216 115.6162)
		(width 0.2032)
		(layer "F.Cu")
		(net "DIP_SW_PPS_SEL")
	)
	(segment
		(start 158.4216 120.1162)
		(end 158.4216 118.23248)
		(width 0.2032)
		(layer "F.Cu")
		(net "DIP_SW_PPS_SEL")
	)
	(segment
		(start 181.3518 131.5464)
		(end 182.4216 132.6162)
		(width 0.2032)
		(layer "F.Cu")
		(net "DIP_SW_PPS_SEL")
	)
	(segment
		(start 187.5914 131.51962)
		(end 189.23802 129.873)
		(width 0.2032)
		(layer "F.Cu")
		(net "DIP_SW_PPS_SEL")
	)
	(segment
		(start 181.47083 125.3162)
		(end 182.4216 125.3162)
		(width 0.2032)
		(layer "F.Cu")
		(net "DIP_SW_PPS_SEL")
	)
	(segment
		(start 182.4216 132.6162)
		(end 187.44183 132.6162)
		(width 0.2032)
		(layer "F.Cu")
		(net "DIP_SW_PPS_SEL")
	)
	(segment
		(start 221.3216 106.66624)
		(end 221.3216 103.1162)
		(width 0.2032)
		(layer "F.Cu")
		(net "DIP_SW_PPS_SEL")
	)
	(segment
		(start 177.98857 118.54923)
		(end 177.98857 116.78542)
		(width 0.2032)
		(layer "F.Cu")
		(net "DIP_SW_PPS_SEL")
	)
	(segment
		(start 187.44183 132.6162)
		(end 187.5914 132.46663)
		(width 0.2032)
		(layer "F.Cu")
		(net "DIP_SW_PPS_SEL")
	)
	(segment
		(start 221.70487 107.55454)
		(end 221.70487 107.04951)
		(width 0.2032)
		(layer "F.Cu")
		(net "DIP_SW_PPS_SEL")
	)
	(segment
		(start 144.5216 105.3662)
		(end 144.9716 105.3662)
		(width 0.2032)
		(layer "F.Cu")
		(net "DIP_SW_PPS_SEL")
	)
	(segment
		(start 146.35537 108.34997)
		(end 148.85449 110.84909)
		(width 0.2032)
		(layer "F.Cu")
		(net "DIP_SW_PPS_SEL")
	)
	(segment
		(start 189.23802 127.49977)
		(end 190.6216 126.1162)
		(width 0.2032)
		(layer "F.Cu")
		(net "DIP_SW_PPS_SEL")
	)
	(segment
		(start 177.98857 116.78542)
		(end 178.91921 116.78542)
		(width 0.2032)
		(layer "F.Cu")
		(net "DIP_SW_PPS_SEL")
	)
	(segment
		(start 199.36814 110.96966)
		(end 202.78029 107.55751)
		(width 0.2032)
		(layer "F.Cu")
		(net "DIP_SW_PPS_SEL")
	)
	(segment
		(start 205.89982 107.55751)
		(end 207.5216 105.93573)
		(width 0.2032)
		(layer "F.Cu")
		(net "DIP_SW_PPS_SEL")
	)
	(segment
		(start 178.91921 116.78542)
		(end 179.78843 115.9162)
		(width 0.2032)
		(layer "F.Cu")
		(net "DIP_SW_PPS_SEL")
	)
	(segment
		(start 221.3216 106.66624)
		(end 221.70487 107.04951)
		(width 0.2032)
		(layer "F.Cu")
		(net "DIP_SW_PPS_SEL")
	)
	(segment
		(start 159.3216 117.33248)
		(end 159.3216 114.8162)
		(width 0.2032)
		(layer "F.Cu")
		(net "DIP_SW_PPS_SEL")
	)
	(segment
		(start 221.70487 107.55454)
		(end 221.70785 107.55751)
		(width 0.2032)
		(layer "F.Cu")
		(net "DIP_SW_PPS_SEL")
	)
	(segment
		(start 159.3216 121.0162)
		(end 175.5216 121.0162)
		(width 0.2032)
		(layer "F.Cu")
		(net "DIP_SW_PPS_SEL")
	)
	(segment
		(start 189.23802 129.873)
		(end 189.23802 127.49977)
		(width 0.2032)
		(layer "F.Cu")
		(net "DIP_SW_PPS_SEL")
	)
	(segment
		(start 218.4216 100.2162)
		(end 221.3216 103.1162)
		(width 0.2032)
		(layer "F.Cu")
		(net "DIP_SW_PPS_SEL")
	)
	(segment
		(start 206.8216 104.9162)
		(end 207.5216 105.6162)
		(width 0.2032)
		(layer "F.Cu")
		(net "DIP_SW_PPS_SEL")
	)
	(segment
		(start 181.3518 131.5464)
		(end 181.3518 125.43523)
		(width 0.2032)
		(layer "F.Cu")
		(net "DIP_SW_PPS_SEL")
	)
	(segment
		(start 146.35537 108.34997)
		(end 146.35537 106.0162)
		(width 0.2032)
		(layer "F.Cu")
		(net "DIP_SW_PPS_SEL")
	)
	(segment
		(start 145.6216 106.0162)
		(end 146.35537 106.0162)
		(width 0.2032)
		(layer "F.Cu")
		(net "DIP_SW_PPS_SEL")
	)
	(segment
		(start 175.5216 121.0162)
		(end 177.98857 118.54923)
		(width 0.2032)
		(layer "F.Cu")
		(net "DIP_SW_PPS_SEL")
	)
	(segment
		(start 182.4216 125.3162)
		(end 182.4216 115.9162)
		(width 0.2032)
		(layer "F.Cu")
		(net "DIP_SW_PPS_SEL")
	)
	(segment
		(start 190.6216 115.6162)
		(end 196.1216 110.1162)
		(width 0.2032)
		(layer "F.Cu")
		(net "DIP_SW_PPS_SEL")
	)
	(via
		(at 142.1216 105.8162)
		(size 0.4064)
		(drill 0.2032)
		(layers "F.Cu" "B.Cu")
		(net "DIP_SW_PPS_SEL")
	)
	(via
		(at 221.70785 107.55751)
		(size 0.4064)
		(drill 0.2032)
		(layers "F.Cu" "B.Cu")
		(net "DIP_SW_PPS_SEL")
	)
	(via
		(at 199.36814 110.96966)
		(size 0.4064)
		(drill 0.2032)
		(layers "F.Cu" "B.Cu")
		(net "DIP_SW_PPS_SEL")
	)
	(via
		(at 196.1216 110.1162)
		(size 0.4064)
		(drill 0.2032)
		(layers "F.Cu" "B.Cu")
		(net "DIP_SW_PPS_SEL")
	)
	(via
		(at 145.6216 106.0162)
		(size 0.4064)
		(drill 0.2032)
		(layers "F.Cu" "B.Cu")
		(net "DIP_SW_PPS_SEL")
	)
	(segment
		(start 219.7716 111.87686)
		(end 222.35266 109.2958)
		(width 0.2032)
		(layer "B.Cu")
		(net "DIP_SW_PPS_SEL")
	)
	(segment
		(start 142.1216 105.8162)
		(end 143.22429 106.91889)
		(width 0.2032)
		(layer "B.Cu")
		(net "DIP_SW_PPS_SEL")
	)
	(segment
		(start 219.7716 113.3162)
		(end 220.6216 114.1662)
		(width 0.2032)
		(layer "B.Cu")
		(net "DIP_SW_PPS_SEL")
	)
	(segment
		(start 196.1216 110.1162)
		(end 196.97506 110.96966)
		(width 0.2032)
		(layer "B.Cu")
		(net "DIP_SW_PPS_SEL")
	)
	(segment
		(start 219.7716 113.3162)
		(end 219.7716 111.87686)
		(width 0.2032)
		(layer "B.Cu")
		(net "DIP_SW_PPS_SEL")
	)
	(segment
		(start 221.70785 107.60245)
		(end 222.35266 108.24726)
		(width 0.2032)
		(layer "B.Cu")
		(net "DIP_SW_PPS_SEL")
	)
	(segment
		(start 220.7966 107.6162)
		(end 220.82594 107.58685)
		(width 0.2032)
		(layer "B.Cu")
		(net "DIP_SW_PPS_SEL")
	)
	(segment
		(start 144.71891 106.91889)
		(end 145.6216 106.0162)
		(width 0.2032)
		(layer "B.Cu")
		(net "DIP_SW_PPS_SEL")
	)
	(segment
		(start 143.22429 106.91889)
		(end 144.71891 106.91889)
		(width 0.2032)
		(layer "B.Cu")
		(net "DIP_SW_PPS_SEL")
	)
	(segment
		(start 222.35266 109.2958)
		(end 222.35266 108.24726)
		(width 0.2032)
		(layer "B.Cu")
		(net "DIP_SW_PPS_SEL")
	)
	(segment
		(start 196.97506 110.96966)
		(end 199.36814 110.96966)
		(width 0.2032)
		(layer "B.Cu")
		(net "DIP_SW_PPS_SEL")
	)
	(segment
		(start 220.82594 107.58685)
		(end 221.67851 107.58685)
		(width 0.2032)
		(layer "B.Cu")
		(net "DIP_SW_PPS_SEL")
	)
	(segment
		(start 221.70785 107.60245)
		(end 221.70785 107.55751)
		(width 0.2032)
		(layer "B.Cu")
		(net "DIP_SW_PPS_SEL")
	)
	(segment
		(start 166.88457 91.6162)
		(end 166.88457 89.2162)
		(width 0.2032)
		(layer "F.Cu")
		(net "P3V3_SENSE")
	)
	(segment
		(start 172.0216 91.6162)
		(end 172.0216 87.4162)
		(width 0.2032)
		(layer "F.Cu")
		(net "P3V3_SENSE")
	)
	(segment
		(start 172.0216 87.4162)
		(end 172.7216 87.4162)
		(width 0.2032)
		(layer "F.Cu")
		(net "P3V3_SENSE")
	)
	(segment
		(start 166.88457 91.6162)
		(end 172.0216 91.6162)
		(width 0.2032)
		(layer "F.Cu")
		(net "P3V3_SENSE")
	)
	(via
		(at 173.9716 87.40011)
		(size 0.4064)
		(drill 0.2032)
		(layers "F.Cu" "B.Cu")
		(net "P3V3_SENSE")
	)
	(segment
		(start 173.9716 88.1162)
		(end 173.9716 87.40011)
		(width 0.2032)
		(layer "B.Cu")
		(net "P3V3_SENSE")
	)
	(segment
		(start 166.88457 94.6162)
		(end 166.9216 94.6162)
		(width 0.2032)
		(layer "F.Cu")
		(net "NetR80_1")
	)
	(segment
		(start 166.9216 96.4162)
		(end 166.9216 94.6162)
		(width 0.2032)
		(layer "F.Cu")
		(net "NetR80_1")
	)
	(via
		(at 166.9216 96.4162)
		(size 0.4064)
		(drill 0.2032)
		(layers "F.Cu" "B.Cu")
		(net "NetR80_1")
	)
	(segment
		(start 166.88457 95.0162)
		(end 166.9216 95.0162)
		(width 0.2032)
		(layer "B.Cu")
		(net "NetR80_1")
	)
	(segment
		(start 166.9216 96.4162)
		(end 166.9216 95.0162)
		(width 0.2032)
		(layer "B.Cu")
		(net "NetR80_1")
	)
	(segment
		(start 168.2216 96.2162)
		(end 168.2216 94.6162)
		(width 0.2032)
		(layer "F.Cu")
		(net "NetR79_1")
	)
	(segment
		(start 168.15457 94.6162)
		(end 168.2216 94.6162)
		(width 0.2032)
		(layer "F.Cu")
		(net "NetR79_1")
	)
	(via
		(at 168.2216 96.2162)
		(size 0.4064)
		(drill 0.2032)
		(layers "F.Cu" "B.Cu")
		(net "NetR79_1")
	)
	(segment
		(start 168.2216 96.2162)
		(end 168.2216 95.0162)
		(width 0.2032)
		(layer "B.Cu")
		(net "NetR79_1")
	)
	(segment
		(start 168.15457 95.0162)
		(end 168.2216 95.0162)
		(width 0.2032)
		(layer "B.Cu")
		(net "NetR79_1")
	)
	(segment
		(start 174.7216 88.0162)
		(end 175.8216 88.0162)
		(width 0.2032)
		(layer "B.Cu")
		(net "NetR67_2")
	)
	(segment
		(start 174.7216 88.1162)
		(end 174.7216 88.0162)
		(width 0.2032)
		(layer "B.Cu")
		(net "NetR67_2")
	)
	(segment
		(start 81.6216 66.12847)
		(end 83.5116 66.12847)
		(width 0.254)
		(layer "F.Cu")
		(net "NetR66_1")
	)
	(via
		(at 81.6216 66.12847)
		(size 0.4064)
		(drill 0.2032)
		(layers "F.Cu" "B.Cu")
		(net "NetR66_1")
	)
	(segment
		(start 81.6216 66.12847)
		(end 83.1116 66.12847)
		(width 0.254)
		(layer "B.Cu")
		(net "NetR66_1")
	)
	(segment
		(start 81.8706 67.39847)
		(end 83.5116 67.39847)
		(width 0.254)
		(layer "F.Cu")
		(net "NetR65_1")
	)
	(via
		(at 81.8706 67.39847)
		(size 0.4064)
		(drill 0.2032)
		(layers "F.Cu" "B.Cu")
		(net "NetR65_1")
	)
	(segment
		(start 81.8706 67.39847)
		(end 83.1116 67.39847)
		(width 0.254)
		(layer "B.Cu")
		(net "NetR65_1")
	)
	(segment
		(start 224.11548 76.31732)
		(end 224.1166 76.3162)
		(width 0.254)
		(layer "F.Cu")
		(net "NetR64_1")
	)
	(segment
		(start 224.11548 77.5401)
		(end 224.11548 76.31732)
		(width 0.254)
		(layer "F.Cu")
		(net "NetR64_1")
	)
	(segment
		(start 224.11436 77.54122)
		(end 224.11548 77.5401)
		(width 0.254)
		(layer "F.Cu")
		(net "NetR64_1")
	)
	(via
		(at 224.11436 77.54122)
		(size 0.4064)
		(drill 0.2032)
		(layers "F.Cu" "B.Cu")
		(net "NetR64_1")
	)
	(segment
		(start 224.11798 77.5376)
		(end 224.11798 76.21982)
		(width 0.254)
		(layer "B.Cu")
		(net "NetR64_1")
	)
	(segment
		(start 224.11436 77.54122)
		(end 224.11798 77.5376)
		(width 0.254)
		(layer "B.Cu")
		(net "NetR64_1")
	)
	(segment
		(start 224.11798 76.21982)
		(end 224.1216 76.2162)
		(width 0.254)
		(layer "B.Cu")
		(net "NetR64_1")
	)
	(segment
		(start 225.4041 77.3987)
		(end 225.4041 76.3337)
		(width 0.254)
		(layer "F.Cu")
		(net "NetR62_1")
	)
	(segment
		(start 225.3866 76.3162)
		(end 225.4041 76.3337)
		(width 0.254)
		(layer "F.Cu")
		(net "NetR62_1")
	)
	(segment
		(start 225.4041 77.3987)
		(end 225.4216 77.4162)
		(width 0.254)
		(layer "F.Cu")
		(net "NetR62_1")
	)
	(via
		(at 225.4216 77.4162)
		(size 0.4064)
		(drill 0.2032)
		(layers "F.Cu" "B.Cu")
		(net "NetR62_1")
	)
	(segment
		(start 225.39787 77.39247)
		(end 225.4216 77.4162)
		(width 0.254)
		(layer "B.Cu")
		(net "NetR62_1")
	)
	(segment
		(start 225.39787 77.39247)
		(end 225.39787 76.22394)
		(width 0.254)
		(layer "B.Cu")
		(net "NetR62_1")
	)
	(segment
		(start 225.37414 76.20021)
		(end 225.39787 76.22394)
		(width 0.254)
		(layer "B.Cu")
		(net "NetR62_1")
	)
	(segment
		(start 100.5966 62.8162)
		(end 100.5966 61.6162)
		(width 0.254)
		(layer "B.Cu")
		(net "NetR2_2")
	)
	(segment
		(start 100.3216 61.6162)
		(end 100.5966 61.6162)
		(width 0.254)
		(layer "B.Cu")
		(net "NetR2_2")
	)
	(segment
		(start 88.9116 66.12847)
		(end 91.6966 66.12847)
		(width 0.254)
		(layer "F.Cu")
		(net "P5V_SENSE")
	)
	(segment
		(start 91.6966 66.12847)
		(end 91.6966 65.3162)
		(width 0.254)
		(layer "F.Cu")
		(net "P5V_SENSE")
	)
	(via
		(at 97.6216 62.8162)
		(size 0.4064)
		(drill 0.2032)
		(layers "F.Cu" "B.Cu")
		(net "P5V_SENSE")
	)
	(segment
		(start 97.6216 62.8162)
		(end 99.8466 62.8162)
		(width 0.2032)
		(layer "B.Cu")
		(net "P5V_SENSE")
	)
	(segment
		(start 186.8216 75.7162)
		(end 190.91945 75.7162)
		(width 0.2032)
		(layer "F.Cu")
		(net "NetD20_1")
	)
	(segment
		(start 186.8216 75.7162)
		(end 186.8216 74.5162)
		(width 0.2032)
		(layer "F.Cu")
		(net "NetD20_1")
	)
	(segment
		(start 186.8216 74.5162)
		(end 187.06945 74.26835)
		(width 0.2032)
		(layer "F.Cu")
		(net "NetD20_1")
	)
	(segment
		(start 190.91945 75.7162)
		(end 190.91945 74.5162)
		(width 0.2032)
		(layer "F.Cu")
		(net "NetD20_1")
	)
	(segment
		(start 221.9216 70.9162)
		(end 221.9216 68.4162)
		(width 0.254)
		(layer "F.Cu")
		(net "+12V_SENS")
	)
	(segment
		(start 221.9216 70.9162)
		(end 224.1166 70.9162)
		(width 0.254)
		(layer "F.Cu")
		(net "+12V_SENS")
	)
	(segment
		(start 111.05269 86.02803)
		(end 112.00639 86.02803)
		(width 0.254)
		(layer "F.Cu")
		(net "NetR58_2")
	)
	(segment
		(start 112.00639 86.02803)
		(end 112.01823 86.0162)
		(width 0.254)
		(layer "F.Cu")
		(net "NetR58_2")
	)
	(segment
		(start 111.04086 86.03986)
		(end 111.05269 86.02803)
		(width 0.254)
		(layer "F.Cu")
		(net "NetR58_2")
	)
	(via
		(at 111.04086 86.03986)
		(size 0.4064)
		(drill 0.2032)
		(layers "F.Cu" "B.Cu")
		(net "NetR58_2")
	)
	(segment
		(start 112.13622 86.0107)
		(end 112.18072 85.9662)
		(width 0.254)
		(layer "B.Cu")
		(net "NetR58_2")
	)
	(segment
		(start 111.07002 86.0107)
		(end 112.13622 86.0107)
		(width 0.254)
		(layer "B.Cu")
		(net "NetR58_2")
	)
	(segment
		(start 111.04086 86.03986)
		(end 111.07002 86.0107)
		(width 0.254)
		(layer "B.Cu")
		(net "NetR58_2")
	)
	(segment
		(start 110.30572 85.5412)
		(end 111.99323 85.5412)
		(width 0.254)
		(layer "F.Cu")
		(net "NetR57_2")
	)
	(segment
		(start 111.99323 85.5412)
		(end 112.01823 85.5162)
		(width 0.254)
		(layer "F.Cu")
		(net "NetR57_2")
	)
	(segment
		(start 110.28072 85.5662)
		(end 110.30572 85.5412)
		(width 0.254)
		(layer "F.Cu")
		(net "NetR57_2")
	)
	(via
		(at 110.28072 85.5662)
		(size 0.4064)
		(drill 0.2032)
		(layers "F.Cu" "B.Cu")
		(net "NetR57_2")
	)
	(segment
		(start 110.28072 85.5662)
		(end 111.32473 85.5662)
		(width 0.254)
		(layer "B.Cu")
		(net "NetR57_2")
	)
	(segment
		(start 111.64972 85.2412)
		(end 112.25573 85.2412)
		(width 0.254)
		(layer "B.Cu")
		(net "NetR57_2")
	)
	(segment
		(start 111.32473 85.5662)
		(end 111.64972 85.2412)
		(width 0.254)
		(layer "B.Cu")
		(net "NetR57_2")
	)
	(segment
		(start 111.33984 87.0162)
		(end 112.01823 87.0162)
		(width 0.254)
		(layer "F.Cu")
		(net "NetR55_2")
	)
	(segment
		(start 110.28072 87.4662)
		(end 110.88984 87.4662)
		(width 0.254)
		(layer "F.Cu")
		(net "NetR55_2")
	)
	(segment
		(start 110.88984 87.4662)
		(end 111.33984 87.0162)
		(width 0.254)
		(layer "F.Cu")
		(net "NetR55_2")
	)
	(via
		(at 110.28072 87.4662)
		(size 0.4064)
		(drill 0.2032)
		(layers "F.Cu" "B.Cu")
		(net "NetR55_2")
	)
	(segment
		(start 112.51093 87.3452)
		(end 112.69054 87.16559)
		(width 0.254)
		(layer "B.Cu")
		(net "NetR55_2")
	)
	(segment
		(start 110.44296 87.3452)
		(end 112.51093 87.3452)
		(width 0.254)
		(layer "B.Cu")
		(net "NetR55_2")
	)
	(segment
		(start 112.69054 87.16559)
		(end 112.69054 87.15638)
		(width 0.254)
		(layer "B.Cu")
		(net "NetR55_2")
	)
	(segment
		(start 110.28072 87.4662)
		(end 110.32196 87.4662)
		(width 0.254)
		(layer "B.Cu")
		(net "NetR55_2")
	)
	(segment
		(start 112.69054 87.15638)
		(end 112.98073 86.8662)
		(width 0.254)
		(layer "B.Cu")
		(net "NetR55_2")
	)
	(segment
		(start 110.32196 87.4662)
		(end 110.44296 87.3452)
		(width 0.254)
		(layer "B.Cu")
		(net "NetR55_2")
	)
	(segment
		(start 113.33072 90.67722)
		(end 113.33072 89.5787)
		(width 0.2032)
		(layer "F.Cu")
		(net "NetR53_1")
	)
	(via
		(at 113.33072 90.67722)
		(size 0.4064)
		(drill 0.2032)
		(layers "F.Cu" "B.Cu")
		(net "NetR53_1")
	)
	(segment
		(start 113.33072 90.67722)
		(end 113.35573 90.65222)
		(width 0.2032)
		(layer "B.Cu")
		(net "NetR53_1")
	)
	(segment
		(start 112.48073 89.7662)
		(end 113.38072 89.7662)
		(width 0.2032)
		(layer "B.Cu")
		(net "NetR53_1")
	)
	(segment
		(start 113.35573 89.7912)
		(end 113.38072 89.7662)
		(width 0.2032)
		(layer "B.Cu")
		(net "NetR53_1")
	)
	(segment
		(start 113.35573 90.65222)
		(end 113.35573 89.7912)
		(width 0.2032)
		(layer "B.Cu")
		(net "NetR53_1")
	)
	(segment
		(start 112.28072 89.9662)
		(end 112.48073 89.7662)
		(width 0.2032)
		(layer "B.Cu")
		(net "NetR53_1")
	)
	(segment
		(start 111.94482 87.5896)
		(end 112.01823 87.5162)
		(width 0.2032)
		(layer "F.Cu")
		(net "NetR52_1")
	)
	(segment
		(start 111.55732 87.5896)
		(end 111.94482 87.5896)
		(width 0.2032)
		(layer "F.Cu")
		(net "NetR52_1")
	)
	(segment
		(start 110.38072 88.2662)
		(end 110.88072 88.2662)
		(width 0.2032)
		(layer "F.Cu")
		(net "NetR52_1")
	)
	(segment
		(start 110.88072 88.2662)
		(end 111.55732 87.5896)
		(width 0.2032)
		(layer "F.Cu")
		(net "NetR52_1")
	)
	(via
		(at 110.38072 88.2662)
		(size 0.4064)
		(drill 0.2032)
		(layers "F.Cu" "B.Cu")
		(net "NetR52_1")
	)
	(via
		(at 117.38072 89.8662)
		(size 0.4064)
		(drill 0.2032)
		(layers "F.Cu" "B.Cu")
		(net "NetR52_1")
	)
	(segment
		(start 116.78072 89.2662)
		(end 117.38072 89.8662)
		(width 0.2032)
		(layer "B.Cu")
		(net "NetR52_1")
	)
	(segment
		(start 118.18072 89.45707)
		(end 118.18072 88.15715)
		(width 0.2032)
		(layer "B.Cu")
		(net "NetR52_1")
	)
	(segment
		(start 115.38072 89.2662)
		(end 116.78072 89.2662)
		(width 0.2032)
		(layer "B.Cu")
		(net "NetR52_1")
	)
	(segment
		(start 117.4196 89.82732)
		(end 117.81048 89.82732)
		(width 0.2032)
		(layer "B.Cu")
		(net "NetR52_1")
	)
	(segment
		(start 110.4216 84.5162)
		(end 110.4216 83.6162)
		(width 0.2032)
		(layer "B.Cu")
		(net "NetR52_1")
	)
	(segment
		(start 115.2216 82.4162)
		(end 117.3216 84.5162)
		(width 0.2032)
		(layer "B.Cu")
		(net "NetR52_1")
	)
	(segment
		(start 117.3216 87.29802)
		(end 118.18072 88.15715)
		(width 0.2032)
		(layer "B.Cu")
		(net "NetR52_1")
	)
	(segment
		(start 110.4216 83.6162)
		(end 111.1216 82.9162)
		(width 0.2032)
		(layer "B.Cu")
		(net "NetR52_1")
	)
	(segment
		(start 110.78072 87.8662)
		(end 112.08072 87.8662)
		(width 0.2032)
		(layer "B.Cu")
		(net "NetR52_1")
	)
	(segment
		(start 117.3216 87.29802)
		(end 117.3216 84.5162)
		(width 0.2032)
		(layer "B.Cu")
		(net "NetR52_1")
	)
	(segment
		(start 109.6216 87.50708)
		(end 109.6216 85.3162)
		(width 0.2032)
		(layer "B.Cu")
		(net "NetR52_1")
	)
	(segment
		(start 113.23225 82.9162)
		(end 113.73226 82.4162)
		(width 0.2032)
		(layer "B.Cu")
		(net "NetR52_1")
	)
	(segment
		(start 111.1216 82.9162)
		(end 113.23225 82.9162)
		(width 0.2032)
		(layer "B.Cu")
		(net "NetR52_1")
	)
	(segment
		(start 109.6216 85.3162)
		(end 110.4216 84.5162)
		(width 0.2032)
		(layer "B.Cu")
		(net "NetR52_1")
	)
	(segment
		(start 109.6216 87.50708)
		(end 110.38072 88.2662)
		(width 0.2032)
		(layer "B.Cu")
		(net "NetR52_1")
	)
	(segment
		(start 110.38072 88.2662)
		(end 110.78072 87.8662)
		(width 0.2032)
		(layer "B.Cu")
		(net "NetR52_1")
	)
	(segment
		(start 113.78072 87.6662)
		(end 115.38072 89.2662)
		(width 0.2032)
		(layer "B.Cu")
		(net "NetR52_1")
	)
	(segment
		(start 113.73226 82.4162)
		(end 115.2216 82.4162)
		(width 0.2032)
		(layer "B.Cu")
		(net "NetR52_1")
	)
	(segment
		(start 117.81048 89.82732)
		(end 118.18072 89.45707)
		(width 0.2032)
		(layer "B.Cu")
		(net "NetR52_1")
	)
	(segment
		(start 117.38072 89.8662)
		(end 117.4196 89.82732)
		(width 0.2032)
		(layer "B.Cu")
		(net "NetR52_1")
	)
	(segment
		(start 113.33072 84.9537)
		(end 113.33072 84.2162)
		(width 0.254)
		(layer "F.Cu")
		(net "NetR51_2")
	)
	(segment
		(start 112.78072 83.6662)
		(end 113.33072 84.2162)
		(width 0.254)
		(layer "F.Cu")
		(net "NetR51_2")
	)
	(via
		(at 112.78072 83.6662)
		(size 0.4064)
		(drill 0.2032)
		(layers "F.Cu" "B.Cu")
		(net "NetR51_2")
	)
	(segment
		(start 113.16707 84.98575)
		(end 113.16707 84.09378)
		(width 0.254)
		(layer "B.Cu")
		(net "NetR51_2")
	)
	(segment
		(start 112.78072 83.70744)
		(end 113.16707 84.09378)
		(width 0.254)
		(layer "B.Cu")
		(net "NetR51_2")
	)
	(segment
		(start 112.78072 83.70744)
		(end 112.78072 83.6662)
		(width 0.254)
		(layer "B.Cu")
		(net "NetR51_2")
	)
	(segment
		(start 111.10928 86.5162)
		(end 112.01823 86.5162)
		(width 0.254)
		(layer "F.Cu")
		(net "NetC65_1")
	)
	(segment
		(start 110.95928 86.6662)
		(end 111.10928 86.5162)
		(width 0.254)
		(layer "F.Cu")
		(net "NetC65_1")
	)
	(via
		(at 110.95928 86.6662)
		(size 0.4064)
		(drill 0.2032)
		(layers "F.Cu" "B.Cu")
		(net "NetC65_1")
	)
	(segment
		(start 118.08072 87.7162)
		(end 118.48072 87.7162)
		(width 0.2032)
		(layer "F.Cu")
		(net "BNO_XOUT32")
	)
	(segment
		(start 118.18072 88.8662)
		(end 118.18072 88.0162)
		(width 0.2032)
		(layer "F.Cu")
		(net "BNO_XOUT32")
	)
	(segment
		(start 116.88072 86.5162)
		(end 118.08072 87.7162)
		(width 0.2032)
		(layer "F.Cu")
		(net "BNO_XOUT32")
	)
	(segment
		(start 118.18072 88.0162)
		(end 118.48072 87.7162)
		(width 0.2032)
		(layer "F.Cu")
		(net "BNO_XOUT32")
	)
	(segment
		(start 115.14322 86.5162)
		(end 116.88072 86.5162)
		(width 0.2032)
		(layer "F.Cu")
		(net "BNO_XOUT32")
	)
	(segment
		(start 118.48072 87.7162)
		(end 119.92072 87.7162)
		(width 0.2032)
		(layer "F.Cu")
		(net "BNO_XOUT32")
	)
	(segment
		(start 119.92072 87.7162)
		(end 120.18072 87.4562)
		(width 0.2032)
		(layer "F.Cu")
		(net "BNO_XOUT32")
	)
	(segment
		(start 118.08072 85.2162)
		(end 118.48072 85.2162)
		(width 0.2032)
		(layer "F.Cu")
		(net "BNO_XIN32")
	)
	(segment
		(start 118.48072 85.2162)
		(end 118.92912 85.6646)
		(width 0.2032)
		(layer "F.Cu")
		(net "BNO_XIN32")
	)
	(segment
		(start 118.18072 84.9162)
		(end 118.48072 85.2162)
		(width 0.2032)
		(layer "F.Cu")
		(net "BNO_XIN32")
	)
	(segment
		(start 119.86912 85.6646)
		(end 120.18072 85.9762)
		(width 0.2032)
		(layer "F.Cu")
		(net "BNO_XIN32")
	)
	(segment
		(start 117.28072 86.0162)
		(end 118.08072 85.2162)
		(width 0.2032)
		(layer "F.Cu")
		(net "BNO_XIN32")
	)
	(segment
		(start 118.18072 84.9162)
		(end 118.18072 83.9662)
		(width 0.2032)
		(layer "F.Cu")
		(net "BNO_XIN32")
	)
	(segment
		(start 118.92912 85.6646)
		(end 119.86912 85.6646)
		(width 0.2032)
		(layer "F.Cu")
		(net "BNO_XIN32")
	)
	(segment
		(start 115.14322 86.0162)
		(end 117.28072 86.0162)
		(width 0.2032)
		(layer "F.Cu")
		(net "BNO_XIN32")
	)
	(segment
		(start 111.94482 89.0896)
		(end 112.01823 89.0162)
		(width 0.2032)
		(layer "F.Cu")
		(net "BNO_INT")
	)
	(segment
		(start 111.28431 89.51433)
		(end 111.70904 89.0896)
		(width 0.2032)
		(layer "F.Cu")
		(net "BNO_INT")
	)
	(segment
		(start 111.70904 89.0896)
		(end 111.94482 89.0896)
		(width 0.2032)
		(layer "F.Cu")
		(net "BNO_INT")
	)
	(segment
		(start 110.58026 90.67732)
		(end 111.28431 89.97327)
		(width 0.2032)
		(layer "F.Cu")
		(net "BNO_INT")
	)
	(segment
		(start 110.3216 90.7162)
		(end 110.36048 90.67732)
		(width 0.2032)
		(layer "F.Cu")
		(net "BNO_INT")
	)
	(segment
		(start 167.04902 106.64985)
		(end 167.04902 103.31041)
		(width 0.2032)
		(layer "F.Cu")
		(net "BNO_INT")
	)
	(segment
		(start 110.36048 90.67732)
		(end 110.58026 90.67732)
		(width 0.2032)
		(layer "F.Cu")
		(net "BNO_INT")
	)
	(segment
		(start 111.28431 89.97327)
		(end 111.28431 89.51433)
		(width 0.2032)
		(layer "F.Cu")
		(net "BNO_INT")
	)
	(via
		(at 110.3216 90.7162)
		(size 0.4064)
		(drill 0.2032)
		(layers "F.Cu" "B.Cu")
		(net "BNO_INT")
	)
	(via
		(at 167.04902 106.64985)
		(size 0.4064)
		(drill 0.2032)
		(layers "F.Cu" "B.Cu")
		(net "BNO_INT")
	)
	(segment
		(start 110.24892 90.18214)
		(end 110.28272 90.21593)
		(width 0.2032)
		(layer "B.Cu")
		(net "BNO_INT")
	)
	(segment
		(start 110.28272 90.67732)
		(end 110.28272 90.21593)
		(width 0.2032)
		(layer "B.Cu")
		(net "BNO_INT")
	)
	(segment
		(start 111.01071 88.6912)
		(end 111.85572 88.6912)
		(width 0.2032)
		(layer "B.Cu")
		(net "BNO_INT")
	)
	(segment
		(start 110.28272 90.67732)
		(end 110.3216 90.7162)
		(width 0.2032)
		(layer "B.Cu")
		(net "BNO_INT")
	)
	(segment
		(start 110.24892 90.18214)
		(end 110.24892 89.45299)
		(width 0.2032)
		(layer "B.Cu")
		(net "BNO_INT")
	)
	(segment
		(start 110.24892 89.45299)
		(end 111.01071 88.6912)
		(width 0.2032)
		(layer "B.Cu")
		(net "BNO_INT")
	)
	(segment
		(start 130.1216 117.3162)
		(end 131.4216 117.3162)
		(width 0.2032)
		(layer "In2.Cu")
		(net "BNO_INT")
	)
	(segment
		(start 163.45525 106.64985)
		(end 167.04902 106.64985)
		(width 0.2032)
		(layer "In2.Cu")
		(net "BNO_INT")
	)
	(segment
		(start 162.9216 106.1162)
		(end 163.45525 106.64985)
		(width 0.2032)
		(layer "In2.Cu")
		(net "BNO_INT")
	)
	(segment
		(start 143.2029 99.5162)
		(end 158.54891 99.5162)
		(width 0.2032)
		(layer "In2.Cu")
		(net "BNO_INT")
	)
	(segment
		(start 162.9216 106.1162)
		(end 162.9216 103.43256)
		(width 0.2032)
		(layer "In2.Cu")
		(net "BNO_INT")
	)
	(segment
		(start 135.1216 107.5975)
		(end 143.2029 99.5162)
		(width 0.2032)
		(layer "In2.Cu")
		(net "BNO_INT")
	)
	(segment
		(start 110.3216 90.7162)
		(end 111.30447 91.69907)
		(width 0.2032)
		(layer "In2.Cu")
		(net "BNO_INT")
	)
	(segment
		(start 161.09465 101.1162)
		(end 161.6216 101.64314)
		(width 0.2032)
		(layer "In2.Cu")
		(net "BNO_INT")
	)
	(segment
		(start 113.64246 91.69907)
		(end 119.7216 97.7782)
		(width 0.2032)
		(layer "In2.Cu")
		(net "BNO_INT")
	)
	(segment
		(start 158.54891 99.5162)
		(end 160.14891 101.1162)
		(width 0.2032)
		(layer "In2.Cu")
		(net "BNO_INT")
	)
	(segment
		(start 131.4216 117.3162)
		(end 135.1216 113.6162)
		(width 0.2032)
		(layer "In2.Cu")
		(net "BNO_INT")
	)
	(segment
		(start 111.30447 91.69907)
		(end 113.64246 91.69907)
		(width 0.2032)
		(layer "In2.Cu")
		(net "BNO_INT")
	)
	(segment
		(start 160.14891 101.1162)
		(end 161.09465 101.1162)
		(width 0.2032)
		(layer "In2.Cu")
		(net "BNO_INT")
	)
	(segment
		(start 119.7216 106.9162)
		(end 119.7216 97.7782)
		(width 0.2032)
		(layer "In2.Cu")
		(net "BNO_INT")
	)
	(segment
		(start 135.1216 113.6162)
		(end 135.1216 107.5975)
		(width 0.2032)
		(layer "In2.Cu")
		(net "BNO_INT")
	)
	(segment
		(start 161.6216 102.13256)
		(end 162.9216 103.43256)
		(width 0.2032)
		(layer "In2.Cu")
		(net "BNO_INT")
	)
	(segment
		(start 119.7216 106.9162)
		(end 130.1216 117.3162)
		(width 0.2032)
		(layer "In2.Cu")
		(net "BNO_INT")
	)
	(segment
		(start 161.6216 102.13256)
		(end 161.6216 101.64314)
		(width 0.2032)
		(layer "In2.Cu")
		(net "BNO_INT")
	)
	(segment
		(start 206.7216 121.7662)
		(end 206.7216 117.4412)
		(width 0.2032)
		(layer "F.Cu")
		(net "GPS2_PIN15")
	)
	(segment
		(start 167.54889 105.33202)
		(end 167.54889 103.31041)
		(width 0.2032)
		(layer "F.Cu")
		(net "GPS2_PIN15")
	)
	(segment
		(start 200.49576 138.6612)
		(end 200.5592 138.6612)
		(width 0.2032)
		(layer "F.Cu")
		(net "GPS2_PIN15")
	)
	(segment
		(start 200.49576 140.46942)
		(end 200.49576 138.6612)
		(width 0.2032)
		(layer "F.Cu")
		(net "GPS2_PIN15")
	)
	(segment
		(start 206.7216 117.4412)
		(end 208.4216 117.4412)
		(width 0.2032)
		(layer "F.Cu")
		(net "GPS2_PIN15")
	)
	(via
		(at 200.49576 140.46942)
		(size 0.4064)
		(drill 0.2032)
		(layers "F.Cu" "B.Cu")
		(net "GPS2_PIN15")
	)
	(via
		(at 167.54889 105.33202)
		(size 0.4064)
		(drill 0.2032)
		(layers "F.Cu" "B.Cu")
		(net "GPS2_PIN15")
	)
	(via
		(at 208.4216 117.4412)
		(size 0.4064)
		(drill 0.2032)
		(layers "F.Cu" "B.Cu")
		(net "GPS2_PIN15")
	)
	(segment
		(start 207.56672 117.4412)
		(end 208.4216 117.4412)
		(width 0.2032)
		(layer "B.Cu")
		(net "GPS2_PIN15")
	)
	(segment
		(start 164.8216 119.37875)
		(end 169.45905 124.0162)
		(width 0.2032)
		(layer "In3.Cu")
		(net "GPS2_PIN15")
	)
	(segment
		(start 164.8216 113.7162)
		(end 166.6216 111.9162)
		(width 0.2032)
		(layer "In3.Cu")
		(net "GPS2_PIN15")
	)
	(segment
		(start 167.54889 107.87116)
		(end 167.54889 105.33202)
		(width 0.2032)
		(layer "In3.Cu")
		(net "GPS2_PIN15")
	)
	(segment
		(start 201.8216 130.02472)
		(end 205.2216 126.62472)
		(width 0.2032)
		(layer "In3.Cu")
		(net "GPS2_PIN15")
	)
	(segment
		(start 201.8216 134.17208)
		(end 201.8216 130.02472)
		(width 0.2032)
		(layer "In3.Cu")
		(net "GPS2_PIN15")
	)
	(segment
		(start 200.0216 139.99527)
		(end 200.0216 135.97208)
		(width 0.2032)
		(layer "In3.Cu")
		(net "GPS2_PIN15")
	)
	(segment
		(start 200.0216 139.99527)
		(end 200.49576 140.46942)
		(width 0.2032)
		(layer "In3.Cu")
		(net "GPS2_PIN15")
	)
	(segment
		(start 200.0216 135.97208)
		(end 201.8216 134.17208)
		(width 0.2032)
		(layer "In3.Cu")
		(net "GPS2_PIN15")
	)
	(segment
		(start 199.10755 117.9162)
		(end 205.7216 117.9162)
		(width 0.2032)
		(layer "In3.Cu")
		(net "GPS2_PIN15")
	)
	(segment
		(start 192.0216 126.9162)
		(end 196.2716 126.9162)
		(width 0.2032)
		(layer "In3.Cu")
		(net "GPS2_PIN15")
	)
	(segment
		(start 205.7216 117.9162)
		(end 206.1966 117.4412)
		(width 0.2032)
		(layer "In3.Cu")
		(net "GPS2_PIN15")
	)
	(segment
		(start 206.1966 117.4412)
		(end 208.4216 117.4412)
		(width 0.2032)
		(layer "In3.Cu")
		(net "GPS2_PIN15")
	)
	(segment
		(start 166.6216 111.9162)
		(end 166.6216 108.79845)
		(width 0.2032)
		(layer "In3.Cu")
		(net "GPS2_PIN15")
	)
	(segment
		(start 164.8216 119.37875)
		(end 164.8216 113.7162)
		(width 0.2032)
		(layer "In3.Cu")
		(net "GPS2_PIN15")
	)
	(segment
		(start 196.48225 126.70555)
		(end 196.48225 120.54149)
		(width 0.2032)
		(layer "In3.Cu")
		(net "GPS2_PIN15")
	)
	(segment
		(start 205.2216 120.6412)
		(end 208.4216 117.4412)
		(width 0.2032)
		(layer "In3.Cu")
		(net "GPS2_PIN15")
	)
	(segment
		(start 189.1216 124.0162)
		(end 192.0216 126.9162)
		(width 0.2032)
		(layer "In3.Cu")
		(net "GPS2_PIN15")
	)
	(segment
		(start 196.48225 120.54149)
		(end 199.10755 117.9162)
		(width 0.2032)
		(layer "In3.Cu")
		(net "GPS2_PIN15")
	)
	(segment
		(start 205.2216 126.62472)
		(end 205.2216 120.6412)
		(width 0.2032)
		(layer "In3.Cu")
		(net "GPS2_PIN15")
	)
	(segment
		(start 196.2716 126.9162)
		(end 196.48225 126.70555)
		(width 0.2032)
		(layer "In3.Cu")
		(net "GPS2_PIN15")
	)
	(segment
		(start 169.45905 124.0162)
		(end 189.1216 124.0162)
		(width 0.2032)
		(layer "In3.Cu")
		(net "GPS2_PIN15")
	)
	(segment
		(start 166.6216 108.79845)
		(end 167.54889 107.87116)
		(width 0.2032)
		(layer "In3.Cu")
		(net "GPS2_PIN15")
	)
	(segment
		(start 170.54889 101.6162)
		(end 170.54889 99.26063)
		(width 0.2032)
		(layer "F.Cu")
		(net "GPS2_PIN14")
	)
	(segment
		(start 207.2216 121.7662)
		(end 207.2216 118.8412)
		(width 0.2032)
		(layer "F.Cu")
		(net "GPS2_PIN14")
	)
	(segment
		(start 202.52668 134.2162)
		(end 202.55919 134.2162)
		(width 0.2032)
		(layer "F.Cu")
		(net "GPS2_PIN14")
	)
	(segment
		(start 169.86048 101.87732)
		(end 170.28777 101.87732)
		(width 0.2032)
		(layer "F.Cu")
		(net "GPS2_PIN14")
	)
	(segment
		(start 202.52668 134.2162)
		(end 202.52668 132.05341)
		(width 0.2032)
		(layer "F.Cu")
		(net "GPS2_PIN14")
	)
	(segment
		(start 169.8216 101.9162)
		(end 169.86048 101.87732)
		(width 0.2032)
		(layer "F.Cu")
		(net "GPS2_PIN14")
	)
	(segment
		(start 170.28777 101.87732)
		(end 170.54889 101.6162)
		(width 0.2032)
		(layer "F.Cu")
		(net "GPS2_PIN14")
	)
	(segment
		(start 207.2216 118.8412)
		(end 209.0216 118.8412)
		(width 0.2032)
		(layer "F.Cu")
		(net "GPS2_PIN14")
	)
	(via
		(at 181.9216 119.8162)
		(size 0.4064)
		(drill 0.2032)
		(layers "F.Cu" "B.Cu")
		(net "GPS2_PIN14")
	)
	(via
		(at 209.0216 118.8412)
		(size 0.4064)
		(drill 0.2032)
		(layers "F.Cu" "B.Cu")
		(net "GPS2_PIN14")
	)
	(via
		(at 169.8216 101.9162)
		(size 0.4064)
		(drill 0.2032)
		(layers "F.Cu" "B.Cu")
		(net "GPS2_PIN14")
	)
	(via
		(at 202.52668 132.05341)
		(size 0.4064)
		(drill 0.2032)
		(layers "F.Cu" "B.Cu")
		(net "GPS2_PIN14")
	)
	(segment
		(start 208.07681 118.8412)
		(end 209.0216 118.8412)
		(width 0.2032)
		(layer "B.Cu")
		(net "GPS2_PIN14")
	)
	(segment
		(start 195.1216 123.5162)
		(end 201.84413 130.23872)
		(width 0.2032)
		(layer "B.Cu")
		(net "GPS2_PIN14")
	)
	(segment
		(start 183.20348 121.09808)
		(end 189.60348 121.09808)
		(width 0.2032)
		(layer "B.Cu")
		(net "GPS2_PIN14")
	)
	(segment
		(start 201.84413 131.37086)
		(end 201.84413 130.23872)
		(width 0.2032)
		(layer "B.Cu")
		(net "GPS2_PIN14")
	)
	(segment
		(start 192.0216 123.5162)
		(end 195.1216 123.5162)
		(width 0.2032)
		(layer "B.Cu")
		(net "GPS2_PIN14")
	)
	(segment
		(start 201.84413 131.37086)
		(end 202.52668 132.05341)
		(width 0.2032)
		(layer "B.Cu")
		(net "GPS2_PIN14")
	)
	(segment
		(start 189.60348 121.09808)
		(end 192.0216 123.5162)
		(width 0.2032)
		(layer "B.Cu")
		(net "GPS2_PIN14")
	)
	(segment
		(start 181.9216 119.8162)
		(end 183.20348 121.09808)
		(width 0.2032)
		(layer "B.Cu")
		(net "GPS2_PIN14")
	)
	(segment
		(start 181.85024 119.8162)
		(end 181.9216 119.8162)
		(width 0.2032)
		(layer "In3.Cu")
		(net "GPS2_PIN14")
	)
	(segment
		(start 169.8216 103.22685)
		(end 170.41263 103.81788)
		(width 0.2032)
		(layer "In3.Cu")
		(net "GPS2_PIN14")
	)
	(segment
		(start 179.3216 118.2162)
		(end 179.3216 111.4162)
		(width 0.2032)
		(layer "In3.Cu")
		(net "GPS2_PIN14")
	)
	(segment
		(start 202.52668 132.05341)
		(end 203.18947 132.7162)
		(width 0.2032)
		(layer "In3.Cu")
		(net "GPS2_PIN14")
	)
	(segment
		(start 170.41263 103.81788)
		(end 171.72328 103.81788)
		(width 0.2032)
		(layer "In3.Cu")
		(net "GPS2_PIN14")
	)
	(segment
		(start 209.0216 119.45384)
		(end 209.0216 118.8412)
		(width 0.2032)
		(layer "In3.Cu")
		(net "GPS2_PIN14")
	)
	(segment
		(start 205.70257 132.7162)
		(end 205.8216 132.59717)
		(width 0.2032)
		(layer "In3.Cu")
		(net "GPS2_PIN14")
	)
	(segment
		(start 179.3216 118.2162)
		(end 181.30175 120.19635)
		(width 0.2032)
		(layer "In3.Cu")
		(net "GPS2_PIN14")
	)
	(segment
		(start 171.72328 103.81788)
		(end 179.3216 111.4162)
		(width 0.2032)
		(layer "In3.Cu")
		(net "GPS2_PIN14")
	)
	(segment
		(start 203.18947 132.7162)
		(end 205.70257 132.7162)
		(width 0.2032)
		(layer "In3.Cu")
		(net "GPS2_PIN14")
	)
	(segment
		(start 169.8216 103.22685)
		(end 169.8216 101.9162)
		(width 0.2032)
		(layer "In3.Cu")
		(net "GPS2_PIN14")
	)
	(segment
		(start 205.8216 122.65384)
		(end 209.0216 119.45384)
		(width 0.2032)
		(layer "In3.Cu")
		(net "GPS2_PIN14")
	)
	(segment
		(start 181.30175 120.19635)
		(end 181.47009 120.19635)
		(width 0.2032)
		(layer "In3.Cu")
		(net "GPS2_PIN14")
	)
	(segment
		(start 181.47009 120.19635)
		(end 181.85024 119.8162)
		(width 0.2032)
		(layer "In3.Cu")
		(net "GPS2_PIN14")
	)
	(segment
		(start 205.8216 132.59717)
		(end 205.8216 122.65384)
		(width 0.2032)
		(layer "In3.Cu")
		(net "GPS2_PIN14")
	)
	(segment
		(start 169.54889 107.49214)
		(end 169.54889 103.31041)
		(width 0.2032)
		(layer "F.Cu")
		(net "GPS2_PIN13")
	)
	(segment
		(start 202.5216 140.5162)
		(end 202.5216 138.6612)
		(width 0.2032)
		(layer "F.Cu")
		(net "GPS2_PIN13")
	)
	(segment
		(start 207.7216 121.7662)
		(end 207.7216 120.1412)
		(width 0.2032)
		(layer "F.Cu")
		(net "GPS2_PIN13")
	)
	(segment
		(start 202.5216 138.6612)
		(end 202.55919 138.6612)
		(width 0.2032)
		(layer "F.Cu")
		(net "GPS2_PIN13")
	)
	(segment
		(start 207.7216 120.1412)
		(end 209.5216 120.1412)
		(width 0.2032)
		(layer "F.Cu")
		(net "GPS2_PIN13")
	)
	(via
		(at 202.5216 140.5162)
		(size 0.4064)
		(drill 0.2032)
		(layers "F.Cu" "B.Cu")
		(net "GPS2_PIN13")
	)
	(via
		(at 209.5216 120.1412)
		(size 0.4064)
		(drill 0.2032)
		(layers "F.Cu" "B.Cu")
		(net "GPS2_PIN13")
	)
	(via
		(at 169.54889 107.49214)
		(size 0.4064)
		(drill 0.2032)
		(layers "F.Cu" "B.Cu")
		(net "GPS2_PIN13")
	)
	(segment
		(start 208.37584 120.1412)
		(end 209.5216 120.1412)
		(width 0.2032)
		(layer "B.Cu")
		(net "GPS2_PIN13")
	)
	(segment
		(start 167.46285 121.11034)
		(end 169.45433 123.10182)
		(width 0.2032)
		(layer "In3.Cu")
		(net "GPS2_PIN13")
	)
	(segment
		(start 189.20722 123.10182)
		(end 190.03304 123.92764)
		(width 0.2032)
		(layer "In3.Cu")
		(net "GPS2_PIN13")
	)
	(segment
		(start 209.5216 120.1412)
		(end 209.5216 116.6162)
		(width 0.2032)
		(layer "In3.Cu")
		(net "GPS2_PIN13")
	)
	(segment
		(start 168.0216 109.01943)
		(end 169.54889 107.49214)
		(width 0.2032)
		(layer "In3.Cu")
		(net "GPS2_PIN13")
	)
	(segment
		(start 208.8216 130.8162)
		(end 209.33467 131.32927)
		(width 0.2032)
		(layer "In3.Cu")
		(net "GPS2_PIN13")
	)
	(segment
		(start 167.46285 121.11034)
		(end 167.46285 116.13077)
		(width 0.2032)
		(layer "In3.Cu")
		(net "GPS2_PIN13")
	)
	(segment
		(start 190.03304 123.92764)
		(end 192.61016 123.92764)
		(width 0.2032)
		(layer "In3.Cu")
		(net "GPS2_PIN13")
	)
	(segment
		(start 197.8216 115.8162)
		(end 208.7216 115.8162)
		(width 0.2032)
		(layer "In3.Cu")
		(net "GPS2_PIN13")
	)
	(segment
		(start 192.61016 123.92764)
		(end 194.68166 121.85614)
		(width 0.2032)
		(layer "In3.Cu")
		(net "GPS2_PIN13")
	)
	(segment
		(start 208.8216 130.8162)
		(end 208.8216 120.8412)
		(width 0.2032)
		(layer "In3.Cu")
		(net "GPS2_PIN13")
	)
	(segment
		(start 208.7216 115.8162)
		(end 209.5216 116.6162)
		(width 0.2032)
		(layer "In3.Cu")
		(net "GPS2_PIN13")
	)
	(segment
		(start 208.8216 120.8412)
		(end 209.5216 120.1412)
		(width 0.2032)
		(layer "In3.Cu")
		(net "GPS2_PIN13")
	)
	(segment
		(start 202.5216 140.5162)
		(end 209.33467 133.70313)
		(width 0.2032)
		(layer "In3.Cu")
		(net "GPS2_PIN13")
	)
	(segment
		(start 167.46285 116.13077)
		(end 168.0216 115.57202)
		(width 0.2032)
		(layer "In3.Cu")
		(net "GPS2_PIN13")
	)
	(segment
		(start 209.33467 133.70313)
		(end 209.33467 131.32927)
		(width 0.2032)
		(layer "In3.Cu")
		(net "GPS2_PIN13")
	)
	(segment
		(start 169.45433 123.10182)
		(end 189.20722 123.10182)
		(width 0.2032)
		(layer "In3.Cu")
		(net "GPS2_PIN13")
	)
	(segment
		(start 194.68166 118.95614)
		(end 197.8216 115.8162)
		(width 0.2032)
		(layer "In3.Cu")
		(net "GPS2_PIN13")
	)
	(segment
		(start 168.0216 115.57202)
		(end 168.0216 109.01943)
		(width 0.2032)
		(layer "In3.Cu")
		(net "GPS2_PIN13")
	)
	(segment
		(start 194.68166 121.85614)
		(end 194.68166 118.95614)
		(width 0.2032)
		(layer "In3.Cu")
		(net "GPS2_PIN13")
	)
	(segment
		(start 194.0216 126.0912)
		(end 194.7216 126.0912)
		(width 0.2032)
		(layer "F.Cu")
		(net "GPS2_PIN12")
	)
	(segment
		(start 170.04902 100.88878)
		(end 170.04902 99.26063)
		(width 0.2032)
		(layer "F.Cu")
		(net "GPS2_PIN12")
	)
	(segment
		(start 194.7216 126.0912)
		(end 195.5216 126.0912)
		(width 0.2032)
		(layer "F.Cu")
		(net "GPS2_PIN12")
	)
	(segment
		(start 169.1216 101.8162)
		(end 170.04902 100.88878)
		(width 0.2032)
		(layer "F.Cu")
		(net "GPS2_PIN12")
	)
	(via
		(at 178.5216 117.4162)
		(size 0.4064)
		(drill 0.2032)
		(layers "F.Cu" "B.Cu")
		(net "GPS2_PIN12")
	)
	(via
		(at 198.1216 117.1162)
		(size 0.4064)
		(drill 0.2032)
		(layers "F.Cu" "B.Cu")
		(net "GPS2_PIN12")
	)
	(via
		(at 169.1216 101.8162)
		(size 0.4064)
		(drill 0.2032)
		(layers "F.Cu" "B.Cu")
		(net "GPS2_PIN12")
	)
	(via
		(at 195.5216 126.0912)
		(size 0.4064)
		(drill 0.2032)
		(layers "F.Cu" "B.Cu")
		(net "GPS2_PIN12")
	)
	(segment
		(start 169.00119 103.10316)
		(end 169.1216 102.98275)
		(width 0.2032)
		(layer "B.Cu")
		(net "GPS2_PIN12")
	)
	(segment
		(start 168.72483 112.41943)
		(end 169.49798 113.19258)
		(width 0.2032)
		(layer "B.Cu")
		(net "GPS2_PIN12")
	)
	(segment
		(start 169.1216 102.98275)
		(end 169.1216 101.8162)
		(width 0.2032)
		(layer "B.Cu")
		(net "GPS2_PIN12")
	)
	(segment
		(start 169.00119 104.21472)
		(end 169.3216 104.53513)
		(width 0.2032)
		(layer "B.Cu")
		(net "GPS2_PIN12")
	)
	(segment
		(start 180.0216 115.9162)
		(end 195.5216 115.9162)
		(width 0.2032)
		(layer "B.Cu")
		(net "GPS2_PIN12")
	)
	(segment
		(start 178.5216 117.4162)
		(end 180.0216 115.9162)
		(width 0.2032)
		(layer "B.Cu")
		(net "GPS2_PIN12")
	)
	(segment
		(start 172.1216 120.6162)
		(end 173.2216 121.7162)
		(width 0.2032)
		(layer "B.Cu")
		(net "GPS2_PIN12")
	)
	(segment
		(start 178.5216 119.5162)
		(end 178.5216 117.4162)
		(width 0.2032)
		(layer "B.Cu")
		(net "GPS2_PIN12")
	)
	(segment
		(start 169.49798 113.19258)
		(end 172.00257 113.19258)
		(width 0.2032)
		(layer "B.Cu")
		(net "GPS2_PIN12")
	)
	(segment
		(start 168.72483 106.91297)
		(end 169.3216 106.3162)
		(width 0.2032)
		(layer "B.Cu")
		(net "GPS2_PIN12")
	)
	(segment
		(start 176.3216 121.7162)
		(end 178.5216 119.5162)
		(width 0.2032)
		(layer "B.Cu")
		(net "GPS2_PIN12")
	)
	(segment
		(start 172.1216 120.6162)
		(end 172.1216 113.31161)
		(width 0.2032)
		(layer "B.Cu")
		(net "GPS2_PIN12")
	)
	(segment
		(start 196.7216 117.1162)
		(end 198.1216 117.1162)
		(width 0.2032)
		(layer "B.Cu")
		(net "GPS2_PIN12")
	)
	(segment
		(start 169.3216 106.3162)
		(end 169.3216 104.53513)
		(width 0.2032)
		(layer "B.Cu")
		(net "GPS2_PIN12")
	)
	(segment
		(start 195.5216 115.9162)
		(end 196.7216 117.1162)
		(width 0.2032)
		(layer "B.Cu")
		(net "GPS2_PIN12")
	)
	(segment
		(start 173.2216 121.7162)
		(end 176.3216 121.7162)
		(width 0.2032)
		(layer "B.Cu")
		(net "GPS2_PIN12")
	)
	(segment
		(start 169.00119 104.21472)
		(end 169.00119 103.10316)
		(width 0.2032)
		(layer "B.Cu")
		(net "GPS2_PIN12")
	)
	(segment
		(start 172.00257 113.19258)
		(end 172.1216 113.31161)
		(width 0.2032)
		(layer "B.Cu")
		(net "GPS2_PIN12")
	)
	(segment
		(start 168.72483 112.41943)
		(end 168.72483 106.91297)
		(width 0.2032)
		(layer "B.Cu")
		(net "GPS2_PIN12")
	)
	(segment
		(start 195.1898 124.07088)
		(end 195.1898 119.66703)
		(width 0.2032)
		(layer "In3.Cu")
		(net "GPS2_PIN12")
	)
	(segment
		(start 195.6898 119.548)
		(end 198.1216 117.1162)
		(width 0.2032)
		(layer "In3.Cu")
		(net "GPS2_PIN12")
	)
	(segment
		(start 195.5216 126.0912)
		(end 195.5216 124.40268)
		(width 0.2032)
		(layer "In3.Cu")
		(net "GPS2_PIN12")
	)
	(segment
		(start 195.30883 119.548)
		(end 195.6898 119.548)
		(width 0.2032)
		(layer "In3.Cu")
		(net "GPS2_PIN12")
	)
	(segment
		(start 195.1898 119.66703)
		(end 195.30883 119.548)
		(width 0.2032)
		(layer "In3.Cu")
		(net "GPS2_PIN12")
	)
	(segment
		(start 195.1898 124.07088)
		(end 195.5216 124.40268)
		(width 0.2032)
		(layer "In3.Cu")
		(net "GPS2_PIN12")
	)
	(segment
		(start 193.2216 119.6412)
		(end 194.8216 119.6412)
		(width 0.2032)
		(layer "F.Cu")
		(net "GPS2_PIN11")
	)
	(segment
		(start 194.8216 119.6412)
		(end 195.9216 119.6412)
		(width 0.2032)
		(layer "F.Cu")
		(net "GPS2_PIN11")
	)
	(segment
		(start 170.04902 106.5411)
		(end 170.04902 103.31041)
		(width 0.2032)
		(layer "F.Cu")
		(net "GPS2_PIN11")
	)
	(via
		(at 170.04902 106.5411)
		(size 0.4064)
		(drill 0.2032)
		(layers "F.Cu" "B.Cu")
		(net "GPS2_PIN11")
	)
	(via
		(at 193.2216 119.6412)
		(size 0.4064)
		(drill 0.2032)
		(layers "F.Cu" "B.Cu")
		(net "GPS2_PIN11")
	)
	(segment
		(start 177.5216 117.7162)
		(end 180.65354 120.84814)
		(width 0.2032)
		(layer "In3.Cu")
		(net "GPS2_PIN11")
	)
	(segment
		(start 173.73973 117.7162)
		(end 177.5216 117.7162)
		(width 0.2032)
		(layer "In3.Cu")
		(net "GPS2_PIN11")
	)
	(segment
		(start 170.04902 111.96648)
		(end 171.8409 113.75837)
		(width 0.2032)
		(layer "In3.Cu")
		(net "GPS2_PIN11")
	)
	(segment
		(start 180.65354 120.84814)
		(end 189.63366 120.84814)
		(width 0.2032)
		(layer "In3.Cu")
		(net "GPS2_PIN11")
	)
	(segment
		(start 171.8409 115.81736)
		(end 173.73973 117.7162)
		(width 0.2032)
		(layer "In3.Cu")
		(net "GPS2_PIN11")
	)
	(segment
		(start 189.63366 120.84814)
		(end 190.84061 119.6412)
		(width 0.2032)
		(layer "In3.Cu")
		(net "GPS2_PIN11")
	)
	(segment
		(start 170.04902 111.96648)
		(end 170.04902 106.5411)
		(width 0.2032)
		(layer "In3.Cu")
		(net "GPS2_PIN11")
	)
	(segment
		(start 190.84061 119.6412)
		(end 193.2216 119.6412)
		(width 0.2032)
		(layer "In3.Cu")
		(net "GPS2_PIN11")
	)
	(segment
		(start 171.8409 115.81736)
		(end 171.8409 113.75837)
		(width 0.2032)
		(layer "In3.Cu")
		(net "GPS2_PIN11")
	)
	(segment
		(start 151.54893 103.96039)
		(end 151.54893 103.31041)
		(width 0.2032)
		(layer "F.Cu")
		(net "GPS1_PIN15")
	)
	(segment
		(start 150.66048 104.77732)
		(end 150.732 104.77732)
		(width 0.2032)
		(layer "F.Cu")
		(net "GPS1_PIN15")
	)
	(segment
		(start 104.4216 58.3162)
		(end 105.0266 58.92121)
		(width 0.2032)
		(layer "F.Cu")
		(net "GPS1_PIN15")
	)
	(segment
		(start 150.6216 104.8162)
		(end 150.66048 104.77732)
		(width 0.2032)
		(layer "F.Cu")
		(net "GPS1_PIN15")
	)
	(segment
		(start 123.8966 63.5162)
		(end 128.2216 63.5162)
		(width 0.2032)
		(layer "F.Cu")
		(net "GPS1_PIN15")
	)
	(segment
		(start 150.732 104.77732)
		(end 151.54893 103.96039)
		(width 0.2032)
		(layer "F.Cu")
		(net "GPS1_PIN15")
	)
	(segment
		(start 128.2216 65.2162)
		(end 128.2216 63.5162)
		(width 0.2032)
		(layer "F.Cu")
		(net "GPS1_PIN15")
	)
	(segment
		(start 105.0266 59.7286)
		(end 105.0266 58.92121)
		(width 0.2032)
		(layer "F.Cu")
		(net "GPS1_PIN15")
	)
	(via
		(at 128.2216 65.2162)
		(size 0.4064)
		(drill 0.2032)
		(layers "F.Cu" "B.Cu")
		(net "GPS1_PIN15")
	)
	(via
		(at 150.6216 104.8162)
		(size 0.4064)
		(drill 0.2032)
		(layers "F.Cu" "B.Cu")
		(net "GPS1_PIN15")
	)
	(via
		(at 152.84999 96.0762)
		(size 0.4064)
		(drill 0.2032)
		(layers "F.Cu" "B.Cu")
		(net "GPS1_PIN15")
	)
	(via
		(at 104.4216 58.3162)
		(size 0.4064)
		(drill 0.2032)
		(layers "F.Cu" "B.Cu")
		(net "GPS1_PIN15")
	)
	(segment
		(start 128.2216 65.2162)
		(end 128.2216 64.25316)
		(width 0.2032)
		(layer "B.Cu")
		(net "GPS1_PIN15")
	)
	(segment
		(start 149.6216 96.5162)
		(end 150.60216 95.53564)
		(width 0.2032)
		(layer "B.Cu")
		(net "GPS1_PIN15")
	)
	(segment
		(start 149.6216 103.8162)
		(end 149.6216 96.5162)
		(width 0.2032)
		(layer "B.Cu")
		(net "GPS1_PIN15")
	)
	(segment
		(start 149.6216 103.8162)
		(end 150.6216 104.8162)
		(width 0.2032)
		(layer "B.Cu")
		(net "GPS1_PIN15")
	)
	(segment
		(start 152.30943 95.53564)
		(end 152.84999 96.0762)
		(width 0.2032)
		(layer "B.Cu")
		(net "GPS1_PIN15")
	)
	(segment
		(start 150.60216 95.53564)
		(end 152.30943 95.53564)
		(width 0.2032)
		(layer "B.Cu")
		(net "GPS1_PIN15")
	)
	(segment
		(start 125.1716 62.1662)
		(end 128.2216 65.2162)
		(width 0.2032)
		(layer "In3.Cu")
		(net "GPS1_PIN15")
	)
	(segment
		(start 151.58996 94.81617)
		(end 151.58996 94.64783)
		(width 0.2032)
		(layer "In3.Cu")
		(net "GPS1_PIN15")
	)
	(segment
		(start 151.58996 94.81617)
		(end 152.84999 96.0762)
		(width 0.2032)
		(layer "In3.Cu")
		(net "GPS1_PIN15")
	)
	(segment
		(start 138.0216 65.2162)
		(end 151.7216 78.9162)
		(width 0.2032)
		(layer "In3.Cu")
		(net "GPS1_PIN15")
	)
	(segment
		(start 108.27803 58.3162)
		(end 108.92862 58.96679)
		(width 0.2032)
		(layer "In3.Cu")
		(net "GPS1_PIN15")
	)
	(segment
		(start 151.58996 94.64783)
		(end 151.7216 94.5162)
		(width 0.2032)
		(layer "In3.Cu")
		(net "GPS1_PIN15")
	)
	(segment
		(start 104.4216 58.3162)
		(end 108.27803 58.3162)
		(width 0.2032)
		(layer "In3.Cu")
		(net "GPS1_PIN15")
	)
	(segment
		(start 151.7216 94.5162)
		(end 151.7216 78.9162)
		(width 0.2032)
		(layer "In3.Cu")
		(net "GPS1_PIN15")
	)
	(segment
		(start 108.92862 58.96679)
		(end 114.87219 58.96679)
		(width 0.2032)
		(layer "In3.Cu")
		(net "GPS1_PIN15")
	)
	(segment
		(start 128.2216 65.2162)
		(end 138.0216 65.2162)
		(width 0.2032)
		(layer "In3.Cu")
		(net "GPS1_PIN15")
	)
	(segment
		(start 118.0716 62.1662)
		(end 125.1716 62.1662)
		(width 0.2032)
		(layer "In3.Cu")
		(net "GPS1_PIN15")
	)
	(segment
		(start 114.87219 58.96679)
		(end 118.0716 62.1662)
		(width 0.2032)
		(layer "In3.Cu")
		(net "GPS1_PIN15")
	)
	(segment
		(start 152.04905 105.6162)
		(end 152.04905 103.31041)
		(width 0.2032)
		(layer "F.Cu")
		(net "GPS1_PIN14")
	)
	(segment
		(start 109.4716 61.7286)
		(end 111.57482 61.7286)
		(width 0.2032)
		(layer "F.Cu")
		(net "GPS1_PIN14")
	)
	(segment
		(start 123.8966 64.0162)
		(end 126.8216 64.0162)
		(width 0.2032)
		(layer "F.Cu")
		(net "GPS1_PIN14")
	)
	(segment
		(start 126.8216 65.8162)
		(end 126.8216 64.0162)
		(width 0.2032)
		(layer "F.Cu")
		(net "GPS1_PIN14")
	)
	(via
		(at 152.04905 105.6162)
		(size 0.4064)
		(drill 0.2032)
		(layers "F.Cu" "B.Cu")
		(net "GPS1_PIN14")
	)
	(via
		(at 111.57482 61.7286)
		(size 0.4064)
		(drill 0.2032)
		(layers "F.Cu" "B.Cu")
		(net "GPS1_PIN14")
	)
	(via
		(at 126.8216 65.8162)
		(size 0.4064)
		(drill 0.2032)
		(layers "F.Cu" "B.Cu")
		(net "GPS1_PIN14")
	)
	(via
		(at 151.84669 96.16174)
		(size 0.4064)
		(drill 0.2032)
		(layers "F.Cu" "B.Cu")
		(net "GPS1_PIN14")
	)
	(segment
		(start 150.22489 97.30225)
		(end 150.75037 96.77677)
		(width 0.2032)
		(layer "B.Cu")
		(net "GPS1_PIN14")
	)
	(segment
		(start 150.22489 102.71949)
		(end 152.04905 104.54365)
		(width 0.2032)
		(layer "B.Cu")
		(net "GPS1_PIN14")
	)
	(segment
		(start 151.23166 96.77677)
		(end 151.84669 96.16174)
		(width 0.2032)
		(layer "B.Cu")
		(net "GPS1_PIN14")
	)
	(segment
		(start 150.22489 102.71949)
		(end 150.22489 97.30225)
		(width 0.2032)
		(layer "B.Cu")
		(net "GPS1_PIN14")
	)
	(segment
		(start 152.04905 105.6162)
		(end 152.04905 104.54365)
		(width 0.2032)
		(layer "B.Cu")
		(net "GPS1_PIN14")
	)
	(segment
		(start 150.75037 96.77677)
		(end 151.23166 96.77677)
		(width 0.2032)
		(layer "B.Cu")
		(net "GPS1_PIN14")
	)
	(segment
		(start 126.8216 65.8162)
		(end 126.8216 64.84211)
		(width 0.2032)
		(layer "B.Cu")
		(net "GPS1_PIN14")
	)
	(segment
		(start 151.2518 95.56685)
		(end 151.84669 96.16174)
		(width 0.2032)
		(layer "In3.Cu")
		(net "GPS1_PIN14")
	)
	(segment
		(start 151.0216 94.9162)
		(end 151.0216 79.3162)
		(width 0.2032)
		(layer "In3.Cu")
		(net "GPS1_PIN14")
	)
	(segment
		(start 151.0216 94.9162)
		(end 151.2518 95.1464)
		(width 0.2032)
		(layer "In3.Cu")
		(net "GPS1_PIN14")
	)
	(segment
		(start 137.5216 65.8162)
		(end 151.0216 79.3162)
		(width 0.2032)
		(layer "In3.Cu")
		(net "GPS1_PIN14")
	)
	(segment
		(start 111.57482 61.7286)
		(end 112.434 61.7286)
		(width 0.2032)
		(layer "In3.Cu")
		(net "GPS1_PIN14")
	)
	(segment
		(start 126.0216 65.0162)
		(end 126.8216 65.8162)
		(width 0.2032)
		(layer "In3.Cu")
		(net "GPS1_PIN14")
	)
	(segment
		(start 126.8216 65.8162)
		(end 137.5216 65.8162)
		(width 0.2032)
		(layer "In3.Cu")
		(net "GPS1_PIN14")
	)
	(segment
		(start 151.2518 95.56685)
		(end 151.2518 95.1464)
		(width 0.2032)
		(layer "In3.Cu")
		(net "GPS1_PIN14")
	)
	(segment
		(start 112.434 61.7286)
		(end 113.3216 62.6162)
		(width 0.2032)
		(layer "In3.Cu")
		(net "GPS1_PIN14")
	)
	(segment
		(start 117.7216 62.6162)
		(end 120.1216 65.0162)
		(width 0.2032)
		(layer "In3.Cu")
		(net "GPS1_PIN14")
	)
	(segment
		(start 120.1216 65.0162)
		(end 126.0216 65.0162)
		(width 0.2032)
		(layer "In3.Cu")
		(net "GPS1_PIN14")
	)
	(segment
		(start 113.3216 62.6162)
		(end 117.7216 62.6162)
		(width 0.2032)
		(layer "In3.Cu")
		(net "GPS1_PIN14")
	)
	(segment
		(start 151.54893 99.26063)
		(end 151.54893 97.84353)
		(width 0.2032)
		(layer "F.Cu")
		(net "GPS1_PIN13")
	)
	(segment
		(start 123.8966 64.5162)
		(end 125.5216 64.5162)
		(width 0.2032)
		(layer "F.Cu")
		(net "GPS1_PIN13")
	)
	(segment
		(start 125.5216 66.3162)
		(end 125.5216 64.5162)
		(width 0.2032)
		(layer "F.Cu")
		(net "GPS1_PIN13")
	)
	(segment
		(start 103.24653 61.7286)
		(end 105.0266 61.7286)
		(width 0.2032)
		(layer "F.Cu")
		(net "GPS1_PIN13")
	)
	(segment
		(start 150.9216 97.2162)
		(end 151.54893 97.84353)
		(width 0.2032)
		(layer "F.Cu")
		(net "GPS1_PIN13")
	)
	(via
		(at 150.9216 97.2162)
		(size 0.4064)
		(drill 0.2032)
		(layers "F.Cu" "B.Cu")
		(net "GPS1_PIN13")
	)
	(via
		(at 103.24653 61.7286)
		(size 0.4064)
		(drill 0.2032)
		(layers "F.Cu" "B.Cu")
		(net "GPS1_PIN13")
	)
	(via
		(at 125.5216 66.3162)
		(size 0.4064)
		(drill 0.2032)
		(layers "F.Cu" "B.Cu")
		(net "GPS1_PIN13")
	)
	(segment
		(start 125.5216 66.3162)
		(end 125.5216 65.38575)
		(width 0.2032)
		(layer "B.Cu")
		(net "GPS1_PIN13")
	)
	(segment
		(start 125.5216 66.3162)
		(end 137.1216 66.3162)
		(width 0.2032)
		(layer "In3.Cu")
		(net "GPS1_PIN13")
	)
	(segment
		(start 103.24653 61.7286)
		(end 109.134 61.7286)
		(width 0.2032)
		(layer "In3.Cu")
		(net "GPS1_PIN13")
	)
	(segment
		(start 117.7216 64.1162)
		(end 119.9216 66.3162)
		(width 0.2032)
		(layer "In3.Cu")
		(net "GPS1_PIN13")
	)
	(segment
		(start 109.134 61.7286)
		(end 110.3216 62.9162)
		(width 0.2032)
		(layer "In3.Cu")
		(net "GPS1_PIN13")
	)
	(segment
		(start 150.6914 95.05297)
		(end 150.6914 79.886)
		(width 0.2032)
		(layer "In3.Cu")
		(net "GPS1_PIN13")
	)
	(segment
		(start 150.9216 97.2162)
		(end 150.9216 95.28317)
		(width 0.2032)
		(layer "In3.Cu")
		(net "GPS1_PIN13")
	)
	(segment
		(start 112.72798 62.9162)
		(end 113.92798 64.1162)
		(width 0.2032)
		(layer "In3.Cu")
		(net "GPS1_PIN13")
	)
	(segment
		(start 150.6914 95.05297)
		(end 150.9216 95.28317)
		(width 0.2032)
		(layer "In3.Cu")
		(net "GPS1_PIN13")
	)
	(segment
		(start 113.92798 64.1162)
		(end 117.7216 64.1162)
		(width 0.2032)
		(layer "In3.Cu")
		(net "GPS1_PIN13")
	)
	(segment
		(start 119.9216 66.3162)
		(end 125.5216 66.3162)
		(width 0.2032)
		(layer "In3.Cu")
		(net "GPS1_PIN13")
	)
	(segment
		(start 137.1216 66.3162)
		(end 150.6914 79.886)
		(width 0.2032)
		(layer "In3.Cu")
		(net "GPS1_PIN13")
	)
	(segment
		(start 110.3216 62.9162)
		(end 112.72798 62.9162)
		(width 0.2032)
		(layer "In3.Cu")
		(net "GPS1_PIN13")
	)
	(segment
		(start 140.07711 98.77171)
		(end 144.87711 98.77171)
		(width 0.2032)
		(layer "F.Cu")
		(net "GPS1_PIN12")
	)
	(segment
		(start 135.1216 93.8162)
		(end 135.1216 87.6323)
		(width 0.2032)
		(layer "F.Cu")
		(net "GPS1_PIN12")
	)
	(segment
		(start 122.9966 80.7412)
		(end 123.2966 80.4412)
		(width 0.2032)
		(layer "F.Cu")
		(net "GPS1_PIN12")
	)
	(segment
		(start 122.9966 81.2162)
		(end 122.9966 80.7412)
		(width 0.2032)
		(layer "F.Cu")
		(net "GPS1_PIN12")
	)
	(segment
		(start 152.54892 104.44352)
		(end 153.2216 105.1162)
		(width 0.2032)
		(layer "F.Cu")
		(net "GPS1_PIN12")
	)
	(segment
		(start 152.54892 104.44352)
		(end 152.54892 103.31041)
		(width 0.2032)
		(layer "F.Cu")
		(net "GPS1_PIN12")
	)
	(segment
		(start 124.74909 80.9162)
		(end 127.04909 78.6162)
		(width 0.2032)
		(layer "F.Cu")
		(net "GPS1_PIN12")
	)
	(segment
		(start 123.2966 78.4162)
		(end 123.2966 77.4162)
		(width 0.2032)
		(layer "F.Cu")
		(net "GPS1_PIN12")
	)
	(segment
		(start 144.87711 98.77171)
		(end 148.2216 102.1162)
		(width 0.2032)
		(layer "F.Cu")
		(net "GPS1_PIN12")
	)
	(segment
		(start 127.04909 78.6162)
		(end 129.86413 78.6162)
		(width 0.2032)
		(layer "F.Cu")
		(net "GPS1_PIN12")
	)
	(segment
		(start 133.15048 79.7162)
		(end 133.9518 80.51752)
		(width 0.2032)
		(layer "F.Cu")
		(net "GPS1_PIN12")
	)
	(segment
		(start 122.9966 81.2162)
		(end 123.7216 81.2162)
		(width 0.2032)
		(layer "F.Cu")
		(net "GPS1_PIN12")
	)
	(segment
		(start 124.0216 80.9162)
		(end 124.74909 80.9162)
		(width 0.2032)
		(layer "F.Cu")
		(net "GPS1_PIN12")
	)
	(segment
		(start 123.7216 81.2162)
		(end 124.0216 80.9162)
		(width 0.2032)
		(layer "F.Cu")
		(net "GPS1_PIN12")
	)
	(segment
		(start 133.9518 86.46249)
		(end 135.1216 87.6323)
		(width 0.2032)
		(layer "F.Cu")
		(net "GPS1_PIN12")
	)
	(segment
		(start 130.96413 79.7162)
		(end 133.15048 79.7162)
		(width 0.2032)
		(layer "F.Cu")
		(net "GPS1_PIN12")
	)
	(segment
		(start 148.2216 102.2162)
		(end 148.2216 102.1162)
		(width 0.2032)
		(layer "F.Cu")
		(net "GPS1_PIN12")
	)
	(segment
		(start 133.9518 86.46249)
		(end 133.9518 80.51752)
		(width 0.2032)
		(layer "F.Cu")
		(net "GPS1_PIN12")
	)
	(segment
		(start 135.1216 93.8162)
		(end 140.07711 98.77171)
		(width 0.2032)
		(layer "F.Cu")
		(net "GPS1_PIN12")
	)
	(segment
		(start 123.2966 80.4412)
		(end 123.2966 78.4162)
		(width 0.2032)
		(layer "F.Cu")
		(net "GPS1_PIN12")
	)
	(segment
		(start 129.86413 78.6162)
		(end 130.96413 79.7162)
		(width 0.2032)
		(layer "F.Cu")
		(net "GPS1_PIN12")
	)
	(via
		(at 153.2216 105.1162)
		(size 0.4064)
		(drill 0.2032)
		(layers "F.Cu" "B.Cu")
		(net "GPS1_PIN12")
	)
	(via
		(at 124.0216 80.9162)
		(size 0.4064)
		(drill 0.2032)
		(layers "F.Cu" "B.Cu")
		(net "GPS1_PIN12")
	)
	(via
		(at 148.2216 102.2162)
		(size 0.4064)
		(drill 0.2032)
		(layers "F.Cu" "B.Cu")
		(net "GPS1_PIN12")
	)
	(segment
		(start 148.9216 102.2162)
		(end 151.8216 105.1162)
		(width 0.2032)
		(layer "In2.Cu")
		(net "GPS1_PIN12")
	)
	(segment
		(start 151.8216 105.1162)
		(end 153.2216 105.1162)
		(width 0.2032)
		(layer "In2.Cu")
		(net "GPS1_PIN12")
	)
	(segment
		(start 148.2216 102.2162)
		(end 148.9216 102.2162)
		(width 0.2032)
		(layer "In2.Cu")
		(net "GPS1_PIN12")
	)
	(segment
		(start 152.04905 98.61065)
		(end 152.19536 98.46434)
		(width 0.2032)
		(layer "F.Cu")
		(net "GPS1_PIN11")
	)
	(segment
		(start 152.19536 98.39099)
		(end 152.32927 98.25708)
		(width 0.2032)
		(layer "F.Cu")
		(net "GPS1_PIN11")
	)
	(segment
		(start 117.2966 80.7662)
		(end 117.3466 80.8162)
		(width 0.2032)
		(layer "F.Cu")
		(net "GPS1_PIN11")
	)
	(segment
		(start 152.04905 99.26063)
		(end 152.04905 98.61065)
		(width 0.2032)
		(layer "F.Cu")
		(net "GPS1_PIN11")
	)
	(segment
		(start 152.19536 98.46434)
		(end 152.19536 98.39099)
		(width 0.2032)
		(layer "F.Cu")
		(net "GPS1_PIN11")
	)
	(segment
		(start 117.2966 80.7662)
		(end 117.2966 78.5662)
		(width 0.2032)
		(layer "F.Cu")
		(net "GPS1_PIN11")
	)
	(segment
		(start 117.2216 77.4162)
		(end 117.2466 77.4162)
		(width 0.2032)
		(layer "F.Cu")
		(net "GPS1_PIN11")
	)
	(segment
		(start 117.2466 78.5162)
		(end 117.2966 78.5662)
		(width 0.2032)
		(layer "F.Cu")
		(net "GPS1_PIN11")
	)
	(segment
		(start 152.78072 98.25708)
		(end 153.7216 97.3162)
		(width 0.2032)
		(layer "F.Cu")
		(net "GPS1_PIN11")
	)
	(segment
		(start 152.32927 98.25708)
		(end 152.78072 98.25708)
		(width 0.2032)
		(layer "F.Cu")
		(net "GPS1_PIN11")
	)
	(segment
		(start 117.2466 78.5162)
		(end 117.2466 77.4162)
		(width 0.2032)
		(layer "F.Cu")
		(net "GPS1_PIN11")
	)
	(via
		(at 117.2216 77.4162)
		(size 0.4064)
		(drill 0.2032)
		(layers "F.Cu" "B.Cu")
		(net "GPS1_PIN11")
	)
	(via
		(at 153.7216 97.3162)
		(size 0.4064)
		(drill 0.2032)
		(layers "F.Cu" "B.Cu")
		(net "GPS1_PIN11")
	)
	(via
		(at 134.4216 84.5162)
		(size 0.4064)
		(drill 0.2032)
		(layers "F.Cu" "B.Cu")
		(net "GPS1_PIN11")
	)
	(via
		(at 125.88025 81.45462)
		(size 0.4064)
		(drill 0.2032)
		(layers "F.Cu" "B.Cu")
		(net "GPS1_PIN11")
	)
	(segment
		(start 127.9216 81.0162)
		(end 133.94891 81.0162)
		(width 0.2032)
		(layer "B.Cu")
		(net "GPS1_PIN11")
	)
	(segment
		(start 133.9518 81.01331)
		(end 134.4216 81.48311)
		(width 0.2032)
		(layer "B.Cu")
		(net "GPS1_PIN11")
	)
	(segment
		(start 134.4216 84.5162)
		(end 134.4216 81.48311)
		(width 0.2032)
		(layer "B.Cu")
		(net "GPS1_PIN11")
	)
	(segment
		(start 127.48318 81.45462)
		(end 127.9216 81.0162)
		(width 0.2032)
		(layer "B.Cu")
		(net "GPS1_PIN11")
	)
	(segment
		(start 125.88025 81.45462)
		(end 127.48318 81.45462)
		(width 0.2032)
		(layer "B.Cu")
		(net "GPS1_PIN11")
	)
	(segment
		(start 133.94891 81.0162)
		(end 133.9518 81.01331)
		(width 0.2032)
		(layer "B.Cu")
		(net "GPS1_PIN11")
	)
	(segment
		(start 135.1216 94.40573)
		(end 135.1216 85.2162)
		(width 0.2032)
		(layer "In3.Cu")
		(net "GPS1_PIN11")
	)
	(segment
		(start 112.70677 80.30829)
		(end 112.70677 79.60483)
		(width 0.2032)
		(layer "In3.Cu")
		(net "GPS1_PIN11")
	)
	(segment
		(start 136.37167 95.6558)
		(end 141.6612 95.6558)
		(width 0.2032)
		(layer "In3.Cu")
		(net "GPS1_PIN11")
	)
	(segment
		(start 112.4216 79.31965)
		(end 112.4216 78.51468)
		(width 0.2032)
		(layer "In3.Cu")
		(net "GPS1_PIN11")
	)
	(segment
		(start 134.4216 84.5162)
		(end 135.1216 85.2162)
		(width 0.2032)
		(layer "In3.Cu")
		(net "GPS1_PIN11")
	)
	(segment
		(start 152.6216 98.4162)
		(end 153.7216 97.3162)
		(width 0.2032)
		(layer "In3.Cu")
		(net "GPS1_PIN11")
	)
	(segment
		(start 113.52008 77.4162)
		(end 117.2216 77.4162)
		(width 0.2032)
		(layer "In3.Cu")
		(net "GPS1_PIN11")
	)
	(segment
		(start 115.39275 82.99426)
		(end 123.9866 82.99426)
		(width 0.2032)
		(layer "In3.Cu")
		(net "GPS1_PIN11")
	)
	(segment
		(start 112.70677 80.30829)
		(end 115.39275 82.99426)
		(width 0.2032)
		(layer "In3.Cu")
		(net "GPS1_PIN11")
	)
	(segment
		(start 123.9866 82.99426)
		(end 125.52624 81.45462)
		(width 0.2032)
		(layer "In3.Cu")
		(net "GPS1_PIN11")
	)
	(segment
		(start 112.4216 78.51468)
		(end 113.52008 77.4162)
		(width 0.2032)
		(layer "In3.Cu")
		(net "GPS1_PIN11")
	)
	(segment
		(start 144.4216 98.4162)
		(end 152.6216 98.4162)
		(width 0.2032)
		(layer "In3.Cu")
		(net "GPS1_PIN11")
	)
	(segment
		(start 135.1216 94.40573)
		(end 136.37167 95.6558)
		(width 0.2032)
		(layer "In3.Cu")
		(net "GPS1_PIN11")
	)
	(segment
		(start 125.52624 81.45462)
		(end 125.88025 81.45462)
		(width 0.2032)
		(layer "In3.Cu")
		(net "GPS1_PIN11")
	)
	(segment
		(start 112.4216 79.31965)
		(end 112.70677 79.60483)
		(width 0.2032)
		(layer "In3.Cu")
		(net "GPS1_PIN11")
	)
	(segment
		(start 141.6612 95.6558)
		(end 144.4216 98.4162)
		(width 0.2032)
		(layer "In3.Cu")
		(net "GPS1_PIN11")
	)
	(via
		(at 83.29774 90.10383)
		(size 0.4064)
		(drill 0.2032)
		(layers "F.Cu" "B.Cu")
		(net "NetP1_5")
	)
	(via
		(at 128.59872 80.1844)
		(size 0.4064)
		(drill 0.2032)
		(layers "F.Cu" "B.Cu")
		(net "NetP1_5")
	)
	(segment
		(start 135.8854 93.10282)
		(end 139.57628 96.7937)
		(width 0.254)
		(layer "B.Cu")
		(net "NetP1_5")
	)
	(segment
		(start 135.4216 83.9162)
		(end 135.8854 84.38)
		(width 0.254)
		(layer "B.Cu")
		(net "NetP1_5")
	)
	(segment
		(start 149.76741 95.17149)
		(end 149.76741 86.402)
		(width 0.254)
		(layer "B.Cu")
		(net "NetP1_5")
	)
	(segment
		(start 83.2216 90.17996)
		(end 83.29774 90.10383)
		(width 0.254)
		(layer "B.Cu")
		(net "NetP1_5")
	)
	(segment
		(start 135.8854 93.10282)
		(end 135.8854 84.38)
		(width 0.254)
		(layer "B.Cu")
		(net "NetP1_5")
	)
	(segment
		(start 134.50061 80.19521)
		(end 135.4216 81.1162)
		(width 0.254)
		(layer "B.Cu")
		(net "NetP1_5")
	)
	(segment
		(start 147.8216 84.4562)
		(end 149.76741 86.402)
		(width 0.254)
		(layer "B.Cu")
		(net "NetP1_5")
	)
	(segment
		(start 139.57628 96.7937)
		(end 148.1452 96.7937)
		(width 0.254)
		(layer "B.Cu")
		(net "NetP1_5")
	)
	(segment
		(start 128.60953 80.19521)
		(end 134.50061 80.19521)
		(width 0.254)
		(layer "B.Cu")
		(net "NetP1_5")
	)
	(segment
		(start 128.59872 80.1844)
		(end 128.60953 80.19521)
		(width 0.254)
		(layer "B.Cu")
		(net "NetP1_5")
	)
	(segment
		(start 148.1452 96.7937)
		(end 149.76741 95.17149)
		(width 0.254)
		(layer "B.Cu")
		(net "NetP1_5")
	)
	(segment
		(start 83.2216 92.9162)
		(end 83.2216 90.17996)
		(width 0.254)
		(layer "B.Cu")
		(net "NetP1_5")
	)
	(segment
		(start 135.4216 83.9162)
		(end 135.4216 81.1162)
		(width 0.254)
		(layer "B.Cu")
		(net "NetP1_5")
	)
	(segment
		(start 84.0216 86.7162)
		(end 87.03402 86.7162)
		(width 0.254)
		(layer "In3.Cu")
		(net "NetP1_5")
	)
	(segment
		(start 87.7216 90.70157)
		(end 88.67594 91.65591)
		(width 0.254)
		(layer "In3.Cu")
		(net "NetP1_5")
	)
	(segment
		(start 83.29774 90.10383)
		(end 83.29774 87.44006)
		(width 0.254)
		(layer "In3.Cu")
		(net "NetP1_5")
	)
	(segment
		(start 116.2216 86.0162)
		(end 126.32158 86.0162)
		(width 0.254)
		(layer "In3.Cu")
		(net "NetP1_5")
	)
	(segment
		(start 87.7216 90.70157)
		(end 87.7216 87.40378)
		(width 0.254)
		(layer "In3.Cu")
		(net "NetP1_5")
	)
	(segment
		(start 83.29774 87.44006)
		(end 84.0216 86.7162)
		(width 0.254)
		(layer "In3.Cu")
		(net "NetP1_5")
	)
	(segment
		(start 109.7657 89.07209)
		(end 113.16571 89.07209)
		(width 0.254)
		(layer "In3.Cu")
		(net "NetP1_5")
	)
	(segment
		(start 87.03402 86.7162)
		(end 87.7216 87.40378)
		(width 0.254)
		(layer "In3.Cu")
		(net "NetP1_5")
	)
	(segment
		(start 107.18189 91.65591)
		(end 109.7657 89.07209)
		(width 0.254)
		(layer "In3.Cu")
		(net "NetP1_5")
	)
	(segment
		(start 113.16571 89.07209)
		(end 116.2216 86.0162)
		(width 0.254)
		(layer "In3.Cu")
		(net "NetP1_5")
	)
	(segment
		(start 88.67594 91.65591)
		(end 107.18189 91.65591)
		(width 0.254)
		(layer "In3.Cu")
		(net "NetP1_5")
	)
	(segment
		(start 128.0216 81.59332)
		(end 128.59872 81.0162)
		(width 0.254)
		(layer "In3.Cu")
		(net "NetP1_5")
	)
	(segment
		(start 126.32158 86.0162)
		(end 128.0216 84.31618)
		(width 0.254)
		(layer "In3.Cu")
		(net "NetP1_5")
	)
	(segment
		(start 128.59872 81.0162)
		(end 128.59872 80.1844)
		(width 0.254)
		(layer "In3.Cu")
		(net "NetP1_5")
	)
	(segment
		(start 128.0216 84.31618)
		(end 128.0216 81.59332)
		(width 0.254)
		(layer "In3.Cu")
		(net "NetP1_5")
	)
	(via
		(at 137.0216 92.4162)
		(size 0.4064)
		(drill 0.254)
		(layers "F.Cu" "B.Cu")
		(net "MAC_VCC")
	)
	(via
		(at 137.5216 93.3162)
		(size 0.4064)
		(drill 0.254)
		(layers "F.Cu" "B.Cu")
		(net "MAC_VCC")
	)
	(via
		(at 137.1216 87.2162)
		(size 0.4064)
		(drill 0.254)
		(layers "F.Cu" "B.Cu")
		(net "MAC_VCC")
	)
	(via
		(at 137.1216 88.5162)
		(size 0.4064)
		(drill 0.254)
		(layers "F.Cu" "B.Cu")
		(net "MAC_VCC")
	)
	(via
		(at 137.1216 91.2162)
		(size 0.4064)
		(drill 0.254)
		(layers "F.Cu" "B.Cu")
		(net "MAC_VCC")
	)
	(via
		(at 137.1216 89.9162)
		(size 0.4064)
		(drill 0.254)
		(layers "F.Cu" "B.Cu")
		(net "MAC_VCC")
	)
	(segment
		(start 140.6466 103.9162)
		(end 140.6466 103.1912)
		(width 0.2032)
		(layer "F.Cu")
		(net "MAC_PPS_OUT")
	)
	(segment
		(start 142.17658 101.9162)
		(end 142.25159 101.8412)
		(width 0.2032)
		(layer "F.Cu")
		(net "MAC_PPS_OUT")
	)
	(segment
		(start 142.1216 101.9162)
		(end 142.17658 101.9162)
		(width 0.2032)
		(layer "F.Cu")
		(net "MAC_PPS_OUT")
	)
	(segment
		(start 140.6466 103.1912)
		(end 141.9216 101.9162)
		(width 0.2032)
		(layer "F.Cu")
		(net "MAC_PPS_OUT")
	)
	(segment
		(start 141.9216 101.9162)
		(end 142.1216 101.9162)
		(width 0.2032)
		(layer "F.Cu")
		(net "MAC_PPS_OUT")
	)
	(segment
		(start 142.25159 101.8412)
		(end 142.8216 101.8412)
		(width 0.2032)
		(layer "F.Cu")
		(net "MAC_PPS_OUT")
	)
	(via
		(at 142.1216 101.9162)
		(size 0.4064)
		(drill 0.2032)
		(layers "F.Cu" "B.Cu")
		(net "MAC_PPS_OUT")
	)
	(segment
		(start 133.0216 117.7162)
		(end 137.37607 113.36173)
		(width 0.2032)
		(layer "B.Cu")
		(net "MAC_PPS_OUT")
	)
	(segment
		(start 137.37607 106.26173)
		(end 140.28941 103.34839)
		(width 0.2032)
		(layer "B.Cu")
		(net "MAC_PPS_OUT")
	)
	(segment
		(start 123.6216 121.6162)
		(end 130.7216 121.6162)
		(width 0.2032)
		(layer "B.Cu")
		(net "MAC_PPS_OUT")
	)
	(segment
		(start 140.68941 103.34839)
		(end 142.1216 101.9162)
		(width 0.2032)
		(layer "B.Cu")
		(net "MAC_PPS_OUT")
	)
	(segment
		(start 133.0216 119.3162)
		(end 133.0216 117.7162)
		(width 0.2032)
		(layer "B.Cu")
		(net "MAC_PPS_OUT")
	)
	(segment
		(start 113.3256 131.9122)
		(end 123.6216 121.6162)
		(width 0.2032)
		(layer "B.Cu")
		(net "MAC_PPS_OUT")
	)
	(segment
		(start 137.37607 113.36173)
		(end 137.37607 106.26173)
		(width 0.2032)
		(layer "B.Cu")
		(net "MAC_PPS_OUT")
	)
	(segment
		(start 130.7216 121.6162)
		(end 133.0216 119.3162)
		(width 0.2032)
		(layer "B.Cu")
		(net "MAC_PPS_OUT")
	)
	(segment
		(start 140.28941 103.34839)
		(end 140.68941 103.34839)
		(width 0.2032)
		(layer "B.Cu")
		(net "MAC_PPS_OUT")
	)
	(segment
		(start 113.3256 140.0162)
		(end 113.3256 131.9122)
		(width 0.2032)
		(layer "B.Cu")
		(net "MAC_PPS_OUT")
	)
	(segment
		(start 147.2216 103.7162)
		(end 147.2216 102.55854)
		(width 0.254)
		(layer "F.Cu")
		(net "MAC_PPS_IN")
	)
	(segment
		(start 146.50426 101.8412)
		(end 147.2216 102.55854)
		(width 0.254)
		(layer "F.Cu")
		(net "MAC_PPS_IN")
	)
	(segment
		(start 146.9966 104.4162)
		(end 146.9966 103.9412)
		(width 0.254)
		(layer "F.Cu")
		(net "MAC_PPS_IN")
	)
	(segment
		(start 144.7216 101.8412)
		(end 146.50426 101.8412)
		(width 0.254)
		(layer "F.Cu")
		(net "MAC_PPS_IN")
	)
	(segment
		(start 146.9966 103.9412)
		(end 147.2216 103.7162)
		(width 0.254)
		(layer "F.Cu")
		(net "MAC_PPS_IN")
	)
	(via
		(at 147.2216 103.7162)
		(size 0.4064)
		(drill 0.2032)
		(layers "F.Cu" "B.Cu")
		(net "MAC_PPS_IN")
	)
	(segment
		(start 147.7216 107.06741)
		(end 147.7216 104.2162)
		(width 0.254)
		(layer "B.Cu")
		(net "MAC_PPS_IN")
	)
	(segment
		(start 116.3736 130.7642)
		(end 123.4216 123.7162)
		(width 0.254)
		(layer "B.Cu")
		(net "MAC_PPS_IN")
	)
	(segment
		(start 123.4216 123.7162)
		(end 130.77759 123.7162)
		(width 0.254)
		(layer "B.Cu")
		(net "MAC_PPS_IN")
	)
	(segment
		(start 147.2216 103.7162)
		(end 147.7216 104.2162)
		(width 0.254)
		(layer "B.Cu")
		(net "MAC_PPS_IN")
	)
	(segment
		(start 137.5216 113.9162)
		(end 139.00677 113.9162)
		(width 0.254)
		(layer "B.Cu")
		(net "MAC_PPS_IN")
	)
	(segment
		(start 144.39307 110.39594)
		(end 147.7216 107.06741)
		(width 0.254)
		(layer "B.Cu")
		(net "MAC_PPS_IN")
	)
	(segment
		(start 116.3736 140.0162)
		(end 116.3736 130.7642)
		(width 0.254)
		(layer "B.Cu")
		(net "MAC_PPS_IN")
	)
	(segment
		(start 142.52703 110.39594)
		(end 144.39307 110.39594)
		(width 0.254)
		(layer "B.Cu")
		(net "MAC_PPS_IN")
	)
	(segment
		(start 133.4216 118.0162)
		(end 137.5216 113.9162)
		(width 0.254)
		(layer "B.Cu")
		(net "MAC_PPS_IN")
	)
	(segment
		(start 139.00677 113.9162)
		(end 142.52703 110.39594)
		(width 0.254)
		(layer "B.Cu")
		(net "MAC_PPS_IN")
	)
	(segment
		(start 133.4216 121.07219)
		(end 133.4216 118.0162)
		(width 0.254)
		(layer "B.Cu")
		(net "MAC_PPS_IN")
	)
	(segment
		(start 130.77759 123.7162)
		(end 133.4216 121.07219)
		(width 0.254)
		(layer "B.Cu")
		(net "MAC_PPS_IN")
	)
	(segment
		(start 77.5716 50.3662)
		(end 78.6716 50.3662)
		(width 0.2032)
		(layer "F.Cu")
		(net "NetD3_1")
	)
	(segment
		(start 77.2216 50.7162)
		(end 77.5716 50.3662)
		(width 0.2032)
		(layer "F.Cu")
		(net "NetD3_1")
	)
	(via
		(at 77.2216 50.7162)
		(size 0.4064)
		(drill 0.2032)
		(layers "F.Cu" "B.Cu")
		(net "NetD3_1")
	)
	(segment
		(start 77.2216 50.7162)
		(end 78.4966 50.7162)
		(width 0.2032)
		(layer "B.Cu")
		(net "NetD3_1")
	)
	(segment
		(start 78.4966 50.7162)
		(end 78.7466 50.9662)
		(width 0.2032)
		(layer "B.Cu")
		(net "NetD3_1")
	)
	(segment
		(start 89.25686 89.06371)
		(end 89.25686 87.06371)
		(width 0.2032)
		(layer "F.Cu")
		(net "NetR41_2")
	)
	(segment
		(start 89.25686 87.06371)
		(end 91.38187 87.06371)
		(width 0.2032)
		(layer "F.Cu")
		(net "NetR41_2")
	)
	(segment
		(start 88.45686 89.06371)
		(end 89.25686 89.06371)
		(width 0.2032)
		(layer "F.Cu")
		(net "NetR41_2")
	)
	(segment
		(start 73.68141 141.1662)
		(end 74.5466 141.1662)
		(width 0.254)
		(layer "F.Cu")
		(net "NetR34_1")
	)
	(segment
		(start 72.4216 141.6662)
		(end 73.68141 141.6662)
		(width 0.254)
		(layer "F.Cu")
		(net "NetR34_1")
	)
	(segment
		(start 73.68141 141.6662)
		(end 73.68141 141.1662)
		(width 0.254)
		(layer "F.Cu")
		(net "NetR34_1")
	)
	(segment
		(start 73.68141 141.6662)
		(end 74.5466 141.6662)
		(width 0.254)
		(layer "F.Cu")
		(net "NetR34_1")
	)
	(segment
		(start 72.4216 141.7162)
		(end 72.4216 141.6662)
		(width 0.254)
		(layer "F.Cu")
		(net "NetR34_1")
	)
	(segment
		(start 75.0216 113.2662)
		(end 75.0216 112.5162)
		(width 0.2032)
		(layer "F.Cu")
		(net "NetR33_1")
	)
	(segment
		(start 75.0216 113.7662)
		(end 75.0216 113.2662)
		(width 0.2032)
		(layer "F.Cu")
		(net "NetR33_1")
	)
	(segment
		(start 75.0216 113.7662)
		(end 75.84659 113.7662)
		(width 0.2032)
		(layer "F.Cu")
		(net "NetR33_1")
	)
	(segment
		(start 75.0216 113.2662)
		(end 75.84659 113.2662)
		(width 0.2032)
		(layer "F.Cu")
		(net "NetR33_1")
	)
	(segment
		(start 74.9216 128.2662)
		(end 75.84659 128.2662)
		(width 0.2032)
		(layer "F.Cu")
		(net "NetR28_1")
	)
	(segment
		(start 74.9216 127.7662)
		(end 75.84659 127.7662)
		(width 0.2032)
		(layer "F.Cu")
		(net "NetR28_1")
	)
	(segment
		(start 74.9216 128.2662)
		(end 74.9216 127.7662)
		(width 0.2032)
		(layer "F.Cu")
		(net "NetR28_1")
	)
	(segment
		(start 74.9216 127.2162)
		(end 75.8216 127.2162)
		(width 0.2032)
		(layer "F.Cu")
		(net "NetR28_1")
	)
	(segment
		(start 75.8216 127.2162)
		(end 75.8216 126.4162)
		(width 0.2032)
		(layer "F.Cu")
		(net "NetR28_1")
	)
	(segment
		(start 74.9216 127.7662)
		(end 74.9216 127.2162)
		(width 0.2032)
		(layer "F.Cu")
		(net "NetR28_1")
	)
	(segment
		(start 93.18287 84.23871)
		(end 93.18287 83.06371)
		(width 0.2032)
		(layer "F.Cu")
		(net "NetD18_4")
	)
	(segment
		(start 66.1466 140.3912)
		(end 67.4216 140.3912)
		(width 0.2032)
		(layer "F.Cu")
		(net "NetD18_4")
	)
	(segment
		(start 67.4216 140.3912)
		(end 67.4466 140.4162)
		(width 0.2032)
		(layer "F.Cu")
		(net "NetD18_4")
	)
	(segment
		(start 93.18287 84.23871)
		(end 93.20687 84.23871)
		(width 0.2032)
		(layer "F.Cu")
		(net "NetD18_4")
	)
	(segment
		(start 66.1216 140.3662)
		(end 66.1466 140.3912)
		(width 0.2032)
		(layer "F.Cu")
		(net "NetD18_4")
	)
	(via
		(at 93.18287 83.06371)
		(size 0.4064)
		(drill 0.2032)
		(layers "F.Cu" "B.Cu")
		(tenting
			(front yes)
			(back yes)
		)
		(net "NetD18_4")
	)
	(via
		(at 66.1216 140.3662)
		(size 0.4064)
		(drill 0.2032)
		(layers "F.Cu" "B.Cu")
		(tenting
			(front yes)
			(back yes)
		)
		(net "NetD18_4")
	)
	(segment
		(start 83.6216 128.81706)
		(end 85.09333 127.34532)
		(width 0.2032)
		(layer "B.Cu")
		(net "NetD18_4")
	)
	(segment
		(start 66.1216 140.3662)
		(end 70.0241 140.3662)
		(width 0.2032)
		(layer "B.Cu")
		(net "NetD18_4")
	)
	(segment
		(start 96.39363 81.63351)
		(end 96.42383 81.66371)
		(width 0.2032)
		(layer "B.Cu")
		(net "NetD18_4")
	)
	(segment
		(start 93.18287 83.06371)
		(end 93.18287 81.66371)
		(width 0.2032)
		(layer "B.Cu")
		(net "NetD18_4")
	)
	(segment
		(start 96.77589 83.46371)
		(end 100.73783 83.46371)
		(width 0.2032)
		(layer "B.Cu")
		(net "NetD18_4")
	)
	(segment
		(start 85.56163 127.06371)
		(end 100.85686 127.06371)
		(width 0.2032)
		(layer "B.Cu")
		(net "NetD18_4")
	)
	(segment
		(start 96.65686 83.34467)
		(end 96.65686 81.66371)
		(width 0.2032)
		(layer "B.Cu")
		(net "NetD18_4")
	)
	(segment
		(start 75.2518 139.486)
		(end 77.15179 139.486)
		(width 0.2032)
		(layer "B.Cu")
		(net "NetD18_4")
	)
	(segment
		(start 79.1216 137.5162)
		(end 79.1216 133.9162)
		(width 0.2032)
		(layer "B.Cu")
		(net "NetD18_4")
	)
	(segment
		(start 96.65686 83.34467)
		(end 96.77589 83.46371)
		(width 0.2032)
		(layer "B.Cu")
		(net "NetD18_4")
	)
	(segment
		(start 79.1216 133.9162)
		(end 83.6216 129.4162)
		(width 0.2032)
		(layer "B.Cu")
		(net "NetD18_4")
	)
	(segment
		(start 100.85686 127.06371)
		(end 100.85686 83.58274)
		(width 0.2032)
		(layer "B.Cu")
		(net "NetD18_4")
	)
	(segment
		(start 94.04789 81.66371)
		(end 94.07809 81.63351)
		(width 0.2032)
		(layer "B.Cu")
		(net "NetD18_4")
	)
	(segment
		(start 85.28002 127.34532)
		(end 85.56163 127.06371)
		(width 0.2032)
		(layer "B.Cu")
		(net "NetD18_4")
	)
	(segment
		(start 77.15179 139.486)
		(end 79.1216 137.5162)
		(width 0.2032)
		(layer "B.Cu")
		(net "NetD18_4")
	)
	(segment
		(start 94.07809 81.63351)
		(end 96.39363 81.63351)
		(width 0.2032)
		(layer "B.Cu")
		(net "NetD18_4")
	)
	(segment
		(start 70.27409 140.6162)
		(end 74.1216 140.6162)
		(width 0.2032)
		(layer "B.Cu")
		(net "NetD18_4")
	)
	(segment
		(start 96.42383 81.66371)
		(end 96.65686 81.66371)
		(width 0.2032)
		(layer "B.Cu")
		(net "NetD18_4")
	)
	(segment
		(start 74.1216 140.6162)
		(end 75.2518 139.486)
		(width 0.2032)
		(layer "B.Cu")
		(net "NetD18_4")
	)
	(segment
		(start 100.73783 83.46371)
		(end 100.85686 83.58274)
		(width 0.2032)
		(layer "B.Cu")
		(net "NetD18_4")
	)
	(segment
		(start 93.18287 81.66371)
		(end 94.04789 81.66371)
		(width 0.2032)
		(layer "B.Cu")
		(net "NetD18_4")
	)
	(segment
		(start 85.09333 127.34532)
		(end 85.28002 127.34532)
		(width 0.2032)
		(layer "B.Cu")
		(net "NetD18_4")
	)
	(segment
		(start 83.6216 129.4162)
		(end 83.6216 128.81706)
		(width 0.2032)
		(layer "B.Cu")
		(net "NetD18_4")
	)
	(segment
		(start 70.0241 140.3662)
		(end 70.27409 140.6162)
		(width 0.2032)
		(layer "B.Cu")
		(net "NetD18_4")
	)
	(segment
		(start 92.69086 84.23871)
		(end 92.69086 82.56371)
		(width 0.2032)
		(layer "F.Cu")
		(net "NetD18_3")
	)
	(segment
		(start 66.1216 141.3662)
		(end 67.1216 141.3662)
		(width 0.2032)
		(layer "F.Cu")
		(net "NetD18_3")
	)
	(segment
		(start 92.69086 84.23871)
		(end 92.70687 84.23871)
		(width 0.2032)
		(layer "F.Cu")
		(net "NetD18_3")
	)
	(via
		(at 92.69086 82.56371)
		(size 0.4064)
		(drill 0.2032)
		(layers "F.Cu" "B.Cu")
		(tenting
			(front yes)
			(back yes)
		)
		(net "NetD18_3")
	)
	(via
		(at 66.1216 141.3662)
		(size 0.4064)
		(drill 0.2032)
		(layers "F.Cu" "B.Cu")
		(tenting
			(front yes)
			(back yes)
		)
		(net "NetD18_3")
	)
	(segment
		(start 74.8716 141.3662)
		(end 76.4216 139.8162)
		(width 0.2032)
		(layer "B.Cu")
		(net "NetD18_3")
	)
	(segment
		(start 96.98706 83.01447)
		(end 97.10609 83.13351)
		(width 0.2032)
		(layer "B.Cu")
		(net "NetD18_3")
	)
	(segment
		(start 101.25686 127.76371)
		(end 101.25686 83.28274)
		(width 0.2032)
		(layer "B.Cu")
		(net "NetD18_3")
	)
	(segment
		(start 92.69086 81.30331)
		(end 96.76343 81.30331)
		(width 0.2032)
		(layer "B.Cu")
		(net "NetD18_3")
	)
	(segment
		(start 97.10609 83.13351)
		(end 101.10763 83.13351)
		(width 0.2032)
		(layer "B.Cu")
		(net "NetD18_3")
	)
	(segment
		(start 96.76343 81.30331)
		(end 96.98706 81.52694)
		(width 0.2032)
		(layer "B.Cu")
		(net "NetD18_3")
	)
	(segment
		(start 85.14192 127.76371)
		(end 101.25686 127.76371)
		(width 0.2032)
		(layer "B.Cu")
		(net "NetD18_3")
	)
	(segment
		(start 92.69086 82.73351)
		(end 92.69086 82.56371)
		(width 0.2032)
		(layer "B.Cu")
		(net "NetD18_3")
	)
	(segment
		(start 79.8216 134.9162)
		(end 85.14192 129.59588)
		(width 0.2032)
		(layer "B.Cu")
		(net "NetD18_3")
	)
	(segment
		(start 85.14192 129.59588)
		(end 85.14192 127.76371)
		(width 0.2032)
		(layer "B.Cu")
		(net "NetD18_3")
	)
	(segment
		(start 101.10763 83.13351)
		(end 101.25686 83.28274)
		(width 0.2032)
		(layer "B.Cu")
		(net "NetD18_3")
	)
	(segment
		(start 76.4216 139.8162)
		(end 78.5216 139.8162)
		(width 0.2032)
		(layer "B.Cu")
		(net "NetD18_3")
	)
	(segment
		(start 78.5216 139.8162)
		(end 79.8216 138.5162)
		(width 0.2032)
		(layer "B.Cu")
		(net "NetD18_3")
	)
	(segment
		(start 92.69086 82.56371)
		(end 92.69086 81.30331)
		(width 0.2032)
		(layer "B.Cu")
		(net "NetD18_3")
	)
	(segment
		(start 92.69086 82.73351)
		(end 92.73363 82.73351)
		(width 0.2032)
		(layer "B.Cu")
		(net "NetD18_3")
	)
	(segment
		(start 92.73363 82.73351)
		(end 92.79715 82.66999)
		(width 0.2032)
		(layer "B.Cu")
		(net "NetD18_3")
	)
	(segment
		(start 66.1216 141.3662)
		(end 74.8716 141.3662)
		(width 0.2032)
		(layer "B.Cu")
		(net "NetD18_3")
	)
	(segment
		(start 79.8216 138.5162)
		(end 79.8216 134.9162)
		(width 0.2032)
		(layer "B.Cu")
		(net "NetD18_3")
	)
	(segment
		(start 96.98706 83.01447)
		(end 96.98706 81.52694)
		(width 0.2032)
		(layer "B.Cu")
		(net "NetD18_3")
	)
	(segment
		(start 92.16687 83.06371)
		(end 92.20687 83.06371)
		(width 0.2032)
		(layer "F.Cu")
		(net "NetD18_2")
	)
	(segment
		(start 67.01048 142.15508)
		(end 67.1216 142.2662)
		(width 0.2032)
		(layer "F.Cu")
		(net "NetD18_2")
	)
	(segment
		(start 92.20687 84.23871)
		(end 92.20687 83.06371)
		(width 0.2032)
		(layer "F.Cu")
		(net "NetD18_2")
	)
	(segment
		(start 66.16048 142.15508)
		(end 67.01048 142.15508)
		(width 0.2032)
		(layer "F.Cu")
		(net "NetD18_2")
	)
	(segment
		(start 66.1216 142.1162)
		(end 66.16048 142.15508)
		(width 0.2032)
		(layer "F.Cu")
		(net "NetD18_2")
	)
	(via
		(at 92.16687 83.06371)
		(size 0.4064)
		(drill 0.2032)
		(layers "F.Cu" "B.Cu")
		(tenting
			(front yes)
			(back yes)
		)
		(net "NetD18_2")
	)
	(via
		(at 66.1216 142.1162)
		(size 0.4064)
		(drill 0.2032)
		(layers "F.Cu" "B.Cu")
		(tenting
			(front yes)
			(back yes)
		)
		(net "NetD18_2")
	)
	(segment
		(start 70.04909 141.9162)
		(end 73.7216 141.9162)
		(width 0.2032)
		(layer "B.Cu")
		(net "NetD18_2")
	)
	(segment
		(start 101.12383 128.36371)
		(end 101.65686 127.83068)
		(width 0.2032)
		(layer "B.Cu")
		(net "NetD18_2")
	)
	(segment
		(start 78.93551 142.22967)
		(end 79.05455 142.11063)
		(width 0.2032)
		(layer "B.Cu")
		(net "NetD18_2")
	)
	(segment
		(start 92.16687 83.06371)
		(end 92.16687 80.98274)
		(width 0.2032)
		(layer "B.Cu")
		(net "NetD18_2")
	)
	(segment
		(start 79.05455 141.78325)
		(end 81.7216 139.1162)
		(width 0.2032)
		(layer "B.Cu")
		(net "NetD18_2")
	)
	(segment
		(start 101.2444 82.80331)
		(end 101.65686 83.21577)
		(width 0.2032)
		(layer "B.Cu")
		(net "NetD18_2")
	)
	(segment
		(start 81.7216 139.1162)
		(end 81.7216 134.23734)
		(width 0.2032)
		(layer "B.Cu")
		(net "NetD18_2")
	)
	(segment
		(start 74.03507 142.22967)
		(end 78.93551 142.22967)
		(width 0.2032)
		(layer "B.Cu")
		(net "NetD18_2")
	)
	(segment
		(start 66.1216 142.1162)
		(end 69.84909 142.1162)
		(width 0.2032)
		(layer "B.Cu")
		(net "NetD18_2")
	)
	(segment
		(start 97.61549 82.80331)
		(end 101.2444 82.80331)
		(width 0.2032)
		(layer "B.Cu")
		(net "NetD18_2")
	)
	(segment
		(start 81.7216 134.23734)
		(end 87.59524 128.36371)
		(width 0.2032)
		(layer "B.Cu")
		(net "NetD18_2")
	)
	(segment
		(start 96.7908 80.86371)
		(end 97.45686 81.52977)
		(width 0.2032)
		(layer "B.Cu")
		(net "NetD18_2")
	)
	(segment
		(start 92.2859 80.86371)
		(end 96.7908 80.86371)
		(width 0.2032)
		(layer "B.Cu")
		(net "NetD18_2")
	)
	(segment
		(start 79.05455 142.11063)
		(end 79.05455 141.78325)
		(width 0.2032)
		(layer "B.Cu")
		(net "NetD18_2")
	)
	(segment
		(start 69.84909 142.1162)
		(end 70.04909 141.9162)
		(width 0.2032)
		(layer "B.Cu")
		(net "NetD18_2")
	)
	(segment
		(start 97.45686 82.64468)
		(end 97.45686 81.52977)
		(width 0.2032)
		(layer "B.Cu")
		(net "NetD18_2")
	)
	(segment
		(start 87.59524 128.36371)
		(end 101.12383 128.36371)
		(width 0.2032)
		(layer "B.Cu")
		(net "NetD18_2")
	)
	(segment
		(start 73.7216 141.9162)
		(end 74.03507 142.22967)
		(width 0.2032)
		(layer "B.Cu")
		(net "NetD18_2")
	)
	(segment
		(start 92.16687 80.98274)
		(end 92.2859 80.86371)
		(width 0.2032)
		(layer "B.Cu")
		(net "NetD18_2")
	)
	(segment
		(start 101.65686 127.83068)
		(end 101.65686 83.21577)
		(width 0.2032)
		(layer "B.Cu")
		(net "NetD18_2")
	)
	(segment
		(start 97.45686 82.64468)
		(end 97.61549 82.80331)
		(width 0.2032)
		(layer "B.Cu")
		(net "NetD18_2")
	)
	(segment
		(start 66.1216 126.8662)
		(end 66.16048 126.90508)
		(width 0.2032)
		(layer "F.Cu")
		(net "NetD17_4")
	)
	(segment
		(start 95.20687 83.07171)
		(end 95.24687 83.07171)
		(width 0.2032)
		(layer "F.Cu")
		(net "NetD17_4")
	)
	(segment
		(start 67.33548 126.90508)
		(end 67.4466 127.0162)
		(width 0.2032)
		(layer "F.Cu")
		(net "NetD17_4")
	)
	(segment
		(start 66.16048 126.90508)
		(end 67.33548 126.90508)
		(width 0.2032)
		(layer "F.Cu")
		(net "NetD17_4")
	)
	(segment
		(start 95.20687 84.23871)
		(end 95.20687 83.07171)
		(width 0.2032)
		(layer "F.Cu")
		(net "NetD17_4")
	)
	(via
		(at 95.24687 83.07171)
		(size 0.4064)
		(drill 0.2032)
		(layers "F.Cu" "B.Cu")
		(tenting
			(front yes)
			(back yes)
		)
		(net "NetD17_4")
	)
	(via
		(at 66.1216 126.8662)
		(size 0.4064)
		(drill 0.2032)
		(layers "F.Cu" "B.Cu")
		(tenting
			(front yes)
			(back yes)
		)
		(net "NetD17_4")
	)
	(segment
		(start 66.1216 126.8662)
		(end 67.0716 127.8162)
		(width 0.2032)
		(layer "B.Cu")
		(net "NetD17_4")
	)
	(segment
		(start 77.07409 124.96371)
		(end 99.53783 124.96371)
		(width 0.2032)
		(layer "B.Cu")
		(net "NetD17_4")
	)
	(segment
		(start 99.65686 124.84468)
		(end 99.65686 84.61797)
		(width 0.2032)
		(layer "B.Cu")
		(net "NetD17_4")
	)
	(segment
		(start 75.1216 126.9162)
		(end 77.07409 124.96371)
		(width 0.2032)
		(layer "B.Cu")
		(net "NetD17_4")
	)
	(segment
		(start 99.53783 124.96371)
		(end 99.65686 124.84468)
		(width 0.2032)
		(layer "B.Cu")
		(net "NetD17_4")
	)
	(segment
		(start 95.24687 84.49893)
		(end 99.53783 84.49893)
		(width 0.2032)
		(layer "B.Cu")
		(net "NetD17_4")
	)
	(segment
		(start 99.53783 84.49893)
		(end 99.65686 84.61797)
		(width 0.2032)
		(layer "B.Cu")
		(net "NetD17_4")
	)
	(segment
		(start 72.22161 127.8162)
		(end 73.12161 126.9162)
		(width 0.2032)
		(layer "B.Cu")
		(net "NetD17_4")
	)
	(segment
		(start 67.0716 127.8162)
		(end 72.22161 127.8162)
		(width 0.2032)
		(layer "B.Cu")
		(net "NetD17_4")
	)
	(segment
		(start 95.24687 84.49893)
		(end 95.24687 83.07171)
		(width 0.2032)
		(layer "B.Cu")
		(net "NetD17_4")
	)
	(segment
		(start 73.12161 126.9162)
		(end 75.1216 126.9162)
		(width 0.2032)
		(layer "B.Cu")
		(net "NetD17_4")
	)
	(segment
		(start 94.70687 84.23871)
		(end 94.72286 84.23871)
		(width 0.2032)
		(layer "F.Cu")
		(net "NetD17_3")
	)
	(segment
		(start 67.06048 127.90508)
		(end 67.1216 127.9662)
		(width 0.2032)
		(layer "F.Cu")
		(net "NetD17_3")
	)
	(segment
		(start 66.16048 127.90508)
		(end 67.06048 127.90508)
		(width 0.2032)
		(layer "F.Cu")
		(net "NetD17_3")
	)
	(segment
		(start 66.1216 127.8662)
		(end 66.16048 127.90508)
		(width 0.2032)
		(layer "F.Cu")
		(net "NetD17_3")
	)
	(segment
		(start 94.72286 84.23871)
		(end 94.72286 82.56371)
		(width 0.2032)
		(layer "F.Cu")
		(net "NetD17_3")
	)
	(via
		(at 94.72286 82.56371)
		(size 0.4064)
		(drill 0.2032)
		(layers "F.Cu" "B.Cu")
		(tenting
			(front yes)
			(back yes)
		)
		(net "NetD17_3")
	)
	(via
		(at 66.1216 127.8662)
		(size 0.4064)
		(drill 0.2032)
		(layers "F.Cu" "B.Cu")
		(tenting
			(front yes)
			(back yes)
		)
		(net "NetD17_3")
	)
	(segment
		(start 94.72286 82.56371)
		(end 94.72286 82.56371)
		(width 0.2032)
		(layer "B.Cu")
		(net "NetD17_3")
	)
	(segment
		(start 99.6746 84.16873)
		(end 100.05686 84.55099)
		(width 0.2032)
		(layer "B.Cu")
		(net "NetD17_3")
	)
	(segment
		(start 100.05686 125.34467)
		(end 100.05686 84.55099)
		(width 0.2032)
		(layer "B.Cu")
		(net "NetD17_3")
	)
	(segment
		(start 72.32161 128.62868)
		(end 73.03409 127.9162)
		(width 0.2032)
		(layer "B.Cu")
		(net "NetD17_3")
	)
	(segment
		(start 77.97409 125.46371)
		(end 99.93783 125.46371)
		(width 0.2032)
		(layer "B.Cu")
		(net "NetD17_3")
	)
	(segment
		(start 73.03409 127.9162)
		(end 75.5216 127.9162)
		(width 0.2032)
		(layer "B.Cu")
		(net "NetD17_3")
	)
	(segment
		(start 95.84748 84.0497)
		(end 95.84748 82.56371)
		(width 0.2032)
		(layer "B.Cu")
		(net "NetD17_3")
	)
	(segment
		(start 75.5216 127.9162)
		(end 77.97409 125.46371)
		(width 0.2032)
		(layer "B.Cu")
		(net "NetD17_3")
	)
	(segment
		(start 66.1216 127.8662)
		(end 66.88408 128.62868)
		(width 0.2032)
		(layer "B.Cu")
		(net "NetD17_3")
	)
	(segment
		(start 66.88408 128.62868)
		(end 72.32161 128.62868)
		(width 0.2032)
		(layer "B.Cu")
		(net "NetD17_3")
	)
	(segment
		(start 99.93783 125.46371)
		(end 100.05686 125.34467)
		(width 0.2032)
		(layer "B.Cu")
		(net "NetD17_3")
	)
	(segment
		(start 94.72286 82.56371)
		(end 95.84748 82.56371)
		(width 0.2032)
		(layer "B.Cu")
		(net "NetD17_3")
	)
	(segment
		(start 95.96651 84.16873)
		(end 99.6746 84.16873)
		(width 0.2032)
		(layer "B.Cu")
		(net "NetD17_3")
	)
	(segment
		(start 95.84748 84.0497)
		(end 95.96651 84.16873)
		(width 0.2032)
		(layer "B.Cu")
		(net "NetD17_3")
	)
	(segment
		(start 94.20687 83.06371)
		(end 94.21486 83.06371)
		(width 0.2032)
		(layer "F.Cu")
		(net "NetD17_2")
	)
	(segment
		(start 66.1216 128.8662)
		(end 67.1216 128.8662)
		(width 0.2032)
		(layer "F.Cu")
		(net "NetD17_2")
	)
	(segment
		(start 94.20687 84.23871)
		(end 94.20687 83.06371)
		(width 0.2032)
		(layer "F.Cu")
		(net "NetD17_2")
	)
	(via
		(at 66.1216 128.8662)
		(size 0.4064)
		(drill 0.2032)
		(layers "F.Cu" "B.Cu")
		(tenting
			(front yes)
			(back yes)
		)
		(net "NetD17_2")
	)
	(via
		(at 94.21486 83.06371)
		(size 0.4064)
		(drill 0.2032)
		(layers "F.Cu" "B.Cu")
		(tenting
			(front yes)
			(back yes)
		)
		(net "NetD17_2")
	)
	(segment
		(start 78.71308 128.5162)
		(end 81.16557 126.06371)
		(width 0.2032)
		(layer "B.Cu")
		(net "NetD17_2")
	)
	(segment
		(start 100.21266 83.83853)
		(end 100.45686 84.08274)
		(width 0.2032)
		(layer "B.Cu")
		(net "NetD17_2")
	)
	(segment
		(start 100.45686 125.94468)
		(end 100.45686 84.08274)
		(width 0.2032)
		(layer "B.Cu")
		(net "NetD17_2")
	)
	(segment
		(start 96.25686 83.7195)
		(end 96.25686 81.96371)
		(width 0.2032)
		(layer "B.Cu")
		(net "NetD17_2")
	)
	(segment
		(start 100.33783 126.06371)
		(end 100.45686 125.94468)
		(width 0.2032)
		(layer "B.Cu")
		(net "NetD17_2")
	)
	(segment
		(start 96.25686 83.7195)
		(end 96.37589 83.83853)
		(width 0.2032)
		(layer "B.Cu")
		(net "NetD17_2")
	)
	(segment
		(start 66.1216 128.8662)
		(end 67.0216 129.7662)
		(width 0.2032)
		(layer "B.Cu")
		(net "NetD17_2")
	)
	(segment
		(start 94.21486 83.06371)
		(end 94.21486 81.96371)
		(width 0.2032)
		(layer "B.Cu")
		(net "NetD17_2")
	)
	(segment
		(start 72.82161 129.7662)
		(end 74.07161 128.5162)
		(width 0.2032)
		(layer "B.Cu")
		(net "NetD17_2")
	)
	(segment
		(start 94.21486 81.96371)
		(end 96.25686 81.96371)
		(width 0.2032)
		(layer "B.Cu")
		(net "NetD17_2")
	)
	(segment
		(start 67.0216 129.7662)
		(end 72.82161 129.7662)
		(width 0.2032)
		(layer "B.Cu")
		(net "NetD17_2")
	)
	(segment
		(start 74.07161 128.5162)
		(end 78.71308 128.5162)
		(width 0.2032)
		(layer "B.Cu")
		(net "NetD17_2")
	)
	(segment
		(start 81.16557 126.06371)
		(end 100.33783 126.06371)
		(width 0.2032)
		(layer "B.Cu")
		(net "NetD17_2")
	)
	(segment
		(start 96.37589 83.83853)
		(end 100.21266 83.83853)
		(width 0.2032)
		(layer "B.Cu")
		(net "NetD17_2")
	)
	(segment
		(start 67.4216 113.3912)
		(end 67.4466 113.4162)
		(width 0.2032)
		(layer "F.Cu")
		(net "NetD16_4")
	)
	(segment
		(start 66.1466 113.3912)
		(end 67.4216 113.3912)
		(width 0.2032)
		(layer "F.Cu")
		(net "NetD16_4")
	)
	(segment
		(start 96.03187 86.06371)
		(end 97.20686 86.06371)
		(width 0.2032)
		(layer "F.Cu")
		(net "NetD16_4")
	)
	(segment
		(start 66.1216 113.3662)
		(end 66.1466 113.3912)
		(width 0.2032)
		(layer "F.Cu")
		(net "NetD16_4")
	)
	(segment
		(start 97.20686 86.07155)
		(end 97.20686 86.06371)
		(width 0.2032)
		(layer "F.Cu")
		(net "NetD16_4")
	)
	(via
		(at 97.20686 86.07155)
		(size 0.4064)
		(drill 0.2032)
		(layers "F.Cu" "B.Cu")
		(tenting
			(front yes)
			(back yes)
		)
		(net "NetD16_4")
	)
	(via
		(at 66.1216 113.3662)
		(size 0.4064)
		(drill 0.2032)
		(layers "F.Cu" "B.Cu")
		(tenting
			(front yes)
			(back yes)
		)
		(net "NetD16_4")
	)
	(segment
		(start 66.1216 113.3662)
		(end 73.9716 113.3662)
		(width 0.2032)
		(layer "B.Cu")
		(net "NetD16_4")
	)
	(segment
		(start 73.9716 113.3662)
		(end 74.6216 112.7162)
		(width 0.2032)
		(layer "B.Cu")
		(net "NetD16_4")
	)
	(segment
		(start 98.55686 105.56371)
		(end 98.55686 86.07155)
		(width 0.2032)
		(layer "B.Cu")
		(net "NetD16_4")
	)
	(segment
		(start 74.6216 112.7162)
		(end 74.6216 107.76782)
		(width 0.2032)
		(layer "B.Cu")
		(net "NetD16_4")
	)
	(segment
		(start 74.6216 107.76782)
		(end 76.82571 105.56371)
		(width 0.2032)
		(layer "B.Cu")
		(net "NetD16_4")
	)
	(segment
		(start 76.82571 105.56371)
		(end 98.55686 105.56371)
		(width 0.2032)
		(layer "B.Cu")
		(net "NetD16_4")
	)
	(segment
		(start 97.20686 86.07155)
		(end 98.55686 86.07155)
		(width 0.2032)
		(layer "B.Cu")
		(net "NetD16_4")
	)
	(segment
		(start 96.03187 85.56371)
		(end 97.70686 85.56371)
		(width 0.2032)
		(layer "F.Cu")
		(net "NetD16_3")
	)
	(segment
		(start 66.1216 114.3662)
		(end 67.1216 114.3662)
		(width 0.2032)
		(layer "F.Cu")
		(net "NetD16_3")
	)
	(segment
		(start 97.70686 85.56371)
		(end 97.70686 85.56355)
		(width 0.2032)
		(layer "F.Cu")
		(net "NetD16_3")
	)
	(via
		(at 66.1216 114.3662)
		(size 0.4064)
		(drill 0.2032)
		(layers "F.Cu" "B.Cu")
		(tenting
			(front yes)
			(back yes)
		)
		(net "NetD16_3")
	)
	(via
		(at 97.70686 85.56355)
		(size 0.4064)
		(drill 0.2032)
		(layers "F.Cu" "B.Cu")
		(tenting
			(front yes)
			(back yes)
		)
		(net "NetD16_3")
	)
	(segment
		(start 75.77395 113.6162)
		(end 75.77395 109.66385)
		(width 0.2032)
		(layer "B.Cu")
		(net "NetD16_3")
	)
	(segment
		(start 66.1216 114.3662)
		(end 75.02395 114.3662)
		(width 0.2032)
		(layer "B.Cu")
		(net "NetD16_3")
	)
	(segment
		(start 97.70686 85.56355)
		(end 98.80763 85.56355)
		(width 0.2032)
		(layer "B.Cu")
		(net "NetD16_3")
	)
	(segment
		(start 98.80763 85.56355)
		(end 98.92666 85.68258)
		(width 0.2032)
		(layer "B.Cu")
		(net "NetD16_3")
	)
	(segment
		(start 98.92666 105.9162)
		(end 98.92666 85.68258)
		(width 0.2032)
		(layer "B.Cu")
		(net "NetD16_3")
	)
	(segment
		(start 98.32666 106.5162)
		(end 98.92666 105.9162)
		(width 0.2032)
		(layer "B.Cu")
		(net "NetD16_3")
	)
	(segment
		(start 75.77395 109.66385)
		(end 78.9216 106.5162)
		(width 0.2032)
		(layer "B.Cu")
		(net "NetD16_3")
	)
	(segment
		(start 75.02395 114.3662)
		(end 75.77395 113.6162)
		(width 0.2032)
		(layer "B.Cu")
		(net "NetD16_3")
	)
	(segment
		(start 78.9216 106.5162)
		(end 98.32666 106.5162)
		(width 0.2032)
		(layer "B.Cu")
		(net "NetD16_3")
	)
	(segment
		(start 97.20686 85.06371)
		(end 97.20686 85.02371)
		(width 0.2032)
		(layer "F.Cu")
		(net "NetD16_2")
	)
	(segment
		(start 67.06048 115.32732)
		(end 67.1216 115.2662)
		(width 0.2032)
		(layer "F.Cu")
		(net "NetD16_2")
	)
	(segment
		(start 66.1216 115.3662)
		(end 66.16048 115.32732)
		(width 0.2032)
		(layer "F.Cu")
		(net "NetD16_2")
	)
	(segment
		(start 96.03187 85.06371)
		(end 97.20686 85.06371)
		(width 0.2032)
		(layer "F.Cu")
		(net "NetD16_2")
	)
	(segment
		(start 66.16048 115.32732)
		(end 67.06048 115.32732)
		(width 0.2032)
		(layer "F.Cu")
		(net "NetD16_2")
	)
	(via
		(at 97.20686 85.02371)
		(size 0.4064)
		(drill 0.2032)
		(layers "F.Cu" "B.Cu")
		(tenting
			(front yes)
			(back yes)
		)
		(net "NetD16_2")
	)
	(via
		(at 66.1216 115.3662)
		(size 0.4064)
		(drill 0.2032)
		(layers "F.Cu" "B.Cu")
		(tenting
			(front yes)
			(back yes)
		)
		(net "NetD16_2")
	)
	(segment
		(start 78.27186 107.86371)
		(end 99.13783 107.86371)
		(width 0.2032)
		(layer "B.Cu")
		(net "NetD16_2")
	)
	(segment
		(start 75.8216 116.3162)
		(end 78.27186 113.86594)
		(width 0.2032)
		(layer "B.Cu")
		(net "NetD16_2")
	)
	(segment
		(start 99.25686 107.74468)
		(end 99.25686 85.14274)
		(width 0.2032)
		(layer "B.Cu")
		(net "NetD16_2")
	)
	(segment
		(start 66.1216 115.3662)
		(end 67.0716 116.3162)
		(width 0.2032)
		(layer "B.Cu")
		(net "NetD16_2")
	)
	(segment
		(start 99.13783 107.86371)
		(end 99.25686 107.74468)
		(width 0.2032)
		(layer "B.Cu")
		(net "NetD16_2")
	)
	(segment
		(start 97.20686 85.02371)
		(end 99.13783 85.02371)
		(width 0.2032)
		(layer "B.Cu")
		(net "NetD16_2")
	)
	(segment
		(start 78.27186 113.86594)
		(end 78.27186 107.86371)
		(width 0.2032)
		(layer "B.Cu")
		(net "NetD16_2")
	)
	(segment
		(start 67.0716 116.3162)
		(end 75.8216 116.3162)
		(width 0.2032)
		(layer "B.Cu")
		(net "NetD16_2")
	)
	(segment
		(start 99.13783 85.02371)
		(end 99.25686 85.14274)
		(width 0.2032)
		(layer "B.Cu")
		(net "NetD16_2")
	)
	(segment
		(start 66.16048 100.07732)
		(end 67.38548 100.07732)
		(width 0.2032)
		(layer "F.Cu")
		(net "NetD15_4")
	)
	(segment
		(start 96.03187 88.06371)
		(end 97.20686 88.06371)
		(width 0.2032)
		(layer "F.Cu")
		(net "NetD15_4")
	)
	(segment
		(start 97.20686 88.10371)
		(end 97.20686 88.06371)
		(width 0.2032)
		(layer "F.Cu")
		(net "NetD15_4")
	)
	(segment
		(start 66.1216 100.1162)
		(end 66.16048 100.07732)
		(width 0.2032)
		(layer "F.Cu")
		(net "NetD15_4")
	)
	(segment
		(start 67.38548 100.07732)
		(end 67.4466 100.0162)
		(width 0.2032)
		(layer "F.Cu")
		(net "NetD15_4")
	)
	(via
		(at 97.20686 88.10371)
		(size 0.4064)
		(drill 0.2032)
		(layers "F.Cu" "B.Cu")
		(tenting
			(front yes)
			(back yes)
		)
		(net "NetD15_4")
	)
	(via
		(at 66.1216 100.1162)
		(size 0.4064)
		(drill 0.2032)
		(layers "F.Cu" "B.Cu")
		(tenting
			(front yes)
			(back yes)
		)
		(net "NetD15_4")
	)
	(segment
		(start 80.21831 100.36371)
		(end 97.20686 100.36371)
		(width 0.2032)
		(layer "B.Cu")
		(net "NetD15_4")
	)
	(segment
		(start 66.1216 100.1162)
		(end 66.5216 99.7162)
		(width 0.2032)
		(layer "B.Cu")
		(net "NetD15_4")
	)
	(segment
		(start 73.2216 99.7162)
		(end 74.34671 98.59109)
		(width 0.2032)
		(layer "B.Cu")
		(net "NetD15_4")
	)
	(segment
		(start 74.34671 98.59109)
		(end 74.34671 93.26371)
		(width 0.2032)
		(layer "B.Cu")
		(net "NetD15_4")
	)
	(segment
		(start 74.34671 93.26371)
		(end 80.21831 93.26371)
		(width 0.2032)
		(layer "B.Cu")
		(net "NetD15_4")
	)
	(segment
		(start 97.20686 100.36371)
		(end 97.20686 88.10371)
		(width 0.2032)
		(layer "B.Cu")
		(net "NetD15_4")
	)
	(segment
		(start 80.21831 100.36371)
		(end 80.21831 93.26371)
		(width 0.2032)
		(layer "B.Cu")
		(net "NetD15_4")
	)
	(segment
		(start 66.5216 99.7162)
		(end 73.2216 99.7162)
		(width 0.2032)
		(layer "B.Cu")
		(net "NetD15_4")
	)
	(segment
		(start 97.70686 87.59555)
		(end 97.70686 87.56371)
		(width 0.2032)
		(layer "F.Cu")
		(net "NetD15_3")
	)
	(segment
		(start 96.03187 87.56371)
		(end 97.70686 87.56371)
		(width 0.2032)
		(layer "F.Cu")
		(net "NetD15_3")
	)
	(segment
		(start 66.16048 101.07732)
		(end 67.01048 101.07732)
		(width 0.2032)
		(layer "F.Cu")
		(net "NetD15_3")
	)
	(segment
		(start 66.1216 101.1162)
		(end 66.16048 101.07732)
		(width 0.2032)
		(layer "F.Cu")
		(net "NetD15_3")
	)
	(segment
		(start 67.01048 101.07732)
		(end 67.1216 100.9662)
		(width 0.2032)
		(layer "F.Cu")
		(net "NetD15_3")
	)
	(via
		(at 97.70686 87.59555)
		(size 0.4064)
		(drill 0.2032)
		(layers "F.Cu" "B.Cu")
		(tenting
			(front yes)
			(back yes)
		)
		(net "NetD15_3")
	)
	(via
		(at 66.1216 101.1162)
		(size 0.4064)
		(drill 0.2032)
		(layers "F.Cu" "B.Cu")
		(tenting
			(front yes)
			(back yes)
		)
		(net "NetD15_3")
	)
	(segment
		(start 74.67691 98.72786)
		(end 74.67691 94.1386)
		(width 0.2032)
		(layer "B.Cu")
		(net "NetD15_3")
	)
	(segment
		(start 97.6216 98.7162)
		(end 97.70686 98.63093)
		(width 0.2032)
		(layer "B.Cu")
		(net "NetD15_3")
	)
	(segment
		(start 72.28857 101.1162)
		(end 74.67691 98.72786)
		(width 0.2032)
		(layer "B.Cu")
		(net "NetD15_3")
	)
	(segment
		(start 97.6216 100.41594)
		(end 97.6216 98.7162)
		(width 0.2032)
		(layer "B.Cu")
		(net "NetD15_3")
	)
	(segment
		(start 79.85611 100.55071)
		(end 79.99931 100.69391)
		(width 0.2032)
		(layer "B.Cu")
		(net "NetD15_3")
	)
	(segment
		(start 97.34363 100.69391)
		(end 97.6216 100.41594)
		(width 0.2032)
		(layer "B.Cu")
		(net "NetD15_3")
	)
	(segment
		(start 97.70686 98.63093)
		(end 97.70686 87.59555)
		(width 0.2032)
		(layer "B.Cu")
		(net "NetD15_3")
	)
	(segment
		(start 79.99931 100.69391)
		(end 97.34363 100.69391)
		(width 0.2032)
		(layer "B.Cu")
		(net "NetD15_3")
	)
	(segment
		(start 66.1216 101.1162)
		(end 72.28857 101.1162)
		(width 0.2032)
		(layer "B.Cu")
		(net "NetD15_3")
	)
	(segment
		(start 79.85611 100.55071)
		(end 79.85611 93.78809)
		(width 0.2032)
		(layer "B.Cu")
		(net "NetD15_3")
	)
	(segment
		(start 79.66192 93.59391)
		(end 79.85611 93.78809)
		(width 0.2032)
		(layer "B.Cu")
		(net "NetD15_3")
	)
	(segment
		(start 75.2216 93.59391)
		(end 79.66192 93.59391)
		(width 0.2032)
		(layer "B.Cu")
		(net "NetD15_3")
	)
	(segment
		(start 74.67691 94.1386)
		(end 75.2216 93.59391)
		(width 0.2032)
		(layer "B.Cu")
		(net "NetD15_3")
	)
	(segment
		(start 96.03187 87.06371)
		(end 97.20686 87.06371)
		(width 0.2032)
		(layer "F.Cu")
		(net "NetD15_2")
	)
	(segment
		(start 97.20686 87.08755)
		(end 97.20686 87.06371)
		(width 0.2032)
		(layer "F.Cu")
		(net "NetD15_2")
	)
	(segment
		(start 66.1216 101.8662)
		(end 67.1216 101.8662)
		(width 0.2032)
		(layer "F.Cu")
		(net "NetD15_2")
	)
	(via
		(at 97.20686 87.08755)
		(size 0.4064)
		(drill 0.2032)
		(layers "F.Cu" "B.Cu")
		(tenting
			(front yes)
			(back yes)
		)
		(net "NetD15_2")
	)
	(via
		(at 66.1216 101.8662)
		(size 0.4064)
		(drill 0.2032)
		(layers "F.Cu" "B.Cu")
		(tenting
			(front yes)
			(back yes)
		)
		(net "NetD15_2")
	)
	(segment
		(start 72.45847 101.8662)
		(end 75.51115 98.81352)
		(width 0.2032)
		(layer "B.Cu")
		(net "NetD15_2")
	)
	(segment
		(start 97.20686 87.08755)
		(end 98.15686 87.08755)
		(width 0.2032)
		(layer "B.Cu")
		(net "NetD15_2")
	)
	(segment
		(start 98.15686 101.16371)
		(end 98.15686 87.08755)
		(width 0.2032)
		(layer "B.Cu")
		(net "NetD15_2")
	)
	(segment
		(start 79.52591 101.16371)
		(end 79.52591 93.92486)
		(width 0.2032)
		(layer "B.Cu")
		(net "NetD15_2")
	)
	(segment
		(start 75.51115 93.92486)
		(end 79.52591 93.92486)
		(width 0.2032)
		(layer "B.Cu")
		(net "NetD15_2")
	)
	(segment
		(start 75.51115 98.81352)
		(end 75.51115 93.92486)
		(width 0.2032)
		(layer "B.Cu")
		(net "NetD15_2")
	)
	(segment
		(start 79.52591 101.16371)
		(end 98.15686 101.16371)
		(width 0.2032)
		(layer "B.Cu")
		(net "NetD15_2")
	)
	(segment
		(start 66.1216 101.8662)
		(end 72.45847 101.8662)
		(width 0.2032)
		(layer "B.Cu")
		(net "NetD15_2")
	)
	(segment
		(start 67.33548 81.15508)
		(end 67.4466 81.2662)
		(width 0.2032)
		(layer "F.Cu")
		(net "NetD14_4")
	)
	(segment
		(start 66.16048 81.15508)
		(end 67.33548 81.15508)
		(width 0.2032)
		(layer "F.Cu")
		(net "NetD14_4")
	)
	(segment
		(start 66.1216 81.1162)
		(end 66.16048 81.15508)
		(width 0.2032)
		(layer "F.Cu")
		(net "NetD14_4")
	)
	(segment
		(start 94.20686 90.15191)
		(end 94.20686 88.8887)
		(width 0.2032)
		(layer "F.Cu")
		(net "NetD14_4")
	)
	(segment
		(start 94.20686 90.15191)
		(end 94.23086 90.15191)
		(width 0.2032)
		(layer "F.Cu")
		(net "NetD14_4")
	)
	(via
		(at 66.1216 81.1162)
		(size 0.4064)
		(drill 0.2032)
		(layers "F.Cu" "B.Cu")
		(tenting
			(front yes)
			(back yes)
		)
		(net "NetD14_4")
	)
	(via
		(at 94.23086 90.15191)
		(size 0.4064)
		(drill 0.2032)
		(layers "F.Cu" "B.Cu")
		(tenting
			(front yes)
			(back yes)
		)
		(net "NetD14_4")
	)
	(segment
		(start 90.74706 90.7045)
		(end 91.36826 91.32571)
		(width 0.2032)
		(layer "B.Cu")
		(net "NetD14_4")
	)
	(segment
		(start 93.57152 91.32571)
		(end 94.23086 90.66636)
		(width 0.2032)
		(layer "B.Cu")
		(net "NetD14_4")
	)
	(segment
		(start 94.23086 90.66636)
		(end 94.23086 90.15191)
		(width 0.2032)
		(layer "B.Cu")
		(net "NetD14_4")
	)
	(segment
		(start 85.7316 90.7045)
		(end 90.74706 90.7045)
		(width 0.2032)
		(layer "B.Cu")
		(net "NetD14_4")
	)
	(segment
		(start 76.1433 81.1162)
		(end 85.7316 90.7045)
		(width 0.2032)
		(layer "B.Cu")
		(net "NetD14_4")
	)
	(segment
		(start 91.36826 91.32571)
		(end 93.57152 91.32571)
		(width 0.2032)
		(layer "B.Cu")
		(net "NetD14_4")
	)
	(segment
		(start 66.1216 81.1162)
		(end 76.1433 81.1162)
		(width 0.2032)
		(layer "B.Cu")
		(net "NetD14_4")
	)
	(segment
		(start 66.16048 82.15508)
		(end 67.06048 82.15508)
		(width 0.2032)
		(layer "F.Cu")
		(net "NetD14_3")
	)
	(segment
		(start 66.1216 82.1162)
		(end 66.16048 82.15508)
		(width 0.2032)
		(layer "F.Cu")
		(net "NetD14_3")
	)
	(segment
		(start 94.70686 88.8887)
		(end 94.73886 88.8887)
		(width 0.2032)
		(layer "F.Cu")
		(net "NetD14_3")
	)
	(segment
		(start 67.06048 82.15508)
		(end 67.1216 82.2162)
		(width 0.2032)
		(layer "F.Cu")
		(net "NetD14_3")
	)
	(segment
		(start 94.73886 90.56371)
		(end 94.73886 88.8887)
		(width 0.2032)
		(layer "F.Cu")
		(net "NetD14_3")
	)
	(via
		(at 94.73886 90.56371)
		(size 0.4064)
		(drill 0.2032)
		(layers "F.Cu" "B.Cu")
		(tenting
			(front yes)
			(back yes)
		)
		(net "NetD14_3")
	)
	(via
		(at 66.1216 82.1162)
		(size 0.4064)
		(drill 0.2032)
		(layers "F.Cu" "B.Cu")
		(tenting
			(front yes)
			(back yes)
		)
		(net "NetD14_3")
	)
	(segment
		(start 66.1216 82.1162)
		(end 76.67633 82.1162)
		(width 0.2032)
		(layer "B.Cu")
		(net "NetD14_3")
	)
	(segment
		(start 91.13584 91.65591)
		(end 93.70829 91.65591)
		(width 0.2032)
		(layer "B.Cu")
		(net "NetD14_3")
	)
	(segment
		(start 93.70829 91.65591)
		(end 94.3295 91.0347)
		(width 0.2032)
		(layer "B.Cu")
		(net "NetD14_3")
	)
	(segment
		(start 94.3295 91.0347)
		(end 94.61983 91.0347)
		(width 0.2032)
		(layer "B.Cu")
		(net "NetD14_3")
	)
	(segment
		(start 76.67633 82.1162)
		(end 85.59483 91.0347)
		(width 0.2032)
		(layer "B.Cu")
		(net "NetD14_3")
	)
	(segment
		(start 94.73886 90.91567)
		(end 94.73886 90.56371)
		(width 0.2032)
		(layer "B.Cu")
		(net "NetD14_3")
	)
	(segment
		(start 85.59483 91.0347)
		(end 90.51464 91.0347)
		(width 0.2032)
		(layer "B.Cu")
		(net "NetD14_3")
	)
	(segment
		(start 90.51464 91.0347)
		(end 91.13584 91.65591)
		(width 0.2032)
		(layer "B.Cu")
		(net "NetD14_3")
	)
	(segment
		(start 94.61983 91.0347)
		(end 94.73886 90.91567)
		(width 0.2032)
		(layer "B.Cu")
		(net "NetD14_3")
	)
	(segment
		(start 95.20686 90.15191)
		(end 95.24686 90.15191)
		(width 0.2032)
		(layer "F.Cu")
		(net "NetD14_2")
	)
	(segment
		(start 95.20686 90.15191)
		(end 95.20686 88.8887)
		(width 0.2032)
		(layer "F.Cu")
		(net "NetD14_2")
	)
	(segment
		(start 66.1216 83.1162)
		(end 67.1216 83.1162)
		(width 0.2032)
		(layer "F.Cu")
		(net "NetD14_2")
	)
	(via
		(at 95.24686 90.15191)
		(size 0.4064)
		(drill 0.2032)
		(layers "F.Cu" "B.Cu")
		(tenting
			(front yes)
			(back yes)
		)
		(net "NetD14_2")
	)
	(via
		(at 66.1216 83.1162)
		(size 0.4064)
		(drill 0.2032)
		(layers "F.Cu" "B.Cu")
		(tenting
			(front yes)
			(back yes)
		)
		(net "NetD14_2")
	)
	(segment
		(start 95.00201 91.3649)
		(end 95.24686 91.12005)
		(width 0.2032)
		(layer "B.Cu")
		(net "NetD14_2")
	)
	(segment
		(start 90.92667 91.98611)
		(end 93.84506 91.98611)
		(width 0.2032)
		(layer "B.Cu")
		(net "NetD14_2")
	)
	(segment
		(start 93.84506 91.98611)
		(end 94.46627 91.3649)
		(width 0.2032)
		(layer "B.Cu")
		(net "NetD14_2")
	)
	(segment
		(start 94.46627 91.3649)
		(end 95.00201 91.3649)
		(width 0.2032)
		(layer "B.Cu")
		(net "NetD14_2")
	)
	(segment
		(start 85.45806 91.3649)
		(end 90.30546 91.3649)
		(width 0.2032)
		(layer "B.Cu")
		(net "NetD14_2")
	)
	(segment
		(start 90.30546 91.3649)
		(end 90.92667 91.98611)
		(width 0.2032)
		(layer "B.Cu")
		(net "NetD14_2")
	)
	(segment
		(start 66.1216 83.1162)
		(end 77.20936 83.1162)
		(width 0.2032)
		(layer "B.Cu")
		(net "NetD14_2")
	)
	(segment
		(start 95.24686 91.12005)
		(end 95.24686 90.15191)
		(width 0.2032)
		(layer "B.Cu")
		(net "NetD14_2")
	)
	(segment
		(start 77.20936 83.1162)
		(end 85.45806 91.3649)
		(width 0.2032)
		(layer "B.Cu")
		(net "NetD14_2")
	)
	(segment
		(start 66.1216 70.3662)
		(end 66.16048 70.32732)
		(width 0.2032)
		(layer "F.Cu")
		(net "NetD13_4")
	)
	(segment
		(start 92.20686 90.15191)
		(end 92.20686 88.8887)
		(width 0.2032)
		(layer "F.Cu")
		(net "NetD13_4")
	)
	(segment
		(start 92.19886 90.15191)
		(end 92.20686 90.15191)
		(width 0.2032)
		(layer "F.Cu")
		(net "NetD13_4")
	)
	(segment
		(start 66.16048 70.32732)
		(end 67.38548 70.32732)
		(width 0.2032)
		(layer "F.Cu")
		(net "NetD13_4")
	)
	(segment
		(start 67.38548 70.32732)
		(end 67.4466 70.2662)
		(width 0.2032)
		(layer "F.Cu")
		(net "NetD13_4")
	)
	(via
		(at 92.19886 90.15191)
		(size 0.4064)
		(drill 0.2032)
		(layers "F.Cu" "B.Cu")
		(tenting
			(front yes)
			(back yes)
		)
		(net "NetD13_4")
	)
	(via
		(at 66.1216 70.3662)
		(size 0.4064)
		(drill 0.2032)
		(layers "F.Cu" "B.Cu")
		(tenting
			(front yes)
			(back yes)
		)
		(net "NetD13_4")
	)
	(segment
		(start 74.0716 70.3662)
		(end 92.19886 88.49347)
		(width 0.2032)
		(layer "B.Cu")
		(net "NetD13_4")
	)
	(segment
		(start 66.1216 70.3662)
		(end 74.0716 70.3662)
		(width 0.2032)
		(layer "B.Cu")
		(net "NetD13_4")
	)
	(segment
		(start 92.19886 90.15191)
		(end 92.19886 88.49347)
		(width 0.2032)
		(layer "B.Cu")
		(net "NetD13_4")
	)
	(segment
		(start 67.06048 71.15508)
		(end 67.1216 71.2162)
		(width 0.2032)
		(layer "F.Cu")
		(net "NetD13_3")
	)
	(segment
		(start 66.1216 71.1162)
		(end 66.16048 71.15508)
		(width 0.2032)
		(layer "F.Cu")
		(net "NetD13_3")
	)
	(segment
		(start 92.70686 90.56371)
		(end 92.70686 88.8887)
		(width 0.2032)
		(layer "F.Cu")
		(net "NetD13_3")
	)
	(segment
		(start 66.16048 71.15508)
		(end 67.06048 71.15508)
		(width 0.2032)
		(layer "F.Cu")
		(net "NetD13_3")
	)
	(via
		(at 66.1216 71.1162)
		(size 0.4064)
		(drill 0.2032)
		(layers "F.Cu" "B.Cu")
		(tenting
			(front yes)
			(back yes)
		)
		(net "NetD13_3")
	)
	(via
		(at 92.70686 90.56371)
		(size 0.4064)
		(drill 0.2032)
		(layers "F.Cu" "B.Cu")
		(tenting
			(front yes)
			(back yes)
		)
		(net "NetD13_3")
	)
	(segment
		(start 91.6216 90.1853)
		(end 91.6216 88.6162)
		(width 0.2032)
		(layer "B.Cu")
		(net "NetD13_3")
	)
	(segment
		(start 74.1216 71.1162)
		(end 91.6216 88.6162)
		(width 0.2032)
		(layer "B.Cu")
		(net "NetD13_3")
	)
	(segment
		(start 66.1216 71.1162)
		(end 74.1216 71.1162)
		(width 0.2032)
		(layer "B.Cu")
		(net "NetD13_3")
	)
	(segment
		(start 91.6216 90.1853)
		(end 92.02001 90.58371)
		(width 0.2032)
		(layer "B.Cu")
		(net "NetD13_3")
	)
	(segment
		(start 92.02001 90.58371)
		(end 92.68686 90.58371)
		(width 0.2032)
		(layer "B.Cu")
		(net "NetD13_3")
	)
	(segment
		(start 92.68686 90.58371)
		(end 92.70686 90.56371)
		(width 0.2032)
		(layer "B.Cu")
		(net "NetD13_3")
	)
	(segment
		(start 93.20686 90.15191)
		(end 93.20686 88.8887)
		(width 0.2032)
		(layer "F.Cu")
		(net "NetD13_2")
	)
	(segment
		(start 66.1216 72.1162)
		(end 67.1216 72.1162)
		(width 0.2032)
		(layer "F.Cu")
		(net "NetD13_2")
	)
	(segment
		(start 93.20686 90.15191)
		(end 93.21486 90.15191)
		(width 0.2032)
		(layer "F.Cu")
		(net "NetD13_2")
	)
	(via
		(at 66.1216 72.1162)
		(size 0.4064)
		(drill 0.2032)
		(layers "F.Cu" "B.Cu")
		(tenting
			(front yes)
			(back yes)
		)
		(net "NetD13_2")
	)
	(via
		(at 93.21486 90.15191)
		(size 0.4064)
		(drill 0.2032)
		(layers "F.Cu" "B.Cu")
		(tenting
			(front yes)
			(back yes)
		)
		(net "NetD13_2")
	)
	(segment
		(start 66.1216 72.1162)
		(end 74.3216 72.1162)
		(width 0.2032)
		(layer "B.Cu")
		(net "NetD13_2")
	)
	(segment
		(start 74.3216 72.1162)
		(end 91.1216 88.9162)
		(width 0.2032)
		(layer "B.Cu")
		(net "NetD13_2")
	)
	(segment
		(start 93.21486 90.66636)
		(end 93.21486 90.15191)
		(width 0.2032)
		(layer "B.Cu")
		(net "NetD13_2")
	)
	(segment
		(start 91.1216 90.15227)
		(end 91.1216 88.9162)
		(width 0.2032)
		(layer "B.Cu")
		(net "NetD13_2")
	)
	(segment
		(start 91.1216 90.15227)
		(end 91.96484 90.99551)
		(width 0.2032)
		(layer "B.Cu")
		(net "NetD13_2")
	)
	(segment
		(start 92.88572 90.99551)
		(end 93.21486 90.66636)
		(width 0.2032)
		(layer "B.Cu")
		(net "NetD13_2")
	)
	(segment
		(start 91.96484 90.99551)
		(end 92.88572 90.99551)
		(width 0.2032)
		(layer "B.Cu")
		(net "NetD13_2")
	)
	(segment
		(start 134.10467 120.77447)
		(end 134.10467 120.7207)
		(width 0.2032)
		(layer "F.Cu")
		(net "EXT_GPIO_10")
	)
	(segment
		(start 134.10467 120.7207)
		(end 136.41149 120.7207)
		(width 0.2032)
		(layer "F.Cu")
		(net "EXT_GPIO_10")
	)
	(via
		(at 134.10467 120.77447)
		(size 0.4064)
		(drill 0.2032)
		(layers "F.Cu" "B.Cu")
		(tenting
			(front yes)
			(back yes)
		)
		(net "EXT_GPIO_10")
	)
	(segment
		(start 148.22417 134.7051)
		(end 156.36779 134.7051)
		(width 0.2032)
		(layer "In3.Cu")
		(net "EXT_GPIO_10")
	)
	(segment
		(start 136.2326 120.77447)
		(end 137.37432 121.9162)
		(width 0.2032)
		(layer "In3.Cu")
		(net "EXT_GPIO_10")
	)
	(segment
		(start 223.8914 97.9464)
		(end 228.2216 93.6162)
		(width 0.2032)
		(layer "In3.Cu")
		(net "EXT_GPIO_10")
	)
	(segment
		(start 223.8716 114.20703)
		(end 223.8716 98.4662)
		(width 0.2032)
		(layer "In3.Cu")
		(net "EXT_GPIO_10")
	)
	(segment
		(start 212.2914 143.186)
		(end 225.96517 143.186)
		(width 0.2032)
		(layer "In3.Cu")
		(net "EXT_GPIO_10")
	)
	(segment
		(start 173.41705 134.04468)
		(end 182.37724 143.00487)
		(width 0.2032)
		(layer "In3.Cu")
		(net "EXT_GPIO_10")
	)
	(segment
		(start 138.99426 121.9162)
		(end 140.51465 123.43659)
		(width 0.2032)
		(layer "In3.Cu")
		(net "EXT_GPIO_10")
	)
	(segment
		(start 226.50513 119.99446)
		(end 228.2216 121.71093)
		(width 0.2032)
		(layer "In3.Cu")
		(net "EXT_GPIO_10")
	)
	(segment
		(start 156.36779 134.7051)
		(end 156.36782 134.70508)
		(width 0.2032)
		(layer "In3.Cu")
		(net "EXT_GPIO_10")
	)
	(segment
		(start 206.53069 142.30711)
		(end 211.41251 142.30711)
		(width 0.2032)
		(layer "In3.Cu")
		(net "EXT_GPIO_10")
	)
	(segment
		(start 137.37432 121.9162)
		(end 138.99426 121.9162)
		(width 0.2032)
		(layer "In3.Cu")
		(net "EXT_GPIO_10")
	)
	(segment
		(start 140.63368 134.70925)
		(end 148.22002 134.70925)
		(width 0.2032)
		(layer "In3.Cu")
		(net "EXT_GPIO_10")
	)
	(segment
		(start 205.83293 143.00487)
		(end 206.53069 142.30711)
		(width 0.2032)
		(layer "In3.Cu")
		(net "EXT_GPIO_10")
	)
	(segment
		(start 226.67828 142.47289)
		(end 226.67828 139.07763)
		(width 0.2032)
		(layer "In3.Cu")
		(net "EXT_GPIO_10")
	)
	(segment
		(start 182.37724 143.00487)
		(end 205.83293 143.00487)
		(width 0.2032)
		(layer "In3.Cu")
		(net "EXT_GPIO_10")
	)
	(segment
		(start 156.36782 134.70508)
		(end 163.86413 134.70508)
		(width 0.2032)
		(layer "In3.Cu")
		(net "EXT_GPIO_10")
	)
	(segment
		(start 223.8914 98.4464)
		(end 223.8914 97.9464)
		(width 0.2032)
		(layer "In3.Cu")
		(net "EXT_GPIO_10")
	)
	(segment
		(start 228.2216 137.53432)
		(end 228.2216 121.71093)
		(width 0.2032)
		(layer "In3.Cu")
		(net "EXT_GPIO_10")
	)
	(segment
		(start 223.8716 114.20703)
		(end 226.50513 116.84056)
		(width 0.2032)
		(layer "In3.Cu")
		(net "EXT_GPIO_10")
	)
	(segment
		(start 228.2216 93.6162)
		(end 228.2216 88.9162)
		(width 0.2032)
		(layer "In3.Cu")
		(net "EXT_GPIO_10")
	)
	(segment
		(start 226.50513 119.99446)
		(end 226.50513 116.84056)
		(width 0.2032)
		(layer "In3.Cu")
		(net "EXT_GPIO_10")
	)
	(segment
		(start 163.86413 134.70508)
		(end 164.52453 134.04468)
		(width 0.2032)
		(layer "In3.Cu")
		(net "EXT_GPIO_10")
	)
	(segment
		(start 226.67828 139.07763)
		(end 228.2216 137.53432)
		(width 0.2032)
		(layer "In3.Cu")
		(net "EXT_GPIO_10")
	)
	(segment
		(start 164.52453 134.04468)
		(end 173.41705 134.04468)
		(width 0.2032)
		(layer "In3.Cu")
		(net "EXT_GPIO_10")
	)
	(segment
		(start 140.51465 134.59022)
		(end 140.51465 123.43659)
		(width 0.2032)
		(layer "In3.Cu")
		(net "EXT_GPIO_10")
	)
	(segment
		(start 140.51465 134.59022)
		(end 140.63368 134.70925)
		(width 0.2032)
		(layer "In3.Cu")
		(net "EXT_GPIO_10")
	)
	(segment
		(start 228.2216 88.9162)
		(end 229.4616 87.6762)
		(width 0.2032)
		(layer "In3.Cu")
		(net "EXT_GPIO_10")
	)
	(segment
		(start 211.41251 142.30711)
		(end 212.2914 143.186)
		(width 0.2032)
		(layer "In3.Cu")
		(net "EXT_GPIO_10")
	)
	(segment
		(start 148.22002 134.70925)
		(end 148.22417 134.7051)
		(width 0.2032)
		(layer "In3.Cu")
		(net "EXT_GPIO_10")
	)
	(segment
		(start 223.8716 98.4662)
		(end 223.8914 98.4464)
		(width 0.2032)
		(layer "In3.Cu")
		(net "EXT_GPIO_10")
	)
	(segment
		(start 225.96517 143.186)
		(end 226.67828 142.47289)
		(width 0.2032)
		(layer "In3.Cu")
		(net "EXT_GPIO_10")
	)
	(segment
		(start 134.10467 120.77447)
		(end 136.2326 120.77447)
		(width 0.2032)
		(layer "In3.Cu")
		(net "EXT_GPIO_10")
	)
	(segment
		(start 134.59667 121.22057)
		(end 136.41149 121.22057)
		(width 0.2032)
		(layer "F.Cu")
		(net "EXT_GPIO_9")
	)
	(segment
		(start 134.59667 121.28247)
		(end 134.59667 121.22057)
		(width 0.2032)
		(layer "F.Cu")
		(net "EXT_GPIO_9")
	)
	(via
		(at 134.59667 121.28247)
		(size 0.4064)
		(drill 0.2032)
		(layers "F.Cu" "B.Cu")
		(tenting
			(front yes)
			(back yes)
		)
		(net "EXT_GPIO_9")
	)
	(segment
		(start 226.05734 143.5608)
		(end 227.0116 142.60654)
		(width 0.2032)
		(layer "In3.Cu")
		(net "EXT_GPIO_9")
	)
	(segment
		(start 226.83533 119.85769)
		(end 226.83533 115.74451)
		(width 0.2032)
		(layer "In3.Cu")
		(net "EXT_GPIO_9")
	)
	(segment
		(start 225.255 143.5608)
		(end 226.05734 143.5608)
		(width 0.2032)
		(layer "In3.Cu")
		(net "EXT_GPIO_9")
	)
	(segment
		(start 228.12404 121.1464)
		(end 230.22362 121.1464)
		(width 0.2032)
		(layer "In3.Cu")
		(net "EXT_GPIO_9")
	)
	(segment
		(start 138.14708 123.3162)
		(end 138.96887 123.3162)
		(width 0.2032)
		(layer "In3.Cu")
		(net "EXT_GPIO_9")
	)
	(segment
		(start 227.0116 142.60654)
		(end 227.0116 139.21129)
		(width 0.2032)
		(layer "In3.Cu")
		(net "EXT_GPIO_9")
	)
	(segment
		(start 230.5216 93.1162)
		(end 230.5216 86.1962)
		(width 0.2032)
		(layer "In3.Cu")
		(net "EXT_GPIO_9")
	)
	(segment
		(start 225.2104 143.5162)
		(end 225.255 143.5608)
		(width 0.2032)
		(layer "In3.Cu")
		(net "EXT_GPIO_9")
	)
	(segment
		(start 229.18059 137.04229)
		(end 229.22866 137.04229)
		(width 0.2032)
		(layer "In3.Cu")
		(net "EXT_GPIO_9")
	)
	(segment
		(start 227.0116 139.21129)
		(end 229.18059 137.04229)
		(width 0.2032)
		(layer "In3.Cu")
		(net "EXT_GPIO_9")
	)
	(segment
		(start 140.90447 135.58004)
		(end 163.55776 135.58004)
		(width 0.2032)
		(layer "In3.Cu")
		(net "EXT_GPIO_9")
	)
	(segment
		(start 138.96887 123.3162)
		(end 140.18445 124.53179)
		(width 0.2032)
		(layer "In3.Cu")
		(net "EXT_GPIO_9")
	)
	(segment
		(start 163.55776 135.58004)
		(end 164.76293 134.37488)
		(width 0.2032)
		(layer "In3.Cu")
		(net "EXT_GPIO_9")
	)
	(segment
		(start 136.14991 121.45227)
		(end 136.28315 121.45227)
		(width 0.2032)
		(layer "In3.Cu")
		(net "EXT_GPIO_9")
	)
	(segment
		(start 224.2216 113.13078)
		(end 226.83533 115.74451)
		(width 0.2032)
		(layer "In3.Cu")
		(net "EXT_GPIO_9")
	)
	(segment
		(start 173.28027 134.37488)
		(end 182.4216 143.5162)
		(width 0.2032)
		(layer "In3.Cu")
		(net "EXT_GPIO_9")
	)
	(segment
		(start 164.76293 134.37488)
		(end 173.28027 134.37488)
		(width 0.2032)
		(layer "In3.Cu")
		(net "EXT_GPIO_9")
	)
	(segment
		(start 229.4616 85.1362)
		(end 230.5216 86.1962)
		(width 0.2032)
		(layer "In3.Cu")
		(net "EXT_GPIO_9")
	)
	(segment
		(start 134.59667 121.28247)
		(end 135.98011 121.28247)
		(width 0.2032)
		(layer "In3.Cu")
		(net "EXT_GPIO_9")
	)
	(segment
		(start 228.30129 94.23651)
		(end 229.40129 94.23651)
		(width 0.2032)
		(layer "In3.Cu")
		(net "EXT_GPIO_9")
	)
	(segment
		(start 136.28315 121.45227)
		(end 138.14708 123.3162)
		(width 0.2032)
		(layer "In3.Cu")
		(net "EXT_GPIO_9")
	)
	(segment
		(start 140.18445 134.86002)
		(end 140.90447 135.58004)
		(width 0.2032)
		(layer "In3.Cu")
		(net "EXT_GPIO_9")
	)
	(segment
		(start 224.2216 113.13078)
		(end 224.2216 98.3162)
		(width 0.2032)
		(layer "In3.Cu")
		(net "EXT_GPIO_9")
	)
	(segment
		(start 229.22866 137.04229)
		(end 230.9612 135.30976)
		(width 0.2032)
		(layer "In3.Cu")
		(net "EXT_GPIO_9")
	)
	(segment
		(start 229.40129 94.23651)
		(end 230.5216 93.1162)
		(width 0.2032)
		(layer "In3.Cu")
		(net "EXT_GPIO_9")
	)
	(segment
		(start 230.22362 121.1464)
		(end 230.9612 121.88398)
		(width 0.2032)
		(layer "In3.Cu")
		(net "EXT_GPIO_9")
	)
	(segment
		(start 140.18445 134.86002)
		(end 140.18445 124.53179)
		(width 0.2032)
		(layer "In3.Cu")
		(net "EXT_GPIO_9")
	)
	(segment
		(start 224.2216 98.3162)
		(end 228.30129 94.23651)
		(width 0.2032)
		(layer "In3.Cu")
		(net "EXT_GPIO_9")
	)
	(segment
		(start 135.98011 121.28247)
		(end 136.14991 121.45227)
		(width 0.2032)
		(layer "In3.Cu")
		(net "EXT_GPIO_9")
	)
	(segment
		(start 226.83533 119.85769)
		(end 228.12404 121.1464)
		(width 0.2032)
		(layer "In3.Cu")
		(net "EXT_GPIO_9")
	)
	(segment
		(start 230.9612 135.30976)
		(end 230.9612 121.88398)
		(width 0.2032)
		(layer "In3.Cu")
		(net "EXT_GPIO_9")
	)
	(segment
		(start 182.4216 143.5162)
		(end 225.2104 143.5162)
		(width 0.2032)
		(layer "In3.Cu")
		(net "EXT_GPIO_9")
	)
	(segment
		(start 134.10467 121.7207)
		(end 136.41149 121.7207)
		(width 0.2032)
		(layer "F.Cu")
		(net "EXT_GPIO_8")
	)
	(segment
		(start 134.10467 121.78247)
		(end 134.10467 121.7207)
		(width 0.2032)
		(layer "F.Cu")
		(net "EXT_GPIO_8")
	)
	(via
		(at 134.10467 121.78247)
		(size 0.4064)
		(drill 0.2032)
		(layers "F.Cu" "B.Cu")
		(tenting
			(front yes)
			(back yes)
		)
		(net "EXT_GPIO_8")
	)
	(segment
		(start 227.16553 119.72092)
		(end 227.16553 115.60774)
		(width 0.2032)
		(layer "In3.Cu")
		(net "EXT_GPIO_8")
	)
	(segment
		(start 224.8216 113.26381)
		(end 224.8216 98.4162)
		(width 0.2032)
		(layer "In3.Cu")
		(net "EXT_GPIO_8")
	)
	(segment
		(start 228.26081 120.8162)
		(end 230.4216 120.8162)
		(width 0.2032)
		(layer "In3.Cu")
		(net "EXT_GPIO_8")
	)
	(segment
		(start 227.3914 142.70467)
		(end 227.3914 139.29846)
		(width 0.2032)
		(layer "In3.Cu")
		(net "EXT_GPIO_8")
	)
	(segment
		(start 230.4216 120.8162)
		(end 231.2914 121.686)
		(width 0.2032)
		(layer "In3.Cu")
		(net "EXT_GPIO_8")
	)
	(segment
		(start 227.16553 119.72092)
		(end 228.26081 120.8162)
		(width 0.2032)
		(layer "In3.Cu")
		(net "EXT_GPIO_8")
	)
	(segment
		(start 164.32473 136.06947)
		(end 165.68913 134.70508)
		(width 0.2032)
		(layer "In3.Cu")
		(net "EXT_GPIO_8")
	)
	(segment
		(start 136.01314 121.78247)
		(end 137.91977 123.6891)
		(width 0.2032)
		(layer "In3.Cu")
		(net "EXT_GPIO_8")
	)
	(segment
		(start 137.91977 123.6891)
		(end 138.59474 123.6891)
		(width 0.2032)
		(layer "In3.Cu")
		(net "EXT_GPIO_8")
	)
	(segment
		(start 231.2914 135.44653)
		(end 231.2914 121.686)
		(width 0.2032)
		(layer "In3.Cu")
		(net "EXT_GPIO_8")
	)
	(segment
		(start 229.31737 137.37249)
		(end 229.36543 137.37249)
		(width 0.2032)
		(layer "In3.Cu")
		(net "EXT_GPIO_8")
	)
	(segment
		(start 139.76617 135.16077)
		(end 140.67487 136.06947)
		(width 0.2032)
		(layer "In3.Cu")
		(net "EXT_GPIO_8")
	)
	(segment
		(start 229.36543 137.37249)
		(end 231.2914 135.44653)
		(width 0.2032)
		(layer "In3.Cu")
		(net "EXT_GPIO_8")
	)
	(segment
		(start 224.8216 98.4162)
		(end 228.4982 94.7396)
		(width 0.2032)
		(layer "In3.Cu")
		(net "EXT_GPIO_8")
	)
	(segment
		(start 134.10467 121.78247)
		(end 136.01314 121.78247)
		(width 0.2032)
		(layer "In3.Cu")
		(net "EXT_GPIO_8")
	)
	(segment
		(start 181.9914 143.886)
		(end 225.11323 143.886)
		(width 0.2032)
		(layer "In3.Cu")
		(net "EXT_GPIO_8")
	)
	(segment
		(start 229.4616 82.5962)
		(end 231.0216 84.1562)
		(width 0.2032)
		(layer "In3.Cu")
		(net "EXT_GPIO_8")
	)
	(segment
		(start 225.11823 143.891)
		(end 226.20507 143.891)
		(width 0.2032)
		(layer "In3.Cu")
		(net "EXT_GPIO_8")
	)
	(segment
		(start 138.59474 123.6891)
		(end 139.76617 124.86052)
		(width 0.2032)
		(layer "In3.Cu")
		(net "EXT_GPIO_8")
	)
	(segment
		(start 139.76617 135.16077)
		(end 139.76617 124.86052)
		(width 0.2032)
		(layer "In3.Cu")
		(net "EXT_GPIO_8")
	)
	(segment
		(start 228.4982 94.7396)
		(end 229.61933 94.7396)
		(width 0.2032)
		(layer "In3.Cu")
		(net "EXT_GPIO_8")
	)
	(segment
		(start 172.81048 134.70508)
		(end 181.9914 143.886)
		(width 0.2032)
		(layer "In3.Cu")
		(net "EXT_GPIO_8")
	)
	(segment
		(start 140.67487 136.06947)
		(end 164.32473 136.06947)
		(width 0.2032)
		(layer "In3.Cu")
		(net "EXT_GPIO_8")
	)
	(segment
		(start 231.0216 93.33733)
		(end 231.0216 84.1562)
		(width 0.2032)
		(layer "In3.Cu")
		(net "EXT_GPIO_8")
	)
	(segment
		(start 225.11323 143.886)
		(end 225.11823 143.891)
		(width 0.2032)
		(layer "In3.Cu")
		(net "EXT_GPIO_8")
	)
	(segment
		(start 227.3914 139.29846)
		(end 229.31737 137.37249)
		(width 0.2032)
		(layer "In3.Cu")
		(net "EXT_GPIO_8")
	)
	(segment
		(start 229.61933 94.7396)
		(end 231.0216 93.33733)
		(width 0.2032)
		(layer "In3.Cu")
		(net "EXT_GPIO_8")
	)
	(segment
		(start 165.68913 134.70508)
		(end 172.81048 134.70508)
		(width 0.2032)
		(layer "In3.Cu")
		(net "EXT_GPIO_8")
	)
	(segment
		(start 224.8216 113.26381)
		(end 227.16553 115.60774)
		(width 0.2032)
		(layer "In3.Cu")
		(net "EXT_GPIO_8")
	)
	(segment
		(start 226.20507 143.891)
		(end 227.3914 142.70467)
		(width 0.2032)
		(layer "In3.Cu")
		(net "EXT_GPIO_8")
	)
	(segment
		(start 134.59667 122.22057)
		(end 136.41149 122.22057)
		(width 0.2032)
		(layer "F.Cu")
		(net "EXT_GPIO_7")
	)
	(segment
		(start 134.59667 122.29847)
		(end 134.59667 122.22057)
		(width 0.2032)
		(layer "F.Cu")
		(net "EXT_GPIO_7")
	)
	(via
		(at 134.59667 122.29847)
		(size 0.4064)
		(drill 0.2032)
		(layers "F.Cu" "B.Cu")
		(tenting
			(front yes)
			(back yes)
		)
		(net "EXT_GPIO_7")
	)
	(segment
		(start 231.6216 135.5833)
		(end 231.6216 121.5162)
		(width 0.2032)
		(layer "In3.Cu")
		(net "EXT_GPIO_7")
	)
	(segment
		(start 227.61534 119.70376)
		(end 228.32778 120.4162)
		(width 0.2032)
		(layer "In3.Cu")
		(net "EXT_GPIO_7")
	)
	(segment
		(start 227.7216 139.43523)
		(end 227.84063 139.3162)
		(width 0.2032)
		(layer "In3.Cu")
		(net "EXT_GPIO_7")
	)
	(segment
		(start 227.84063 139.3162)
		(end 227.8887 139.3162)
		(width 0.2032)
		(layer "In3.Cu")
		(net "EXT_GPIO_7")
	)
	(segment
		(start 228.5216 95.5162)
		(end 229.5216 95.5162)
		(width 0.2032)
		(layer "In3.Cu")
		(net "EXT_GPIO_7")
	)
	(segment
		(start 225.5216 98.5162)
		(end 228.5216 95.5162)
		(width 0.2032)
		(layer "In3.Cu")
		(net "EXT_GPIO_7")
	)
	(segment
		(start 231.4216 93.6162)
		(end 231.4216 82.0162)
		(width 0.2032)
		(layer "In3.Cu")
		(net "EXT_GPIO_7")
	)
	(segment
		(start 227.61534 119.70376)
		(end 227.61534 115.25772)
		(width 0.2032)
		(layer "In3.Cu")
		(net "EXT_GPIO_7")
	)
	(segment
		(start 165.34674 135.7162)
		(end 173.2216 135.7162)
		(width 0.2032)
		(layer "In3.Cu")
		(net "EXT_GPIO_7")
	)
	(segment
		(start 139.43597 135.33057)
		(end 139.43597 126.91876)
		(width 0.2032)
		(layer "In3.Cu")
		(net "EXT_GPIO_7")
	)
	(segment
		(start 136.00387 122.29847)
		(end 138.4216 124.7162)
		(width 0.2032)
		(layer "In3.Cu")
		(net "EXT_GPIO_7")
	)
	(segment
		(start 226.34184 144.2212)
		(end 227.7216 142.84144)
		(width 0.2032)
		(layer "In3.Cu")
		(net "EXT_GPIO_7")
	)
	(segment
		(start 225.5216 113.16398)
		(end 227.61534 115.25772)
		(width 0.2032)
		(layer "In3.Cu")
		(net "EXT_GPIO_7")
	)
	(segment
		(start 224.97646 144.2162)
		(end 224.98146 144.2212)
		(width 0.2032)
		(layer "In3.Cu")
		(net "EXT_GPIO_7")
	)
	(segment
		(start 138.4216 125.90439)
		(end 138.4216 124.7162)
		(width 0.2032)
		(layer "In3.Cu")
		(net "EXT_GPIO_7")
	)
	(segment
		(start 140.60195 136.49655)
		(end 164.56639 136.49655)
		(width 0.2032)
		(layer "In3.Cu")
		(net "EXT_GPIO_7")
	)
	(segment
		(start 134.59667 122.29847)
		(end 136.00387 122.29847)
		(width 0.2032)
		(layer "In3.Cu")
		(net "EXT_GPIO_7")
	)
	(segment
		(start 181.7216 144.2162)
		(end 224.97646 144.2162)
		(width 0.2032)
		(layer "In3.Cu")
		(net "EXT_GPIO_7")
	)
	(segment
		(start 229.5216 95.5162)
		(end 231.4216 93.6162)
		(width 0.2032)
		(layer "In3.Cu")
		(net "EXT_GPIO_7")
	)
	(segment
		(start 227.8887 139.3162)
		(end 231.6216 135.5833)
		(width 0.2032)
		(layer "In3.Cu")
		(net "EXT_GPIO_7")
	)
	(segment
		(start 227.7216 142.84144)
		(end 227.7216 139.43523)
		(width 0.2032)
		(layer "In3.Cu")
		(net "EXT_GPIO_7")
	)
	(segment
		(start 139.43597 135.33057)
		(end 140.60195 136.49655)
		(width 0.2032)
		(layer "In3.Cu")
		(net "EXT_GPIO_7")
	)
	(segment
		(start 230.5216 120.4162)
		(end 231.6216 121.5162)
		(width 0.2032)
		(layer "In3.Cu")
		(net "EXT_GPIO_7")
	)
	(segment
		(start 164.56639 136.49655)
		(end 165.34674 135.7162)
		(width 0.2032)
		(layer "In3.Cu")
		(net "EXT_GPIO_7")
	)
	(segment
		(start 225.5216 113.16398)
		(end 225.5216 98.5162)
		(width 0.2032)
		(layer "In3.Cu")
		(net "EXT_GPIO_7")
	)
	(segment
		(start 229.4616 80.0562)
		(end 231.4216 82.0162)
		(width 0.2032)
		(layer "In3.Cu")
		(net "EXT_GPIO_7")
	)
	(segment
		(start 228.32778 120.4162)
		(end 230.5216 120.4162)
		(width 0.2032)
		(layer "In3.Cu")
		(net "EXT_GPIO_7")
	)
	(segment
		(start 138.4216 125.90439)
		(end 139.43597 126.91876)
		(width 0.2032)
		(layer "In3.Cu")
		(net "EXT_GPIO_7")
	)
	(segment
		(start 224.98146 144.2212)
		(end 226.34184 144.2212)
		(width 0.2032)
		(layer "In3.Cu")
		(net "EXT_GPIO_7")
	)
	(segment
		(start 173.2216 135.7162)
		(end 181.7216 144.2162)
		(width 0.2032)
		(layer "In3.Cu")
		(net "EXT_GPIO_7")
	)
	(segment
		(start 134.09667 118.27447)
		(end 134.15166 118.27447)
		(width 0.2032)
		(layer "F.Cu")
		(net "EXT_GPIO_4")
	)
	(segment
		(start 134.15166 118.27447)
		(end 134.20164 118.22449)
		(width 0.2032)
		(layer "F.Cu")
		(net "EXT_GPIO_4")
	)
	(segment
		(start 134.20164 118.22449)
		(end 136.41149 118.22449)
		(width 0.2032)
		(layer "F.Cu")
		(net "EXT_GPIO_4")
	)
	(via
		(at 134.09667 118.27447)
		(size 0.4064)
		(drill 0.2032)
		(layers "F.Cu" "B.Cu")
		(tenting
			(front yes)
			(back yes)
		)
		(net "EXT_GPIO_4")
	)
	(via
		(at 223.1216 88.8162)
		(size 0.4064)
		(drill 0.2032)
		(layers "F.Cu" "B.Cu")
		(net "EXT_GPIO_4")
	)
	(segment
		(start 225.7816 88.8162)
		(end 226.9216 87.6762)
		(width 0.2032)
		(layer "B.Cu")
		(net "EXT_GPIO_4")
	)
	(segment
		(start 223.1216 88.8162)
		(end 225.7816 88.8162)
		(width 0.2032)
		(layer "B.Cu")
		(net "EXT_GPIO_4")
	)
	(segment
		(start 197.6216 141.0162)
		(end 197.9518 141.3464)
		(width 0.2032)
		(layer "In3.Cu")
		(net "EXT_GPIO_4")
	)
	(segment
		(start 216.63655 113.10125)
		(end 216.63655 111.60125)
		(width 0.2032)
		(layer "In3.Cu")
		(net "EXT_GPIO_4")
	)
	(segment
		(start 142.19591 131.79051)
		(end 142.19591 122.56947)
		(width 0.2032)
		(layer "In3.Cu")
		(net "EXT_GPIO_4")
	)
	(segment
		(start 214.3216 115.65586)
		(end 214.3216 115.4162)
		(width 0.2032)
		(layer "In3.Cu")
		(net "EXT_GPIO_4")
	)
	(segment
		(start 191.95657 134.38122)
		(end 195.68662 134.38122)
		(width 0.2032)
		(layer "In3.Cu")
		(net "EXT_GPIO_4")
	)
	(segment
		(start 197.9518 141.3464)
		(end 204.69513 141.3464)
		(width 0.2032)
		(layer "In3.Cu")
		(net "EXT_GPIO_4")
	)
	(segment
		(start 213.6216 135.18837)
		(end 213.6216 132.1162)
		(width 0.2032)
		(layer "In3.Cu")
		(net "EXT_GPIO_4")
	)
	(segment
		(start 135.95748 118.27447)
		(end 136.4978 118.81479)
		(width 0.2032)
		(layer "In3.Cu")
		(net "EXT_GPIO_4")
	)
	(segment
		(start 142.19591 131.79051)
		(end 143.45381 133.04841)
		(width 0.2032)
		(layer "In3.Cu")
		(net "EXT_GPIO_4")
	)
	(segment
		(start 191.3216 135.0162)
		(end 191.95657 134.38122)
		(width 0.2032)
		(layer "In3.Cu")
		(net "EXT_GPIO_4")
	)
	(segment
		(start 143.45381 133.04841)
		(end 159.62451 133.04841)
		(width 0.2032)
		(layer "In3.Cu")
		(net "EXT_GPIO_4")
	)
	(segment
		(start 207.72533 138.3162)
		(end 210.49376 138.3162)
		(width 0.2032)
		(layer "In3.Cu")
		(net "EXT_GPIO_4")
	)
	(segment
		(start 212.3216 132.2162)
		(end 212.8216 131.7162)
		(width 0.2032)
		(layer "In3.Cu")
		(net "EXT_GPIO_4")
	)
	(segment
		(start 177.27887 132.4162)
		(end 179.87887 135.0162)
		(width 0.2032)
		(layer "In3.Cu")
		(net "EXT_GPIO_4")
	)
	(segment
		(start 136.4978 118.81479)
		(end 137.22138 118.81479)
		(width 0.2032)
		(layer "In3.Cu")
		(net "EXT_GPIO_4")
	)
	(segment
		(start 213.2216 131.7162)
		(end 213.6216 132.1162)
		(width 0.2032)
		(layer "In3.Cu")
		(net "EXT_GPIO_4")
	)
	(segment
		(start 204.69513 141.3464)
		(end 207.72533 138.3162)
		(width 0.2032)
		(layer "In3.Cu")
		(net "EXT_GPIO_4")
	)
	(segment
		(start 210.49376 138.3162)
		(end 213.6216 135.18837)
		(width 0.2032)
		(layer "In3.Cu")
		(net "EXT_GPIO_4")
	)
	(segment
		(start 179.87887 135.0162)
		(end 191.3216 135.0162)
		(width 0.2032)
		(layer "In3.Cu")
		(net "EXT_GPIO_4")
	)
	(segment
		(start 223.1216 94.9162)
		(end 223.1216 88.8162)
		(width 0.2032)
		(layer "In3.Cu")
		(net "EXT_GPIO_4")
	)
	(segment
		(start 210.3716 131.3662)
		(end 211.2216 132.2162)
		(width 0.2032)
		(layer "In3.Cu")
		(net "EXT_GPIO_4")
	)
	(segment
		(start 137.22138 118.81479)
		(end 137.89259 119.486)
		(width 0.2032)
		(layer "In3.Cu")
		(net "EXT_GPIO_4")
	)
	(segment
		(start 210.3716 131.3662)
		(end 210.3716 119.60586)
		(width 0.2032)
		(layer "In3.Cu")
		(net "EXT_GPIO_4")
	)
	(segment
		(start 211.2216 132.2162)
		(end 212.3216 132.2162)
		(width 0.2032)
		(layer "In3.Cu")
		(net "EXT_GPIO_4")
	)
	(segment
		(start 137.89259 119.486)
		(end 139.11244 119.486)
		(width 0.2032)
		(layer "In3.Cu")
		(net "EXT_GPIO_4")
	)
	(segment
		(start 216.63655 111.60125)
		(end 218.1216 110.1162)
		(width 0.2032)
		(layer "In3.Cu")
		(net "EXT_GPIO_4")
	)
	(segment
		(start 195.68662 134.38122)
		(end 197.6216 136.3162)
		(width 0.2032)
		(layer "In3.Cu")
		(net "EXT_GPIO_4")
	)
	(segment
		(start 218.1216 99.9162)
		(end 223.1216 94.9162)
		(width 0.2032)
		(layer "In3.Cu")
		(net "EXT_GPIO_4")
	)
	(segment
		(start 212.8216 131.7162)
		(end 213.2216 131.7162)
		(width 0.2032)
		(layer "In3.Cu")
		(net "EXT_GPIO_4")
	)
	(segment
		(start 134.09667 118.27447)
		(end 135.95748 118.27447)
		(width 0.2032)
		(layer "In3.Cu")
		(net "EXT_GPIO_4")
	)
	(segment
		(start 197.6216 141.0162)
		(end 197.6216 136.3162)
		(width 0.2032)
		(layer "In3.Cu")
		(net "EXT_GPIO_4")
	)
	(segment
		(start 214.3216 115.4162)
		(end 216.63655 113.10125)
		(width 0.2032)
		(layer "In3.Cu")
		(net "EXT_GPIO_4")
	)
	(segment
		(start 160.25672 132.4162)
		(end 177.27887 132.4162)
		(width 0.2032)
		(layer "In3.Cu")
		(net "EXT_GPIO_4")
	)
	(segment
		(start 210.3716 119.60586)
		(end 214.3216 115.65586)
		(width 0.2032)
		(layer "In3.Cu")
		(net "EXT_GPIO_4")
	)
	(segment
		(start 139.11244 119.486)
		(end 142.19591 122.56947)
		(width 0.2032)
		(layer "In3.Cu")
		(net "EXT_GPIO_4")
	)
	(segment
		(start 159.62451 133.04841)
		(end 160.25672 132.4162)
		(width 0.2032)
		(layer "In3.Cu")
		(net "EXT_GPIO_4")
	)
	(segment
		(start 218.1216 110.1162)
		(end 218.1216 99.9162)
		(width 0.2032)
		(layer "In3.Cu")
		(net "EXT_GPIO_4")
	)
	(segment
		(start 134.59667 118.7207)
		(end 136.41149 118.7207)
		(width 0.2032)
		(layer "F.Cu")
		(net "EXT_GPIO_3")
	)
	(segment
		(start 134.59667 118.78247)
		(end 134.59667 118.7207)
		(width 0.2032)
		(layer "F.Cu")
		(net "EXT_GPIO_3")
	)
	(via
		(at 134.59667 118.78247)
		(size 0.4064)
		(drill 0.2032)
		(layers "F.Cu" "B.Cu")
		(tenting
			(front yes)
			(back yes)
		)
		(net "EXT_GPIO_3")
	)
	(via
		(at 222.7216 84.7162)
		(size 0.4064)
		(drill 0.2032)
		(layers "F.Cu" "B.Cu")
		(net "EXT_GPIO_3")
	)
	(segment
		(start 222.7216 84.7162)
		(end 223.1416 85.1362)
		(width 0.2032)
		(layer "B.Cu")
		(net "EXT_GPIO_3")
	)
	(segment
		(start 223.1416 85.1362)
		(end 226.9216 85.1362)
		(width 0.2032)
		(layer "B.Cu")
		(net "EXT_GPIO_3")
	)
	(segment
		(start 195.2958 135.1162)
		(end 197.0216 136.842)
		(width 0.2032)
		(layer "In3.Cu")
		(net "EXT_GPIO_3")
	)
	(segment
		(start 141.58401 133.25958)
		(end 141.70305 133.37861)
		(width 0.2032)
		(layer "In3.Cu")
		(net "EXT_GPIO_3")
	)
	(segment
		(start 221.5216 98.5412)
		(end 221.5216 97.31701)
		(width 0.2032)
		(layer "In3.Cu")
		(net "EXT_GPIO_3")
	)
	(segment
		(start 135.63653 119.34554)
		(end 136.66776 119.34554)
		(width 0.2032)
		(layer "In3.Cu")
		(net "EXT_GPIO_3")
	)
	(segment
		(start 218.58606 111.75174)
		(end 218.58606 101.47673)
		(width 0.2032)
		(layer "In3.Cu")
		(net "EXT_GPIO_3")
	)
	(segment
		(start 194.66585 135.1162)
		(end 195.2958 135.1162)
		(width 0.2032)
		(layer "In3.Cu")
		(net "EXT_GPIO_3")
	)
	(segment
		(start 205.56506 141.24734)
		(end 206.3582 140.4542)
		(width 0.2032)
		(layer "In3.Cu")
		(net "EXT_GPIO_3")
	)
	(segment
		(start 212.10314 130.2844)
		(end 213.0898 130.2844)
		(width 0.2032)
		(layer "In3.Cu")
		(net "EXT_GPIO_3")
	)
	(segment
		(start 134.63555 118.82135)
		(end 135.11234 118.82135)
		(width 0.2032)
		(layer "In3.Cu")
		(net "EXT_GPIO_3")
	)
	(segment
		(start 197.0216 141.61427)
		(end 197.0216 136.842)
		(width 0.2032)
		(layer "In3.Cu")
		(net "EXT_GPIO_3")
	)
	(segment
		(start 222.7216 84.7162)
		(end 223.8216 85.8162)
		(width 0.2032)
		(layer "In3.Cu")
		(net "EXT_GPIO_3")
	)
	(segment
		(start 184.2216 138.2162)
		(end 186.44023 135.99757)
		(width 0.2032)
		(layer "In3.Cu")
		(net "EXT_GPIO_3")
	)
	(segment
		(start 210.9216 119.8162)
		(end 216.5216 114.2162)
		(width 0.2032)
		(layer "In3.Cu")
		(net "EXT_GPIO_3")
	)
	(segment
		(start 141.70305 133.37861)
		(end 163.62307 133.37861)
		(width 0.2032)
		(layer "In3.Cu")
		(net "EXT_GPIO_3")
	)
	(segment
		(start 216.5216 114.2162)
		(end 216.5216 113.8162)
		(width 0.2032)
		(layer "In3.Cu")
		(net "EXT_GPIO_3")
	)
	(segment
		(start 216.5216 113.8162)
		(end 218.58606 111.75174)
		(width 0.2032)
		(layer "In3.Cu")
		(net "EXT_GPIO_3")
	)
	(segment
		(start 197.0216 141.61427)
		(end 197.4216 142.01427)
		(width 0.2032)
		(layer "In3.Cu")
		(net "EXT_GPIO_3")
	)
	(segment
		(start 206.3582 140.4542)
		(end 209.22673 140.4542)
		(width 0.2032)
		(layer "In3.Cu")
		(net "EXT_GPIO_3")
	)
	(segment
		(start 136.66776 119.34554)
		(end 137.23842 119.9162)
		(width 0.2032)
		(layer "In3.Cu")
		(net "EXT_GPIO_3")
	)
	(segment
		(start 179.1216 138.2162)
		(end 184.2216 138.2162)
		(width 0.2032)
		(layer "In3.Cu")
		(net "EXT_GPIO_3")
	)
	(segment
		(start 137.99906 119.8162)
		(end 138.4216 120.23874)
		(width 0.2032)
		(layer "In3.Cu")
		(net "EXT_GPIO_3")
	)
	(segment
		(start 193.78448 135.99757)
		(end 194.66585 135.1162)
		(width 0.2032)
		(layer "In3.Cu")
		(net "EXT_GPIO_3")
	)
	(segment
		(start 218.58606 101.47673)
		(end 221.5216 98.5412)
		(width 0.2032)
		(layer "In3.Cu")
		(net "EXT_GPIO_3")
	)
	(segment
		(start 221.5216 97.31701)
		(end 223.8216 95.01701)
		(width 0.2032)
		(layer "In3.Cu")
		(net "EXT_GPIO_3")
	)
	(segment
		(start 210.9216 129.10286)
		(end 212.10314 130.2844)
		(width 0.2032)
		(layer "In3.Cu")
		(net "EXT_GPIO_3")
	)
	(segment
		(start 213.0898 130.2844)
		(end 214.4216 131.6162)
		(width 0.2032)
		(layer "In3.Cu")
		(net "EXT_GPIO_3")
	)
	(segment
		(start 138.75106 120.84567)
		(end 139.74611 120.84567)
		(width 0.2032)
		(layer "In3.Cu")
		(net "EXT_GPIO_3")
	)
	(segment
		(start 135.11234 118.82135)
		(end 135.63653 119.34554)
		(width 0.2032)
		(layer "In3.Cu")
		(net "EXT_GPIO_3")
	)
	(segment
		(start 205.56506 141.67044)
		(end 205.56506 141.24734)
		(width 0.2032)
		(layer "In3.Cu")
		(net "EXT_GPIO_3")
	)
	(segment
		(start 173.78844 132.88304)
		(end 179.1216 138.2162)
		(width 0.2032)
		(layer "In3.Cu")
		(net "EXT_GPIO_3")
	)
	(segment
		(start 137.58001 119.9162)
		(end 137.68001 119.8162)
		(width 0.2032)
		(layer "In3.Cu")
		(net "EXT_GPIO_3")
	)
	(segment
		(start 214.4216 137.18776)
		(end 214.4216 131.6162)
		(width 0.2032)
		(layer "In3.Cu")
		(net "EXT_GPIO_3")
	)
	(segment
		(start 138.4216 120.5162)
		(end 138.75106 120.84567)
		(width 0.2032)
		(layer "In3.Cu")
		(net "EXT_GPIO_3")
	)
	(segment
		(start 134.59667 118.78247)
		(end 134.63555 118.82135)
		(width 0.2032)
		(layer "In3.Cu")
		(net "EXT_GPIO_3")
	)
	(segment
		(start 205.22123 142.01427)
		(end 205.56506 141.67044)
		(width 0.2032)
		(layer "In3.Cu")
		(net "EXT_GPIO_3")
	)
	(segment
		(start 139.74611 120.84567)
		(end 141.58401 122.68357)
		(width 0.2032)
		(layer "In3.Cu")
		(net "EXT_GPIO_3")
	)
	(segment
		(start 213.44892 138.16044)
		(end 214.4216 137.18776)
		(width 0.2032)
		(layer "In3.Cu")
		(net "EXT_GPIO_3")
	)
	(segment
		(start 211.52048 138.16044)
		(end 213.44892 138.16044)
		(width 0.2032)
		(layer "In3.Cu")
		(net "EXT_GPIO_3")
	)
	(segment
		(start 164.11864 132.88304)
		(end 173.78844 132.88304)
		(width 0.2032)
		(layer "In3.Cu")
		(net "EXT_GPIO_3")
	)
	(segment
		(start 163.62307 133.37861)
		(end 164.11864 132.88304)
		(width 0.2032)
		(layer "In3.Cu")
		(net "EXT_GPIO_3")
	)
	(segment
		(start 197.4216 142.01427)
		(end 205.22123 142.01427)
		(width 0.2032)
		(layer "In3.Cu")
		(net "EXT_GPIO_3")
	)
	(segment
		(start 186.44023 135.99757)
		(end 193.78448 135.99757)
		(width 0.2032)
		(layer "In3.Cu")
		(net "EXT_GPIO_3")
	)
	(segment
		(start 141.58401 133.25958)
		(end 141.58401 122.68357)
		(width 0.2032)
		(layer "In3.Cu")
		(net "EXT_GPIO_3")
	)
	(segment
		(start 138.4216 120.5162)
		(end 138.4216 120.23874)
		(width 0.2032)
		(layer "In3.Cu")
		(net "EXT_GPIO_3")
	)
	(segment
		(start 137.23842 119.9162)
		(end 137.58001 119.9162)
		(width 0.2032)
		(layer "In3.Cu")
		(net "EXT_GPIO_3")
	)
	(segment
		(start 210.9216 129.10286)
		(end 210.9216 119.8162)
		(width 0.2032)
		(layer "In3.Cu")
		(net "EXT_GPIO_3")
	)
	(segment
		(start 209.22673 140.4542)
		(end 211.52048 138.16044)
		(width 0.2032)
		(layer "In3.Cu")
		(net "EXT_GPIO_3")
	)
	(segment
		(start 223.8216 95.01701)
		(end 223.8216 85.8162)
		(width 0.2032)
		(layer "In3.Cu")
		(net "EXT_GPIO_3")
	)
	(segment
		(start 137.68001 119.8162)
		(end 137.99906 119.8162)
		(width 0.2032)
		(layer "In3.Cu")
		(net "EXT_GPIO_3")
	)
	(segment
		(start 134.09667 119.22057)
		(end 136.41149 119.22057)
		(width 0.2032)
		(layer "F.Cu")
		(net "EXT_GPIO_2")
	)
	(segment
		(start 134.09667 119.27447)
		(end 134.09667 119.22057)
		(width 0.2032)
		(layer "F.Cu")
		(net "EXT_GPIO_2")
	)
	(via
		(at 223.8216 82.7162)
		(size 0.4064)
		(drill 0.2032)
		(layers "F.Cu" "B.Cu")
		(net "EXT_GPIO_2")
	)
	(via
		(at 134.09667 119.27447)
		(size 0.4064)
		(drill 0.2032)
		(layers "F.Cu" "B.Cu")
		(tenting
			(front yes)
			(back yes)
		)
		(net "EXT_GPIO_2")
	)
	(segment
		(start 223.86048 82.67732)
		(end 226.84048 82.67732)
		(width 0.2032)
		(layer "B.Cu")
		(net "EXT_GPIO_2")
	)
	(segment
		(start 223.8216 82.7162)
		(end 223.86048 82.67732)
		(width 0.2032)
		(layer "B.Cu")
		(net "EXT_GPIO_2")
	)
	(segment
		(start 226.84048 82.67732)
		(end 226.9216 82.5962)
		(width 0.2032)
		(layer "B.Cu")
		(net "EXT_GPIO_2")
	)
	(segment
		(start 211.4848 138.6631)
		(end 214.31106 138.6631)
		(width 0.2032)
		(layer "In3.Cu")
		(net "EXT_GPIO_2")
	)
	(segment
		(start 134.8876 119.27447)
		(end 135.37233 119.75921)
		(width 0.2032)
		(layer "In3.Cu")
		(net "EXT_GPIO_2")
	)
	(segment
		(start 182.74987 142.34447)
		(end 205.358 142.34447)
		(width 0.2032)
		(layer "In3.Cu")
		(net "EXT_GPIO_2")
	)
	(segment
		(start 220.74519 105.09261)
		(end 221.5466 104.2912)
		(width 0.2032)
		(layer "In3.Cu")
		(net "EXT_GPIO_2")
	)
	(segment
		(start 214.31106 138.6631)
		(end 214.7518 138.22236)
		(width 0.2032)
		(layer "In3.Cu")
		(net "EXT_GPIO_2")
	)
	(segment
		(start 141.40709 133.886)
		(end 163.58483 133.886)
		(width 0.2032)
		(layer "In3.Cu")
		(net "EXT_GPIO_2")
	)
	(segment
		(start 223.8216 82.7162)
		(end 224.29419 83.1888)
		(width 0.2032)
		(layer "In3.Cu")
		(net "EXT_GPIO_2")
	)
	(segment
		(start 222.1216 98.4162)
		(end 222.1216 97.63334)
		(width 0.2032)
		(layer "In3.Cu")
		(net "EXT_GPIO_2")
	)
	(segment
		(start 220.74519 110.79261)
		(end 220.74519 105.09261)
		(width 0.2032)
		(layer "In3.Cu")
		(net "EXT_GPIO_2")
	)
	(segment
		(start 173.7216 133.3162)
		(end 182.74987 142.34447)
		(width 0.2032)
		(layer "In3.Cu")
		(net "EXT_GPIO_2")
	)
	(segment
		(start 164.15463 133.3162)
		(end 173.7216 133.3162)
		(width 0.2032)
		(layer "In3.Cu")
		(net "EXT_GPIO_2")
	)
	(segment
		(start 212.2216 119.75223)
		(end 212.2216 119.3162)
		(width 0.2032)
		(layer "In3.Cu")
		(net "EXT_GPIO_2")
	)
	(segment
		(start 141.23622 133.71513)
		(end 141.23622 123.14564)
		(width 0.2032)
		(layer "In3.Cu")
		(net "EXT_GPIO_2")
	)
	(segment
		(start 224.29419 95.46075)
		(end 224.29419 83.1888)
		(width 0.2032)
		(layer "In3.Cu")
		(net "EXT_GPIO_2")
	)
	(segment
		(start 214.7518 138.22236)
		(end 214.7518 132.886)
		(width 0.2032)
		(layer "In3.Cu")
		(net "EXT_GPIO_2")
	)
	(segment
		(start 222.15584 101.38196)
		(end 222.15584 98.45044)
		(width 0.2032)
		(layer "In3.Cu")
		(net "EXT_GPIO_2")
	)
	(segment
		(start 212.10577 127.13203)
		(end 212.2534 126.9844)
		(width 0.2032)
		(layer "In3.Cu")
		(net "EXT_GPIO_2")
	)
	(segment
		(start 209.3635 140.7844)
		(end 211.4848 138.6631)
		(width 0.2032)
		(layer "In3.Cu")
		(net "EXT_GPIO_2")
	)
	(segment
		(start 212.2534 126.9844)
		(end 212.2534 119.78403)
		(width 0.2032)
		(layer "In3.Cu")
		(net "EXT_GPIO_2")
	)
	(segment
		(start 215.1216 132.5162)
		(end 215.1216 131.55186)
		(width 0.2032)
		(layer "In3.Cu")
		(net "EXT_GPIO_2")
	)
	(segment
		(start 221.5466 104.2912)
		(end 221.5466 101.9912)
		(width 0.2032)
		(layer "In3.Cu")
		(net "EXT_GPIO_2")
	)
	(segment
		(start 212.10577 128.53602)
		(end 212.10577 127.13203)
		(width 0.2032)
		(layer "In3.Cu")
		(net "EXT_GPIO_2")
	)
	(segment
		(start 206.49497 140.7844)
		(end 209.3635 140.7844)
		(width 0.2032)
		(layer "In3.Cu")
		(net "EXT_GPIO_2")
	)
	(segment
		(start 205.358 142.34447)
		(end 205.95859 141.74388)
		(width 0.2032)
		(layer "In3.Cu")
		(net "EXT_GPIO_2")
	)
	(segment
		(start 135.37233 119.75921)
		(end 136.31845 119.75921)
		(width 0.2032)
		(layer "In3.Cu")
		(net "EXT_GPIO_2")
	)
	(segment
		(start 137.77544 121.2162)
		(end 139.30678 121.2162)
		(width 0.2032)
		(layer "In3.Cu")
		(net "EXT_GPIO_2")
	)
	(segment
		(start 141.23622 133.71513)
		(end 141.40709 133.886)
		(width 0.2032)
		(layer "In3.Cu")
		(net "EXT_GPIO_2")
	)
	(segment
		(start 212.2216 119.75223)
		(end 212.2534 119.78403)
		(width 0.2032)
		(layer "In3.Cu")
		(net "EXT_GPIO_2")
	)
	(segment
		(start 212.10577 128.53602)
		(end 215.1216 131.55186)
		(width 0.2032)
		(layer "In3.Cu")
		(net "EXT_GPIO_2")
	)
	(segment
		(start 205.95859 141.74388)
		(end 205.95859 141.32078)
		(width 0.2032)
		(layer "In3.Cu")
		(net "EXT_GPIO_2")
	)
	(segment
		(start 136.31845 119.75921)
		(end 137.77544 121.2162)
		(width 0.2032)
		(layer "In3.Cu")
		(net "EXT_GPIO_2")
	)
	(segment
		(start 134.09667 119.27447)
		(end 134.8876 119.27447)
		(width 0.2032)
		(layer "In3.Cu")
		(net "EXT_GPIO_2")
	)
	(segment
		(start 221.5466 101.9912)
		(end 222.15584 101.38196)
		(width 0.2032)
		(layer "In3.Cu")
		(net "EXT_GPIO_2")
	)
	(segment
		(start 205.95859 141.32078)
		(end 206.49497 140.7844)
		(width 0.2032)
		(layer "In3.Cu")
		(net "EXT_GPIO_2")
	)
	(segment
		(start 163.58483 133.886)
		(end 164.15463 133.3162)
		(width 0.2032)
		(layer "In3.Cu")
		(net "EXT_GPIO_2")
	)
	(segment
		(start 212.2216 119.3162)
		(end 220.74519 110.79261)
		(width 0.2032)
		(layer "In3.Cu")
		(net "EXT_GPIO_2")
	)
	(segment
		(start 222.1216 98.4162)
		(end 222.15584 98.45044)
		(width 0.2032)
		(layer "In3.Cu")
		(net "EXT_GPIO_2")
	)
	(segment
		(start 214.7518 132.886)
		(end 215.1216 132.5162)
		(width 0.2032)
		(layer "In3.Cu")
		(net "EXT_GPIO_2")
	)
	(segment
		(start 222.1216 97.63334)
		(end 224.29419 95.46075)
		(width 0.2032)
		(layer "In3.Cu")
		(net "EXT_GPIO_2")
	)
	(segment
		(start 139.30678 121.2162)
		(end 141.23622 123.14564)
		(width 0.2032)
		(layer "In3.Cu")
		(net "EXT_GPIO_2")
	)
	(segment
		(start 134.59667 119.7207)
		(end 136.41149 119.7207)
		(width 0.2032)
		(layer "F.Cu")
		(net "EXT_GPIO_1")
	)
	(segment
		(start 134.59667 119.79847)
		(end 134.59667 119.7207)
		(width 0.2032)
		(layer "F.Cu")
		(net "EXT_GPIO_1")
	)
	(via
		(at 225.05619 80.28996)
		(size 0.4064)
		(drill 0.2032)
		(layers "F.Cu" "B.Cu")
		(net "EXT_GPIO_1")
	)
	(via
		(at 134.59667 119.79847)
		(size 0.4064)
		(drill 0.2032)
		(layers "F.Cu" "B.Cu")
		(tenting
			(front yes)
			(back yes)
		)
		(net "EXT_GPIO_1")
	)
	(segment
		(start 225.05619 80.28996)
		(end 226.68784 80.28996)
		(width 0.2032)
		(layer "B.Cu")
		(net "EXT_GPIO_1")
	)
	(segment
		(start 226.68784 80.28996)
		(end 226.9216 80.0562)
		(width 0.2032)
		(layer "B.Cu")
		(net "EXT_GPIO_1")
	)
	(segment
		(start 137.5881 121.586)
		(end 139.13103 121.586)
		(width 0.2032)
		(layer "In3.Cu")
		(net "EXT_GPIO_1")
	)
	(segment
		(start 140.84485 134.09717)
		(end 140.84485 123.29982)
		(width 0.2032)
		(layer "In3.Cu")
		(net "EXT_GPIO_1")
	)
	(segment
		(start 136.44637 120.44427)
		(end 137.5881 121.586)
		(width 0.2032)
		(layer "In3.Cu")
		(net "EXT_GPIO_1")
	)
	(segment
		(start 223.2216 114.69602)
		(end 223.2216 97.2162)
		(width 0.2032)
		(layer "In3.Cu")
		(net "EXT_GPIO_1")
	)
	(segment
		(start 226.6914 120.8162)
		(end 227.8914 122.0162)
		(width 0.2032)
		(layer "In3.Cu")
		(net "EXT_GPIO_1")
	)
	(segment
		(start 226.2448 142.4394)
		(end 226.2448 139.04415)
		(width 0.2032)
		(layer "In3.Cu")
		(net "EXT_GPIO_1")
	)
	(segment
		(start 226.2448 139.04415)
		(end 227.8914 137.39755)
		(width 0.2032)
		(layer "In3.Cu")
		(net "EXT_GPIO_1")
	)
	(segment
		(start 135.24247 120.44427)
		(end 136.44637 120.44427)
		(width 0.2032)
		(layer "In3.Cu")
		(net "EXT_GPIO_1")
	)
	(segment
		(start 223.2216 97.2162)
		(end 225.0216 95.4162)
		(width 0.2032)
		(layer "In3.Cu")
		(net "EXT_GPIO_1")
	)
	(segment
		(start 211.56068 141.2844)
		(end 213.09248 142.8162)
		(width 0.2032)
		(layer "In3.Cu")
		(net "EXT_GPIO_1")
	)
	(segment
		(start 227.8914 137.39755)
		(end 227.8914 122.0162)
		(width 0.2032)
		(layer "In3.Cu")
		(net "EXT_GPIO_1")
	)
	(segment
		(start 134.59667 119.79847)
		(end 135.24247 120.44427)
		(width 0.2032)
		(layer "In3.Cu")
		(net "EXT_GPIO_1")
	)
	(segment
		(start 140.96388 134.2162)
		(end 163.7216 134.2162)
		(width 0.2032)
		(layer "In3.Cu")
		(net "EXT_GPIO_1")
	)
	(segment
		(start 164.22332 133.71448)
		(end 173.55382 133.71448)
		(width 0.2032)
		(layer "In3.Cu")
		(net "EXT_GPIO_1")
	)
	(segment
		(start 225.0216 80.25536)
		(end 225.05619 80.28996)
		(width 0.2032)
		(layer "In3.Cu")
		(net "EXT_GPIO_1")
	)
	(segment
		(start 225.0216 95.4162)
		(end 225.0216 80.28996)
		(width 0.2032)
		(layer "In3.Cu")
		(net "EXT_GPIO_1")
	)
	(segment
		(start 173.55382 133.71448)
		(end 182.51401 142.67467)
		(width 0.2032)
		(layer "In3.Cu")
		(net "EXT_GPIO_1")
	)
	(segment
		(start 182.51401 142.67467)
		(end 205.69616 142.67467)
		(width 0.2032)
		(layer "In3.Cu")
		(net "EXT_GPIO_1")
	)
	(segment
		(start 225.0216 80.25536)
		(end 225.0216 80.1162)
		(width 0.2032)
		(layer "In3.Cu")
		(net "EXT_GPIO_1")
	)
	(segment
		(start 139.13103 121.586)
		(end 140.84485 123.29982)
		(width 0.2032)
		(layer "In3.Cu")
		(net "EXT_GPIO_1")
	)
	(segment
		(start 225.1016 120.2962)
		(end 225.1016 116.57603)
		(width 0.2032)
		(layer "In3.Cu")
		(net "EXT_GPIO_1")
	)
	(segment
		(start 225.6216 120.8162)
		(end 226.6914 120.8162)
		(width 0.2032)
		(layer "In3.Cu")
		(net "EXT_GPIO_1")
	)
	(segment
		(start 213.09248 142.8162)
		(end 225.868 142.8162)
		(width 0.2032)
		(layer "In3.Cu")
		(net "EXT_GPIO_1")
	)
	(segment
		(start 140.84485 134.09717)
		(end 140.96388 134.2162)
		(width 0.2032)
		(layer "In3.Cu")
		(net "EXT_GPIO_1")
	)
	(segment
		(start 225.868 142.8162)
		(end 226.2448 142.4394)
		(width 0.2032)
		(layer "In3.Cu")
		(net "EXT_GPIO_1")
	)
	(segment
		(start 208.42185 141.7662)
		(end 208.90365 141.2844)
		(width 0.2032)
		(layer "In3.Cu")
		(net "EXT_GPIO_1")
	)
	(segment
		(start 163.7216 134.2162)
		(end 164.22332 133.71448)
		(width 0.2032)
		(layer "In3.Cu")
		(net "EXT_GPIO_1")
	)
	(segment
		(start 205.69616 142.67467)
		(end 206.60463 141.7662)
		(width 0.2032)
		(layer "In3.Cu")
		(net "EXT_GPIO_1")
	)
	(segment
		(start 223.2216 114.69602)
		(end 225.1016 116.57603)
		(width 0.2032)
		(layer "In3.Cu")
		(net "EXT_GPIO_1")
	)
	(segment
		(start 225.1016 120.2962)
		(end 225.6216 120.8162)
		(width 0.2032)
		(layer "In3.Cu")
		(net "EXT_GPIO_1")
	)
	(segment
		(start 206.60463 141.7662)
		(end 208.42185 141.7662)
		(width 0.2032)
		(layer "In3.Cu")
		(net "EXT_GPIO_1")
	)
	(segment
		(start 208.90365 141.2844)
		(end 211.56068 141.2844)
		(width 0.2032)
		(layer "In3.Cu")
		(net "EXT_GPIO_1")
	)
	(segment
		(start 158.04904 104.4162)
		(end 158.04904 103.31041)
		(width 0.2032)
		(layer "F.Cu")
		(net "ANT4_OUT")
	)
	(segment
		(start 158.04904 104.4162)
		(end 158.93212 104.4162)
		(width 0.2032)
		(layer "F.Cu")
		(net "ANT4_OUT")
	)
	(segment
		(start 158.93212 104.98301)
		(end 158.93212 104.4162)
		(width 0.2032)
		(layer "F.Cu")
		(net "ANT4_OUT")
	)
	(segment
		(start 78.99108 142.1662)
		(end 79.62552 142.80064)
		(width 0.2032)
		(layer "F.Cu")
		(net "ANT4_OUT")
	)
	(segment
		(start 77.6966 142.1662)
		(end 78.99108 142.1662)
		(width 0.2032)
		(layer "F.Cu")
		(net "ANT4_OUT")
	)
	(via
		(at 158.93212 104.98301)
		(size 0.4064)
		(drill 0.2032)
		(layers "F.Cu" "B.Cu")
		(tenting
			(front yes)
			(back yes)
		)
		(net "ANT4_OUT")
	)
	(via
		(at 79.62552 142.80064)
		(size 0.4064)
		(drill 0.2032)
		(layers "F.Cu" "B.Cu")
		(net "ANT4_OUT")
	)
	(segment
		(start 132.56598 117.17182)
		(end 136.65416 117.17182)
		(width 0.2032)
		(layer "In3.Cu")
		(net "ANT4_OUT")
	)
	(segment
		(start 137.1686 130.15166)
		(end 137.1686 125.97767)
		(width 0.2032)
		(layer "In3.Cu")
		(net "ANT4_OUT")
	)
	(segment
		(start 158.93212 107.80568)
		(end 158.93212 104.98301)
		(width 0.2032)
		(layer "In3.Cu")
		(net "ANT4_OUT")
	)
	(segment
		(start 77.7466 143.37259)
		(end 78.31855 142.80064)
		(width 0.2032)
		(layer "In3.Cu")
		(net "ANT4_OUT")
	)
	(segment
		(start 131.1216 123.7162)
		(end 131.366 123.9606)
		(width 0.2032)
		(layer "In3.Cu")
		(net "ANT4_OUT")
	)
	(segment
		(start 136.65416 117.17182)
		(end 137.95696 118.47461)
		(width 0.2032)
		(layer "In3.Cu")
		(net "ANT4_OUT")
	)
	(segment
		(start 137.95696 118.47461)
		(end 146.86318 118.47461)
		(width 0.2032)
		(layer "In3.Cu")
		(net "ANT4_OUT")
	)
	(segment
		(start 131.366 123.9606)
		(end 135.15153 123.9606)
		(width 0.2032)
		(layer "In3.Cu")
		(net "ANT4_OUT")
	)
	(segment
		(start 99.1216 144.5162)
		(end 112.0216 131.6162)
		(width 0.2032)
		(layer "In3.Cu")
		(net "ANT4_OUT")
	)
	(segment
		(start 112.0216 131.6162)
		(end 135.70406 131.6162)
		(width 0.2032)
		(layer "In3.Cu")
		(net "ANT4_OUT")
	)
	(segment
		(start 77.7466 143.92009)
		(end 77.7466 143.37259)
		(width 0.2032)
		(layer "In3.Cu")
		(net "ANT4_OUT")
	)
	(segment
		(start 131.1216 118.6162)
		(end 132.56598 117.17182)
		(width 0.2032)
		(layer "In3.Cu")
		(net "ANT4_OUT")
	)
	(segment
		(start 77.7466 143.92009)
		(end 78.34271 144.5162)
		(width 0.2032)
		(layer "In3.Cu")
		(net "ANT4_OUT")
	)
	(segment
		(start 78.34271 144.5162)
		(end 99.1216 144.5162)
		(width 0.2032)
		(layer "In3.Cu")
		(net "ANT4_OUT")
	)
	(segment
		(start 135.70406 131.6162)
		(end 137.1686 130.15166)
		(width 0.2032)
		(layer "In3.Cu")
		(net "ANT4_OUT")
	)
	(segment
		(start 78.31855 142.80064)
		(end 79.62552 142.80064)
		(width 0.2032)
		(layer "In3.Cu")
		(net "ANT4_OUT")
	)
	(segment
		(start 146.86318 118.47461)
		(end 154.2216 111.1162)
		(width 0.2032)
		(layer "In3.Cu")
		(net "ANT4_OUT")
	)
	(segment
		(start 135.15153 123.9606)
		(end 137.1686 125.97767)
		(width 0.2032)
		(layer "In3.Cu")
		(net "ANT4_OUT")
	)
	(segment
		(start 154.2216 111.1162)
		(end 155.6216 111.1162)
		(width 0.2032)
		(layer "In3.Cu")
		(net "ANT4_OUT")
	)
	(segment
		(start 131.1216 123.7162)
		(end 131.1216 118.6162)
		(width 0.2032)
		(layer "In3.Cu")
		(net "ANT4_OUT")
	)
	(segment
		(start 155.6216 111.1162)
		(end 158.93212 107.80568)
		(width 0.2032)
		(layer "In3.Cu")
		(net "ANT4_OUT")
	)
	(segment
		(start 78.9216 144.0162)
		(end 78.9216 143.7162)
		(width 0.254)
		(layer "F.Cu")
		(net "ANT4_IO_OUT")
	)
	(segment
		(start 142.41739 118.7207)
		(end 142.41739 117.73718)
		(width 0.2032)
		(layer "F.Cu")
		(net "ANT4_IO_OUT")
	)
	(segment
		(start 77.7466 144.0162)
		(end 78.9216 144.0162)
		(width 0.254)
		(layer "F.Cu")
		(net "ANT4_IO_OUT")
	)
	(segment
		(start 78.89244 143.68704)
		(end 78.89244 143.58704)
		(width 0.254)
		(layer "F.Cu")
		(net "ANT4_IO_OUT")
	)
	(segment
		(start 77.9716 142.6662)
		(end 78.89244 143.58704)
		(width 0.254)
		(layer "F.Cu")
		(net "ANT4_IO_OUT")
	)
	(segment
		(start 77.6966 142.6662)
		(end 77.9716 142.6662)
		(width 0.254)
		(layer "F.Cu")
		(net "ANT4_IO_OUT")
	)
	(segment
		(start 140.46126 118.7207)
		(end 142.41739 118.7207)
		(width 0.2032)
		(layer "F.Cu")
		(net "ANT4_IO_OUT")
	)
	(segment
		(start 78.89244 143.68704)
		(end 78.9216 143.7162)
		(width 0.254)
		(layer "F.Cu")
		(net "ANT4_IO_OUT")
	)
	(via
		(at 142.41739 117.73718)
		(size 0.4064)
		(drill 0.2032)
		(layers "F.Cu" "B.Cu")
		(tenting
			(front yes)
			(back yes)
		)
		(net "ANT4_IO_OUT")
	)
	(via
		(at 78.9216 143.7162)
		(size 0.4064)
		(drill 0.2032)
		(layers "F.Cu" "B.Cu")
		(net "ANT4_IO_OUT")
	)
	(segment
		(start 140.37586 117.78516)
		(end 142.08953 117.78516)
		(width 0.254)
		(layer "In3.Cu")
		(net "ANT4_IO_OUT")
	)
	(segment
		(start 134.4216 131.0162)
		(end 136.28555 129.15225)
		(width 0.254)
		(layer "In3.Cu")
		(net "ANT4_IO_OUT")
	)
	(segment
		(start 142.08953 117.78516)
		(end 142.10835 117.76634)
		(width 0.254)
		(layer "In3.Cu")
		(net "ANT4_IO_OUT")
	)
	(segment
		(start 139.29185 116.70115)
		(end 140.37586 117.78516)
		(width 0.254)
		(layer "In3.Cu")
		(net "ANT4_IO_OUT")
	)
	(segment
		(start 129.6216 119.3162)
		(end 132.23665 116.70115)
		(width 0.254)
		(layer "In3.Cu")
		(net "ANT4_IO_OUT")
	)
	(segment
		(start 111.2216 131.0162)
		(end 134.4216 131.0162)
		(width 0.254)
		(layer "In3.Cu")
		(net "ANT4_IO_OUT")
	)
	(segment
		(start 129.6216 123.0162)
		(end 129.6216 119.3162)
		(width 0.254)
		(layer "In3.Cu")
		(net "ANT4_IO_OUT")
	)
	(segment
		(start 129.6216 123.0162)
		(end 130.9216 124.3162)
		(width 0.254)
		(layer "In3.Cu")
		(net "ANT4_IO_OUT")
	)
	(segment
		(start 142.10835 117.76634)
		(end 142.38824 117.76634)
		(width 0.254)
		(layer "In3.Cu")
		(net "ANT4_IO_OUT")
	)
	(segment
		(start 132.23665 116.70115)
		(end 139.29185 116.70115)
		(width 0.254)
		(layer "In3.Cu")
		(net "ANT4_IO_OUT")
	)
	(segment
		(start 98.5216 143.7162)
		(end 111.2216 131.0162)
		(width 0.254)
		(layer "In3.Cu")
		(net "ANT4_IO_OUT")
	)
	(segment
		(start 130.9216 124.3162)
		(end 134.996 124.3162)
		(width 0.254)
		(layer "In3.Cu")
		(net "ANT4_IO_OUT")
	)
	(segment
		(start 136.28555 129.15225)
		(end 136.28555 125.60575)
		(width 0.254)
		(layer "In3.Cu")
		(net "ANT4_IO_OUT")
	)
	(segment
		(start 134.996 124.3162)
		(end 136.28555 125.60575)
		(width 0.254)
		(layer "In3.Cu")
		(net "ANT4_IO_OUT")
	)
	(segment
		(start 142.38824 117.76634)
		(end 142.41739 117.73718)
		(width 0.254)
		(layer "In3.Cu")
		(net "ANT4_IO_OUT")
	)
	(segment
		(start 78.9216 143.7162)
		(end 98.5216 143.7162)
		(width 0.254)
		(layer "In3.Cu")
		(net "ANT4_IO_OUT")
	)
	(segment
		(start 73.2216 142.6162)
		(end 73.6716 142.1662)
		(width 0.2032)
		(layer "F.Cu")
		(net "ANT4_IO_IN")
	)
	(segment
		(start 73.6716 142.1662)
		(end 74.5466 142.1662)
		(width 0.2032)
		(layer "F.Cu")
		(net "ANT4_IO_IN")
	)
	(segment
		(start 140.46126 118.22058)
		(end 141.90015 118.22058)
		(width 0.2032)
		(layer "F.Cu")
		(net "ANT4_IO_IN")
	)
	(segment
		(start 141.90015 118.22058)
		(end 141.90015 117.32796)
		(width 0.2032)
		(layer "F.Cu")
		(net "ANT4_IO_IN")
	)
	(segment
		(start 73.2216 142.9912)
		(end 73.2216 142.6162)
		(width 0.2032)
		(layer "F.Cu")
		(net "ANT4_IO_IN")
	)
	(segment
		(start 71.8216 142.9912)
		(end 73.2216 142.9912)
		(width 0.2032)
		(layer "F.Cu")
		(net "ANT4_IO_IN")
	)
	(via
		(at 73.2216 142.6162)
		(size 0.4064)
		(drill 0.2032)
		(layers "F.Cu" "B.Cu")
		(net "ANT4_IO_IN")
	)
	(via
		(at 141.90015 117.32796)
		(size 0.4064)
		(drill 0.2032)
		(layers "F.Cu" "B.Cu")
		(tenting
			(front yes)
			(back yes)
		)
		(net "ANT4_IO_IN")
	)
	(segment
		(start 129.1216 123.1162)
		(end 130.7216 124.7162)
		(width 0.2032)
		(layer "In3.Cu")
		(net "ANT4_IO_IN")
	)
	(segment
		(start 77.38461 142.26569)
		(end 97.47211 142.26569)
		(width 0.2032)
		(layer "In3.Cu")
		(net "ANT4_IO_IN")
	)
	(segment
		(start 129.1216 123.1162)
		(end 129.1216 119.1162)
		(width 0.2032)
		(layer "In3.Cu")
		(net "ANT4_IO_IN")
	)
	(segment
		(start 140.91775 116.34555)
		(end 141.90015 117.32796)
		(width 0.2032)
		(layer "In3.Cu")
		(net "ANT4_IO_IN")
	)
	(segment
		(start 129.1216 119.1162)
		(end 131.89225 116.34555)
		(width 0.2032)
		(layer "In3.Cu")
		(net "ANT4_IO_IN")
	)
	(segment
		(start 134.42528 128.9162)
		(end 135.63653 127.70494)
		(width 0.2032)
		(layer "In3.Cu")
		(net "ANT4_IO_IN")
	)
	(segment
		(start 77.0341 142.6162)
		(end 77.38461 142.26569)
		(width 0.2032)
		(layer "In3.Cu")
		(net "ANT4_IO_IN")
	)
	(segment
		(start 135.63653 127.70494)
		(end 135.63653 125.46894)
		(width 0.2032)
		(layer "In3.Cu")
		(net "ANT4_IO_IN")
	)
	(segment
		(start 130.7216 124.7162)
		(end 134.8838 124.7162)
		(width 0.2032)
		(layer "In3.Cu")
		(net "ANT4_IO_IN")
	)
	(segment
		(start 131.89225 116.34555)
		(end 140.91775 116.34555)
		(width 0.2032)
		(layer "In3.Cu")
		(net "ANT4_IO_IN")
	)
	(segment
		(start 97.47211 142.26569)
		(end 110.8216 128.9162)
		(width 0.2032)
		(layer "In3.Cu")
		(net "ANT4_IO_IN")
	)
	(segment
		(start 134.8838 124.7162)
		(end 135.63653 125.46894)
		(width 0.2032)
		(layer "In3.Cu")
		(net "ANT4_IO_IN")
	)
	(segment
		(start 73.2216 142.6162)
		(end 77.0341 142.6162)
		(width 0.2032)
		(layer "In3.Cu")
		(net "ANT4_IO_IN")
	)
	(segment
		(start 110.8216 128.9162)
		(end 134.42528 128.9162)
		(width 0.2032)
		(layer "In3.Cu")
		(net "ANT4_IO_IN")
	)
	(segment
		(start 155.8216 101.3162)
		(end 155.8216 101.26121)
		(width 0.2032)
		(layer "F.Cu")
		(net "ANT4_IN")
	)
	(segment
		(start 155.54892 100.98853)
		(end 155.54892 99.26063)
		(width 0.2032)
		(layer "F.Cu")
		(net "ANT4_IN")
	)
	(segment
		(start 78.32 141.6178)
		(end 79.1216 140.8162)
		(width 0.2032)
		(layer "F.Cu")
		(net "ANT4_IN")
	)
	(segment
		(start 77.6966 141.6662)
		(end 77.745 141.6178)
		(width 0.2032)
		(layer "F.Cu")
		(net "ANT4_IN")
	)
	(segment
		(start 77.745 141.6178)
		(end 78.32 141.6178)
		(width 0.2032)
		(layer "F.Cu")
		(net "ANT4_IN")
	)
	(segment
		(start 155.54892 100.98853)
		(end 155.8216 101.26121)
		(width 0.2032)
		(layer "F.Cu")
		(net "ANT4_IN")
	)
	(via
		(at 155.8216 101.3162)
		(size 0.4064)
		(drill 0.2032)
		(layers "F.Cu" "B.Cu")
		(tenting
			(front yes)
			(back yes)
		)
		(net "ANT4_IN")
	)
	(via
		(at 79.1216 140.8162)
		(size 0.4064)
		(drill 0.2032)
		(layers "F.Cu" "B.Cu")
		(net "ANT4_IN")
	)
	(segment
		(start 156.47987 101.27447)
		(end 157.0216 101.8162)
		(width 0.2032)
		(layer "In3.Cu")
		(net "ANT4_IN")
	)
	(segment
		(start 130.90622 115.49017)
		(end 131.18688 115.77082)
		(width 0.2032)
		(layer "In3.Cu")
		(net "ANT4_IN")
	)
	(segment
		(start 145.9216 117.4162)
		(end 157.4216 105.9162)
		(width 0.2032)
		(layer "In3.Cu")
		(net "ANT4_IN")
	)
	(segment
		(start 144.0216 116.4162)
		(end 145.0216 117.4162)
		(width 0.2032)
		(layer "In3.Cu")
		(net "ANT4_IN")
	)
	(segment
		(start 157.0216 103.68136)
		(end 157.0216 101.8162)
		(width 0.2032)
		(layer "In3.Cu")
		(net "ANT4_IN")
	)
	(segment
		(start 155.8216 101.3162)
		(end 155.86048 101.27732)
		(width 0.2032)
		(layer "In3.Cu")
		(net "ANT4_IN")
	)
	(segment
		(start 119.80836 117.80444)
		(end 124.26963 117.80444)
		(width 0.2032)
		(layer "In3.Cu")
		(net "ANT4_IN")
	)
	(segment
		(start 124.26963 117.80444)
		(end 126.5839 115.49017)
		(width 0.2032)
		(layer "In3.Cu")
		(net "ANT4_IN")
	)
	(segment
		(start 141.60969 116.4162)
		(end 144.0216 116.4162)
		(width 0.2032)
		(layer "In3.Cu")
		(net "ANT4_IN")
	)
	(segment
		(start 157.0216 103.68136)
		(end 157.4216 104.08135)
		(width 0.2032)
		(layer "In3.Cu")
		(net "ANT4_IN")
	)
	(segment
		(start 156.27667 101.27447)
		(end 156.47987 101.27447)
		(width 0.2032)
		(layer "In3.Cu")
		(net "ANT4_IN")
	)
	(segment
		(start 155.86048 101.27732)
		(end 156.27383 101.27732)
		(width 0.2032)
		(layer "In3.Cu")
		(net "ANT4_IN")
	)
	(segment
		(start 145.0216 117.4162)
		(end 145.9216 117.4162)
		(width 0.2032)
		(layer "In3.Cu")
		(net "ANT4_IN")
	)
	(segment
		(start 131.18688 115.77082)
		(end 140.96432 115.77082)
		(width 0.2032)
		(layer "In3.Cu")
		(net "ANT4_IN")
	)
	(segment
		(start 157.4216 105.9162)
		(end 157.4216 104.08135)
		(width 0.2032)
		(layer "In3.Cu")
		(net "ANT4_IN")
	)
	(segment
		(start 140.96432 115.77082)
		(end 141.60969 116.4162)
		(width 0.2032)
		(layer "In3.Cu")
		(net "ANT4_IN")
	)
	(segment
		(start 79.1216 140.8162)
		(end 85.8216 134.1162)
		(width 0.2032)
		(layer "In3.Cu")
		(net "ANT4_IN")
	)
	(segment
		(start 156.27383 101.27732)
		(end 156.27667 101.27447)
		(width 0.2032)
		(layer "In3.Cu")
		(net "ANT4_IN")
	)
	(segment
		(start 126.5839 115.49017)
		(end 130.90622 115.49017)
		(width 0.2032)
		(layer "In3.Cu")
		(net "ANT4_IN")
	)
	(segment
		(start 85.8216 134.1162)
		(end 103.4966 134.1162)
		(width 0.2032)
		(layer "In3.Cu")
		(net "ANT4_IN")
	)
	(segment
		(start 103.4966 134.1162)
		(end 119.80836 117.80444)
		(width 0.2032)
		(layer "In3.Cu")
		(net "ANT4_IN")
	)
	(segment
		(start 157.54891 105.02447)
		(end 157.91612 105.02447)
		(width 0.2032)
		(layer "F.Cu")
		(net "ANT3_OUT")
	)
	(segment
		(start 78.99659 128.7662)
		(end 81.0216 128.7662)
		(width 0.2032)
		(layer "F.Cu")
		(net "ANT3_OUT")
	)
	(segment
		(start 157.54891 105.02447)
		(end 157.54891 103.31041)
		(width 0.2032)
		(layer "F.Cu")
		(net "ANT3_OUT")
	)
	(via
		(at 157.91612 105.02447)
		(size 0.4064)
		(drill 0.2032)
		(layers "F.Cu" "B.Cu")
		(tenting
			(front yes)
			(back yes)
		)
		(net "ANT3_OUT")
	)
	(via
		(at 81.0216 128.7662)
		(size 0.4064)
		(drill 0.2032)
		(layers "F.Cu" "B.Cu")
		(net "ANT3_OUT")
	)
	(segment
		(start 73.57161 130.56621)
		(end 75.35707 132.35167)
		(width 0.2032)
		(layer "In3.Cu")
		(net "ANT3_OUT")
	)
	(segment
		(start 73.89144 143.64521)
		(end 75.36243 145.1162)
		(width 0.2032)
		(layer "In3.Cu")
		(net "ANT3_OUT")
	)
	(segment
		(start 138.3216 128.5162)
		(end 138.3216 126.5162)
		(width 0.2032)
		(layer "In3.Cu")
		(net "ANT3_OUT")
	)
	(segment
		(start 136.13183 132.3162)
		(end 137.6216 130.82643)
		(width 0.2032)
		(layer "In3.Cu")
		(net "ANT3_OUT")
	)
	(segment
		(start 131.6216 122.8162)
		(end 132.2216 123.4162)
		(width 0.2032)
		(layer "In3.Cu")
		(net "ANT3_OUT")
	)
	(segment
		(start 99.8216 145.1162)
		(end 112.6216 132.3162)
		(width 0.2032)
		(layer "In3.Cu")
		(net "ANT3_OUT")
	)
	(segment
		(start 73.57161 128.58729)
		(end 74.04271 128.1162)
		(width 0.2032)
		(layer "In3.Cu")
		(net "ANT3_OUT")
	)
	(segment
		(start 73.23227 143.64521)
		(end 73.89144 143.64521)
		(width 0.2032)
		(layer "In3.Cu")
		(net "ANT3_OUT")
	)
	(segment
		(start 73.57161 130.56621)
		(end 73.57161 128.58729)
		(width 0.2032)
		(layer "In3.Cu")
		(net "ANT3_OUT")
	)
	(segment
		(start 157.91612 105.02447)
		(end 159.02729 103.9133)
		(width 0.2032)
		(layer "In3.Cu")
		(net "ANT3_OUT")
	)
	(segment
		(start 73.05431 141.90846)
		(end 73.12934 141.90846)
		(width 0.2032)
		(layer "In3.Cu")
		(net "ANT3_OUT")
	)
	(segment
		(start 136.67863 117.78037)
		(end 137.99387 119.09561)
		(width 0.2032)
		(layer "In3.Cu")
		(net "ANT3_OUT")
	)
	(segment
		(start 141.33175 119.09561)
		(end 142.39625 120.1601)
		(width 0.2032)
		(layer "In3.Cu")
		(net "ANT3_OUT")
	)
	(segment
		(start 161.64168 103.9133)
		(end 162.07082 104.34244)
		(width 0.2032)
		(layer "In3.Cu")
		(net "ANT3_OUT")
	)
	(segment
		(start 73.12934 141.90846)
		(end 75.35707 139.68073)
		(width 0.2032)
		(layer "In3.Cu")
		(net "ANT3_OUT")
	)
	(segment
		(start 131.6216 118.9854)
		(end 132.82662 117.78037)
		(width 0.2032)
		(layer "In3.Cu")
		(net "ANT3_OUT")
	)
	(segment
		(start 137.6216 129.2162)
		(end 138.3216 128.5162)
		(width 0.2032)
		(layer "In3.Cu")
		(net "ANT3_OUT")
	)
	(segment
		(start 136.10072 123.4162)
		(end 137.20072 124.5162)
		(width 0.2032)
		(layer "In3.Cu")
		(net "ANT3_OUT")
	)
	(segment
		(start 159.02729 103.9133)
		(end 161.64168 103.9133)
		(width 0.2032)
		(layer "In3.Cu")
		(net "ANT3_OUT")
	)
	(segment
		(start 142.39625 120.1601)
		(end 156.2777 120.1601)
		(width 0.2032)
		(layer "In3.Cu")
		(net "ANT3_OUT")
	)
	(segment
		(start 78.9905 128.1162)
		(end 79.6405 128.7662)
		(width 0.2032)
		(layer "In3.Cu")
		(net "ANT3_OUT")
	)
	(segment
		(start 137.99387 119.09561)
		(end 141.33175 119.09561)
		(width 0.2032)
		(layer "In3.Cu")
		(net "ANT3_OUT")
	)
	(segment
		(start 75.35707 139.68073)
		(end 75.35707 132.35167)
		(width 0.2032)
		(layer "In3.Cu")
		(net "ANT3_OUT")
	)
	(segment
		(start 72.5216 142.93454)
		(end 73.23227 143.64521)
		(width 0.2032)
		(layer "In3.Cu")
		(net "ANT3_OUT")
	)
	(segment
		(start 131.6216 122.8162)
		(end 131.6216 118.9854)
		(width 0.2032)
		(layer "In3.Cu")
		(net "ANT3_OUT")
	)
	(segment
		(start 156.2777 120.1601)
		(end 162.07082 114.36698)
		(width 0.2032)
		(layer "In3.Cu")
		(net "ANT3_OUT")
	)
	(segment
		(start 132.2216 123.4162)
		(end 136.10072 123.4162)
		(width 0.2032)
		(layer "In3.Cu")
		(net "ANT3_OUT")
	)
	(segment
		(start 72.5216 142.93454)
		(end 72.5216 142.44116)
		(width 0.2032)
		(layer "In3.Cu")
		(net "ANT3_OUT")
	)
	(segment
		(start 72.5216 142.44116)
		(end 73.05431 141.90846)
		(width 0.2032)
		(layer "In3.Cu")
		(net "ANT3_OUT")
	)
	(segment
		(start 137.20072 125.39532)
		(end 137.20072 124.5162)
		(width 0.2032)
		(layer "In3.Cu")
		(net "ANT3_OUT")
	)
	(segment
		(start 132.82662 117.78037)
		(end 136.67863 117.78037)
		(width 0.2032)
		(layer "In3.Cu")
		(net "ANT3_OUT")
	)
	(segment
		(start 75.36243 145.1162)
		(end 99.8216 145.1162)
		(width 0.2032)
		(layer "In3.Cu")
		(net "ANT3_OUT")
	)
	(segment
		(start 137.6216 130.82643)
		(end 137.6216 129.2162)
		(width 0.2032)
		(layer "In3.Cu")
		(net "ANT3_OUT")
	)
	(segment
		(start 137.20072 125.39532)
		(end 138.3216 126.5162)
		(width 0.2032)
		(layer "In3.Cu")
		(net "ANT3_OUT")
	)
	(segment
		(start 162.07082 114.36698)
		(end 162.07082 104.34244)
		(width 0.2032)
		(layer "In3.Cu")
		(net "ANT3_OUT")
	)
	(segment
		(start 79.6405 128.7662)
		(end 81.0216 128.7662)
		(width 0.2032)
		(layer "In3.Cu")
		(net "ANT3_OUT")
	)
	(segment
		(start 74.04271 128.1162)
		(end 78.9905 128.1162)
		(width 0.2032)
		(layer "In3.Cu")
		(net "ANT3_OUT")
	)
	(segment
		(start 112.6216 132.3162)
		(end 136.13183 132.3162)
		(width 0.2032)
		(layer "In3.Cu")
		(net "ANT3_OUT")
	)
	(segment
		(start 143.03271 119.7207)
		(end 143.6216 119.13181)
		(width 0.2032)
		(layer "F.Cu")
		(net "ANT3_IO_OUT")
	)
	(segment
		(start 78.99659 130.99275)
		(end 78.99659 129.2662)
		(width 0.2032)
		(layer "F.Cu")
		(net "ANT3_IO_OUT")
	)
	(segment
		(start 143.6216 119.13181)
		(end 143.6216 115.4162)
		(width 0.2032)
		(layer "F.Cu")
		(net "ANT3_IO_OUT")
	)
	(segment
		(start 140.46126 119.7207)
		(end 143.03271 119.7207)
		(width 0.2032)
		(layer "F.Cu")
		(net "ANT3_IO_OUT")
	)
	(via
		(at 143.6216 115.4162)
		(size 0.4064)
		(drill 0.2032)
		(layers "F.Cu" "B.Cu")
		(tenting
			(front yes)
			(back yes)
		)
		(net "ANT3_IO_OUT")
	)
	(via
		(at 78.99659 130.99275)
		(size 0.4064)
		(drill 0.2032)
		(layers "F.Cu" "B.Cu")
		(net "ANT3_IO_OUT")
	)
	(segment
		(start 78.9466 130.99275)
		(end 78.99659 130.99275)
		(width 0.2032)
		(layer "B.Cu")
		(net "ANT3_IO_OUT")
	)
	(segment
		(start 78.9466 130.99275)
		(end 78.9466 130.0162)
		(width 0.2032)
		(layer "B.Cu")
		(net "ANT3_IO_OUT")
	)
	(segment
		(start 112.93988 117.89792)
		(end 118.83988 117.89792)
		(width 0.2032)
		(layer "In3.Cu")
		(net "ANT3_IO_OUT")
	)
	(segment
		(start 132.25626 114.59574)
		(end 140.7474 114.59574)
		(width 0.2032)
		(layer "In3.Cu")
		(net "ANT3_IO_OUT")
	)
	(segment
		(start 143.23871 115.75173)
		(end 143.57424 115.4162)
		(width 0.2032)
		(layer "In3.Cu")
		(net "ANT3_IO_OUT")
	)
	(segment
		(start 99.84505 130.99275)
		(end 112.93988 117.89792)
		(width 0.2032)
		(layer "In3.Cu")
		(net "ANT3_IO_OUT")
	)
	(segment
		(start 140.7474 114.59574)
		(end 141.90338 115.75173)
		(width 0.2032)
		(layer "In3.Cu")
		(net "ANT3_IO_OUT")
	)
	(segment
		(start 123.4216 113.3162)
		(end 130.97671 113.3162)
		(width 0.2032)
		(layer "In3.Cu")
		(net "ANT3_IO_OUT")
	)
	(segment
		(start 141.90338 115.75173)
		(end 143.23871 115.75173)
		(width 0.2032)
		(layer "In3.Cu")
		(net "ANT3_IO_OUT")
	)
	(segment
		(start 143.57424 115.4162)
		(end 143.6216 115.4162)
		(width 0.2032)
		(layer "In3.Cu")
		(net "ANT3_IO_OUT")
	)
	(segment
		(start 130.97671 113.3162)
		(end 132.25626 114.59574)
		(width 0.2032)
		(layer "In3.Cu")
		(net "ANT3_IO_OUT")
	)
	(segment
		(start 118.83988 117.89792)
		(end 123.4216 113.3162)
		(width 0.2032)
		(layer "In3.Cu")
		(net "ANT3_IO_OUT")
	)
	(segment
		(start 78.99659 130.99275)
		(end 99.84505 130.99275)
		(width 0.2032)
		(layer "In3.Cu")
		(net "ANT3_IO_OUT")
	)
	(segment
		(start 140.46126 119.22057)
		(end 142.38448 119.22057)
		(width 0.2032)
		(layer "F.Cu")
		(net "ANT3_IO_IN")
	)
	(segment
		(start 74.8216 129.3162)
		(end 75.3232 128.8146)
		(width 0.2032)
		(layer "F.Cu")
		(net "ANT3_IO_IN")
	)
	(segment
		(start 143.0216 118.58346)
		(end 143.0216 115.67119)
		(width 0.2032)
		(layer "F.Cu")
		(net "ANT3_IO_IN")
	)
	(segment
		(start 75.3232 128.8146)
		(end 75.79819 128.8146)
		(width 0.2032)
		(layer "F.Cu")
		(net "ANT3_IO_IN")
	)
	(segment
		(start 142.5216 115.17118)
		(end 143.0216 115.67119)
		(width 0.2032)
		(layer "F.Cu")
		(net "ANT3_IO_IN")
	)
	(segment
		(start 75.79819 128.8146)
		(end 75.84659 128.7662)
		(width 0.2032)
		(layer "F.Cu")
		(net "ANT3_IO_IN")
	)
	(segment
		(start 142.5216 115.17118)
		(end 142.5216 115.1162)
		(width 0.2032)
		(layer "F.Cu")
		(net "ANT3_IO_IN")
	)
	(segment
		(start 142.38448 119.22057)
		(end 143.0216 118.58346)
		(width 0.2032)
		(layer "F.Cu")
		(net "ANT3_IO_IN")
	)
	(via
		(at 74.8216 129.3162)
		(size 0.4064)
		(drill 0.2032)
		(layers "F.Cu" "B.Cu")
		(net "ANT3_IO_IN")
	)
	(via
		(at 142.5216 115.1162)
		(size 0.4064)
		(drill 0.2032)
		(layers "F.Cu" "B.Cu")
		(tenting
			(front yes)
			(back yes)
		)
		(net "ANT3_IO_IN")
	)
	(segment
		(start 76.7216 129.4912)
		(end 76.7216 129.3162)
		(width 0.2032)
		(layer "B.Cu")
		(net "ANT3_IO_IN")
	)
	(segment
		(start 74.8216 129.3162)
		(end 76.7216 129.3162)
		(width 0.2032)
		(layer "B.Cu")
		(net "ANT3_IO_IN")
	)
	(segment
		(start 136.85342 114.1739)
		(end 141.5793 114.1739)
		(width 0.2032)
		(layer "In3.Cu")
		(net "ANT3_IO_IN")
	)
	(segment
		(start 90.8216 129.7162)
		(end 99.9216 129.7162)
		(width 0.2032)
		(layer "In3.Cu")
		(net "ANT3_IO_IN")
	)
	(segment
		(start 74.8216 129.3162)
		(end 77.07159 129.3162)
		(width 0.2032)
		(layer "In3.Cu")
		(net "ANT3_IO_IN")
	)
	(segment
		(start 141.5793 114.1739)
		(end 142.5216 115.1162)
		(width 0.2032)
		(layer "In3.Cu")
		(net "ANT3_IO_IN")
	)
	(segment
		(start 77.07159 129.3162)
		(end 78.07159 130.3162)
		(width 0.2032)
		(layer "In3.Cu")
		(net "ANT3_IO_IN")
	)
	(segment
		(start 112.3216 117.3162)
		(end 118.4216 117.3162)
		(width 0.2032)
		(layer "In3.Cu")
		(net "ANT3_IO_IN")
	)
	(segment
		(start 122.85536 112.88244)
		(end 135.56196 112.88244)
		(width 0.2032)
		(layer "In3.Cu")
		(net "ANT3_IO_IN")
	)
	(segment
		(start 135.56196 112.88244)
		(end 136.85342 114.1739)
		(width 0.2032)
		(layer "In3.Cu")
		(net "ANT3_IO_IN")
	)
	(segment
		(start 78.07159 130.3162)
		(end 90.2216 130.3162)
		(width 0.2032)
		(layer "In3.Cu")
		(net "ANT3_IO_IN")
	)
	(segment
		(start 90.2216 130.3162)
		(end 90.8216 129.7162)
		(width 0.2032)
		(layer "In3.Cu")
		(net "ANT3_IO_IN")
	)
	(segment
		(start 118.4216 117.3162)
		(end 122.85536 112.88244)
		(width 0.2032)
		(layer "In3.Cu")
		(net "ANT3_IO_IN")
	)
	(segment
		(start 99.9216 129.7162)
		(end 112.3216 117.3162)
		(width 0.2032)
		(layer "In3.Cu")
		(net "ANT3_IO_IN")
	)
	(segment
		(start 155.04905 100.59723)
		(end 155.04905 99.26063)
		(width 0.2032)
		(layer "F.Cu")
		(net "ANT3_IN")
	)
	(segment
		(start 78.99659 128.2662)
		(end 80.4716 128.2662)
		(width 0.2032)
		(layer "F.Cu")
		(net "ANT3_IN")
	)
	(segment
		(start 80.4716 128.2662)
		(end 81.0216 127.7162)
		(width 0.2032)
		(layer "F.Cu")
		(net "ANT3_IN")
	)
	(segment
		(start 155.04905 100.59723)
		(end 155.10467 100.59723)
		(width 0.2032)
		(layer "F.Cu")
		(net "ANT3_IN")
	)
	(via
		(at 155.10467 100.59723)
		(size 0.4064)
		(drill 0.2032)
		(layers "F.Cu" "B.Cu")
		(tenting
			(front yes)
			(back yes)
		)
		(net "ANT3_IN")
	)
	(via
		(at 81.0216 127.7162)
		(size 0.4064)
		(drill 0.2032)
		(layers "F.Cu" "B.Cu")
		(net "ANT3_IN")
	)
	(segment
		(start 131.39453 94.2162)
		(end 135.24418 98.06585)
		(width 0.2032)
		(layer "In3.Cu")
		(net "ANT3_IN")
	)
	(segment
		(start 73.3216 103.08178)
		(end 73.3216 101.26797)
		(width 0.2032)
		(layer "In3.Cu")
		(net "ANT3_IN")
	)
	(segment
		(start 149.16464 101.81119)
		(end 151.8266 101.81119)
		(width 0.2032)
		(layer "In3.Cu")
		(net "ANT3_IN")
	)
	(segment
		(start 73.3216 103.08178)
		(end 73.32745 103.08178)
		(width 0.2032)
		(layer "In3.Cu")
		(net "ANT3_IN")
	)
	(segment
		(start 78.1216 113.3162)
		(end 78.1216 105.86661)
		(width 0.2032)
		(layer "In3.Cu")
		(net "ANT3_IN")
	)
	(segment
		(start 78.4534 116.348)
		(end 81.0216 118.9162)
		(width 0.2032)
		(layer "In3.Cu")
		(net "ANT3_IN")
	)
	(segment
		(start 123.3216 94.2162)
		(end 131.39453 94.2162)
		(width 0.2032)
		(layer "In3.Cu")
		(net "ANT3_IN")
	)
	(segment
		(start 74.07759 114.3162)
		(end 74.47759 113.9162)
		(width 0.2032)
		(layer "In3.Cu")
		(net "ANT3_IN")
	)
	(segment
		(start 154.68751 100.18007)
		(end 155.10467 100.59723)
		(width 0.2032)
		(layer "In3.Cu")
		(net "ANT3_IN")
	)
	(segment
		(start 75.04538 99.54419)
		(end 114.39361 99.54419)
		(width 0.2032)
		(layer "In3.Cu")
		(net "ANT3_IN")
	)
	(segment
		(start 74.07759 115.336)
		(end 74.95779 116.2162)
		(width 0.2032)
		(layer "In3.Cu")
		(net "ANT3_IN")
	)
	(segment
		(start 81.0216 127.7162)
		(end 81.0216 118.9162)
		(width 0.2032)
		(layer "In3.Cu")
		(net "ANT3_IN")
	)
	(segment
		(start 114.39361 99.54419)
		(end 119.49382 94.44398)
		(width 0.2032)
		(layer "In3.Cu")
		(net "ANT3_IN")
	)
	(segment
		(start 147.56964 100.2162)
		(end 149.16464 101.81119)
		(width 0.2032)
		(layer "In3.Cu")
		(net "ANT3_IN")
	)
	(segment
		(start 142.7216 100.2162)
		(end 147.56964 100.2162)
		(width 0.2032)
		(layer "In3.Cu")
		(net "ANT3_IN")
	)
	(segment
		(start 76.94274 116.348)
		(end 78.4534 116.348)
		(width 0.2032)
		(layer "In3.Cu")
		(net "ANT3_IN")
	)
	(segment
		(start 140.57125 98.06585)
		(end 142.7216 100.2162)
		(width 0.2032)
		(layer "In3.Cu")
		(net "ANT3_IN")
	)
	(segment
		(start 153.08988 100.43302)
		(end 153.34282 100.18007)
		(width 0.2032)
		(layer "In3.Cu")
		(net "ANT3_IN")
	)
	(segment
		(start 73.32745 103.08178)
		(end 75.66187 105.4162)
		(width 0.2032)
		(layer "In3.Cu")
		(net "ANT3_IN")
	)
	(segment
		(start 73.3216 101.26797)
		(end 75.04538 99.54419)
		(width 0.2032)
		(layer "In3.Cu")
		(net "ANT3_IN")
	)
	(segment
		(start 123.09382 94.44398)
		(end 123.3216 94.2162)
		(width 0.2032)
		(layer "In3.Cu")
		(net "ANT3_IN")
	)
	(segment
		(start 153.08988 100.54792)
		(end 153.08988 100.43302)
		(width 0.2032)
		(layer "In3.Cu")
		(net "ANT3_IN")
	)
	(segment
		(start 74.47759 113.9162)
		(end 77.5216 113.9162)
		(width 0.2032)
		(layer "In3.Cu")
		(net "ANT3_IN")
	)
	(segment
		(start 77.5216 113.9162)
		(end 78.1216 113.3162)
		(width 0.2032)
		(layer "In3.Cu")
		(net "ANT3_IN")
	)
	(segment
		(start 74.95779 116.2162)
		(end 76.81094 116.2162)
		(width 0.2032)
		(layer "In3.Cu")
		(net "ANT3_IN")
	)
	(segment
		(start 75.66187 105.4162)
		(end 77.67119 105.4162)
		(width 0.2032)
		(layer "In3.Cu")
		(net "ANT3_IN")
	)
	(segment
		(start 151.8266 101.81119)
		(end 153.08988 100.54792)
		(width 0.2032)
		(layer "In3.Cu")
		(net "ANT3_IN")
	)
	(segment
		(start 135.24418 98.06585)
		(end 140.57125 98.06585)
		(width 0.2032)
		(layer "In3.Cu")
		(net "ANT3_IN")
	)
	(segment
		(start 77.67119 105.4162)
		(end 78.1216 105.86661)
		(width 0.2032)
		(layer "In3.Cu")
		(net "ANT3_IN")
	)
	(segment
		(start 76.81094 116.2162)
		(end 76.94274 116.348)
		(width 0.2032)
		(layer "In3.Cu")
		(net "ANT3_IN")
	)
	(segment
		(start 153.34282 100.18007)
		(end 154.68751 100.18007)
		(width 0.2032)
		(layer "In3.Cu")
		(net "ANT3_IN")
	)
	(segment
		(start 74.07759 115.336)
		(end 74.07759 114.3162)
		(width 0.2032)
		(layer "In3.Cu")
		(net "ANT3_IN")
	)
	(segment
		(start 119.49382 94.44398)
		(end 123.09382 94.44398)
		(width 0.2032)
		(layer "In3.Cu")
		(net "ANT3_IN")
	)
	(segment
		(start 78.99659 114.2662)
		(end 80.7716 114.2662)
		(width 0.2032)
		(layer "F.Cu")
		(net "ANT2_OUT")
	)
	(segment
		(start 155.54892 103.31041)
		(end 155.54892 102.02447)
		(width 0.2032)
		(layer "F.Cu")
		(net "ANT2_OUT")
	)
	(segment
		(start 80.7716 114.2662)
		(end 81.3216 114.8162)
		(width 0.2032)
		(layer "F.Cu")
		(net "ANT2_OUT")
	)
	(segment
		(start 155.34667 102.02447)
		(end 155.54892 102.02447)
		(width 0.2032)
		(layer "F.Cu")
		(net "ANT2_OUT")
	)
	(via
		(at 155.34667 102.02447)
		(size 0.4064)
		(drill 0.2032)
		(layers "F.Cu" "B.Cu")
		(tenting
			(front yes)
			(back yes)
		)
		(net "ANT2_OUT")
	)
	(via
		(at 81.3216 114.8162)
		(size 0.4064)
		(drill 0.2032)
		(layers "F.Cu" "B.Cu")
		(net "ANT2_OUT")
	)
	(segment
		(start 80.6526 114.8162)
		(end 81.3216 114.8162)
		(width 0.2032)
		(layer "In3.Cu")
		(net "ANT2_OUT")
	)
	(segment
		(start 73.8216 101.5162)
		(end 75.25825 100.07954)
		(width 0.2032)
		(layer "In3.Cu")
		(net "ANT2_OUT")
	)
	(segment
		(start 152.29416 102.3162)
		(end 153.39416 101.2162)
		(width 0.2032)
		(layer "In3.Cu")
		(net "ANT2_OUT")
	)
	(segment
		(start 77.70578 104.6162)
		(end 78.7216 105.63201)
		(width 0.2032)
		(layer "In3.Cu")
		(net "ANT2_OUT")
	)
	(segment
		(start 154.5384 101.2162)
		(end 155.34667 102.02447)
		(width 0.2032)
		(layer "In3.Cu")
		(net "ANT2_OUT")
	)
	(segment
		(start 140.61151 100.6162)
		(end 147.3216 100.6162)
		(width 0.2032)
		(layer "In3.Cu")
		(net "ANT2_OUT")
	)
	(segment
		(start 135.0216 101.0162)
		(end 136.2216 102.2162)
		(width 0.2032)
		(layer "In3.Cu")
		(net "ANT2_OUT")
	)
	(segment
		(start 123.83222 95.30557)
		(end 124.4216 94.7162)
		(width 0.2032)
		(layer "In3.Cu")
		(net "ANT2_OUT")
	)
	(segment
		(start 153.39416 101.2162)
		(end 154.5384 101.2162)
		(width 0.2032)
		(layer "In3.Cu")
		(net "ANT2_OUT")
	)
	(segment
		(start 73.8216 102.93003)
		(end 73.8216 101.5162)
		(width 0.2032)
		(layer "In3.Cu")
		(net "ANT2_OUT")
	)
	(segment
		(start 78.7216 112.88519)
		(end 80.6526 114.8162)
		(width 0.2032)
		(layer "In3.Cu")
		(net "ANT2_OUT")
	)
	(segment
		(start 119.53223 95.30557)
		(end 123.83222 95.30557)
		(width 0.2032)
		(layer "In3.Cu")
		(net "ANT2_OUT")
	)
	(segment
		(start 114.75826 100.07954)
		(end 119.53223 95.30557)
		(width 0.2032)
		(layer "In3.Cu")
		(net "ANT2_OUT")
	)
	(segment
		(start 135.0216 101.0162)
		(end 135.0216 99.27021)
		(width 0.2032)
		(layer "In3.Cu")
		(net "ANT2_OUT")
	)
	(segment
		(start 149.0216 102.3162)
		(end 152.29416 102.3162)
		(width 0.2032)
		(layer "In3.Cu")
		(net "ANT2_OUT")
	)
	(segment
		(start 75.25825 100.07954)
		(end 114.75826 100.07954)
		(width 0.2032)
		(layer "In3.Cu")
		(net "ANT2_OUT")
	)
	(segment
		(start 147.3216 100.6162)
		(end 149.0216 102.3162)
		(width 0.2032)
		(layer "In3.Cu")
		(net "ANT2_OUT")
	)
	(segment
		(start 73.97693 102.93003)
		(end 75.66309 104.6162)
		(width 0.2032)
		(layer "In3.Cu")
		(net "ANT2_OUT")
	)
	(segment
		(start 73.8216 102.93003)
		(end 73.97693 102.93003)
		(width 0.2032)
		(layer "In3.Cu")
		(net "ANT2_OUT")
	)
	(segment
		(start 75.66309 104.6162)
		(end 77.70578 104.6162)
		(width 0.2032)
		(layer "In3.Cu")
		(net "ANT2_OUT")
	)
	(segment
		(start 124.4216 94.7162)
		(end 130.46759 94.7162)
		(width 0.2032)
		(layer "In3.Cu")
		(net "ANT2_OUT")
	)
	(segment
		(start 136.2216 102.2162)
		(end 139.01151 102.2162)
		(width 0.2032)
		(layer "In3.Cu")
		(net "ANT2_OUT")
	)
	(segment
		(start 130.46759 94.7162)
		(end 135.0216 99.27021)
		(width 0.2032)
		(layer "In3.Cu")
		(net "ANT2_OUT")
	)
	(segment
		(start 78.7216 112.88519)
		(end 78.7216 105.63201)
		(width 0.2032)
		(layer "In3.Cu")
		(net "ANT2_OUT")
	)
	(segment
		(start 139.01151 102.2162)
		(end 140.61151 100.6162)
		(width 0.2032)
		(layer "In3.Cu")
		(net "ANT2_OUT")
	)
	(segment
		(start 78.99659 114.7662)
		(end 80.3716 114.7662)
		(width 0.2032)
		(layer "F.Cu")
		(net "ANT2_IO_OUT")
	)
	(segment
		(start 140.46126 121.22057)
		(end 143.01723 121.22057)
		(width 0.2032)
		(layer "F.Cu")
		(net "ANT2_IO_OUT")
	)
	(segment
		(start 143.01723 121.22057)
		(end 144.9216 119.3162)
		(width 0.2032)
		(layer "F.Cu")
		(net "ANT2_IO_OUT")
	)
	(segment
		(start 81.0216 115.9162)
		(end 81.0216 115.4162)
		(width 0.2032)
		(layer "F.Cu")
		(net "ANT2_IO_OUT")
	)
	(segment
		(start 80.3716 114.7662)
		(end 81.0216 115.4162)
		(width 0.2032)
		(layer "F.Cu")
		(net "ANT2_IO_OUT")
	)
	(segment
		(start 78.9466 115.9162)
		(end 81.0216 115.9162)
		(width 0.2032)
		(layer "F.Cu")
		(net "ANT2_IO_OUT")
	)
	(segment
		(start 144.9216 119.3162)
		(end 144.9216 114.2162)
		(width 0.2032)
		(layer "F.Cu")
		(net "ANT2_IO_OUT")
	)
	(segment
		(start 143.3216 112.6162)
		(end 144.9216 114.2162)
		(width 0.2032)
		(layer "F.Cu")
		(net "ANT2_IO_OUT")
	)
	(via
		(at 81.0216 115.4162)
		(size 0.4064)
		(drill 0.2032)
		(layers "F.Cu" "B.Cu")
		(net "ANT2_IO_OUT")
	)
	(via
		(at 143.3216 112.6162)
		(size 0.4064)
		(drill 0.2032)
		(layers "F.Cu" "B.Cu")
		(tenting
			(front yes)
			(back yes)
		)
		(net "ANT2_IO_OUT")
	)
	(segment
		(start 105.91822 120.3162)
		(end 112.91822 113.3162)
		(width 0.2032)
		(layer "In3.Cu")
		(net "ANT2_IO_OUT")
	)
	(segment
		(start 81.0216 115.4162)
		(end 85.9216 120.3162)
		(width 0.2032)
		(layer "In3.Cu")
		(net "ANT2_IO_OUT")
	)
	(segment
		(start 112.91822 113.3162)
		(end 116.85195 113.3162)
		(width 0.2032)
		(layer "In3.Cu")
		(net "ANT2_IO_OUT")
	)
	(segment
		(start 116.85195 113.3162)
		(end 118.85195 111.3162)
		(width 0.2032)
		(layer "In3.Cu")
		(net "ANT2_IO_OUT")
	)
	(segment
		(start 85.9216 120.3162)
		(end 105.91822 120.3162)
		(width 0.2032)
		(layer "In3.Cu")
		(net "ANT2_IO_OUT")
	)
	(segment
		(start 118.85195 111.3162)
		(end 142.0216 111.3162)
		(width 0.2032)
		(layer "In3.Cu")
		(net "ANT2_IO_OUT")
	)
	(segment
		(start 142.0216 111.3162)
		(end 143.3216 112.6162)
		(width 0.2032)
		(layer "In3.Cu")
		(net "ANT2_IO_OUT")
	)
	(segment
		(start 74.66346 114.7162)
		(end 74.66346 114.2662)
		(width 0.2032)
		(layer "F.Cu")
		(net "ANT2_IO_IN")
	)
	(segment
		(start 143.02857 114.1242)
		(end 144.4216 115.51722)
		(width 0.2032)
		(layer "F.Cu")
		(net "ANT2_IO_IN")
	)
	(segment
		(start 74.66346 114.798)
		(end 74.66346 114.7162)
		(width 0.2032)
		(layer "F.Cu")
		(net "ANT2_IO_IN")
	)
	(segment
		(start 142.81204 120.7207)
		(end 144.4216 119.11114)
		(width 0.2032)
		(layer "F.Cu")
		(net "ANT2_IO_IN")
	)
	(segment
		(start 74.66346 114.2662)
		(end 75.84659 114.2662)
		(width 0.2032)
		(layer "F.Cu")
		(net "ANT2_IO_IN")
	)
	(segment
		(start 140.46126 120.7207)
		(end 142.81204 120.7207)
		(width 0.2032)
		(layer "F.Cu")
		(net "ANT2_IO_IN")
	)
	(segment
		(start 143.02857 114.1242)
		(end 143.02857 113.62317)
		(width 0.2032)
		(layer "F.Cu")
		(net "ANT2_IO_IN")
	)
	(segment
		(start 73.8466 114.7162)
		(end 74.66346 114.7162)
		(width 0.2032)
		(layer "F.Cu")
		(net "ANT2_IO_IN")
	)
	(segment
		(start 143.0216 113.6162)
		(end 143.02857 113.62317)
		(width 0.2032)
		(layer "F.Cu")
		(net "ANT2_IO_IN")
	)
	(segment
		(start 144.4216 119.11114)
		(end 144.4216 115.51722)
		(width 0.2032)
		(layer "F.Cu")
		(net "ANT2_IO_IN")
	)
	(via
		(at 143.0216 113.6162)
		(size 0.4064)
		(drill 0.2032)
		(layers "F.Cu" "B.Cu")
		(tenting
			(front yes)
			(back yes)
		)
		(net "ANT2_IO_IN")
	)
	(via
		(at 74.66346 114.798)
		(size 0.4064)
		(drill 0.2032)
		(layers "F.Cu" "B.Cu")
		(net "ANT2_IO_IN")
	)
	(segment
		(start 74.66346 114.798)
		(end 77.6034 114.798)
		(width 0.2032)
		(layer "In3.Cu")
		(net "ANT2_IO_IN")
	)
	(segment
		(start 106.7216 121.6162)
		(end 114.5534 113.7844)
		(width 0.2032)
		(layer "In3.Cu")
		(net "ANT2_IO_IN")
	)
	(segment
		(start 114.5534 113.7844)
		(end 117.54314 113.7844)
		(width 0.2032)
		(layer "In3.Cu")
		(net "ANT2_IO_IN")
	)
	(segment
		(start 77.6034 114.798)
		(end 84.4216 121.6162)
		(width 0.2032)
		(layer "In3.Cu")
		(net "ANT2_IO_IN")
	)
	(segment
		(start 117.54314 113.7844)
		(end 119.20475 112.12278)
		(width 0.2032)
		(layer "In3.Cu")
		(net "ANT2_IO_IN")
	)
	(segment
		(start 137.51136 113.6162)
		(end 143.0216 113.6162)
		(width 0.2032)
		(layer "In3.Cu")
		(net "ANT2_IO_IN")
	)
	(segment
		(start 119.20475 112.12278)
		(end 136.01794 112.12278)
		(width 0.2032)
		(layer "In3.Cu")
		(net "ANT2_IO_IN")
	)
	(segment
		(start 136.01794 112.12278)
		(end 137.51136 113.6162)
		(width 0.2032)
		(layer "In3.Cu")
		(net "ANT2_IO_IN")
	)
	(segment
		(start 84.4216 121.6162)
		(end 106.7216 121.6162)
		(width 0.2032)
		(layer "In3.Cu")
		(net "ANT2_IO_IN")
	)
	(segment
		(start 150.8216 106.3162)
		(end 155.6692 106.3162)
		(width 0.2032)
		(layer "F.Cu")
		(net "ANT2_IN")
	)
	(segment
		(start 78.99659 113.7662)
		(end 80.9716 113.7662)
		(width 0.2032)
		(layer "F.Cu")
		(net "ANT2_IN")
	)
	(segment
		(start 150.1216 105.6162)
		(end 150.8216 106.3162)
		(width 0.2032)
		(layer "F.Cu")
		(net "ANT2_IN")
	)
	(segment
		(start 155.6692 106.3162)
		(end 157.04904 104.93636)
		(width 0.2032)
		(layer "F.Cu")
		(net "ANT2_IN")
	)
	(segment
		(start 80.9716 113.7662)
		(end 81.4216 114.2162)
		(width 0.2032)
		(layer "F.Cu")
		(net "ANT2_IN")
	)
	(segment
		(start 157.04904 104.93636)
		(end 157.04904 103.31041)
		(width 0.2032)
		(layer "F.Cu")
		(net "ANT2_IN")
	)
	(via
		(at 81.4216 114.2162)
		(size 0.4064)
		(drill 0.2032)
		(layers "F.Cu" "B.Cu")
		(net "ANT2_IN")
	)
	(via
		(at 150.1216 105.6162)
		(size 0.4064)
		(drill 0.2032)
		(layers "F.Cu" "B.Cu")
		(tenting
			(front yes)
			(back yes)
		)
		(net "ANT2_IN")
	)
	(segment
		(start 80.61039 113.44505)
		(end 80.86333 113.698)
		(width 0.2032)
		(layer "In3.Cu")
		(net "ANT2_IN")
	)
	(segment
		(start 74.1898 101.96703)
		(end 74.44063 101.7162)
		(width 0.2032)
		(layer "In3.Cu")
		(net "ANT2_IN")
	)
	(segment
		(start 136.1216 102.8162)
		(end 139.3216 102.8162)
		(width 0.2032)
		(layer "In3.Cu")
		(net "ANT2_IN")
	)
	(segment
		(start 74.474 102.81656)
		(end 77.73378 102.81656)
		(width 0.2032)
		(layer "In3.Cu")
		(net "ANT2_IN")
	)
	(segment
		(start 139.3216 102.8162)
		(end 140.88087 101.25693)
		(width 0.2032)
		(layer "In3.Cu")
		(net "ANT2_IN")
	)
	(segment
		(start 80.32785 101.60995)
		(end 80.7216 101.2162)
		(width 0.2032)
		(layer "In3.Cu")
		(net "ANT2_IN")
	)
	(segment
		(start 143.4148 102.2094)
		(end 145.0148 102.2094)
		(width 0.2032)
		(layer "In3.Cu")
		(net "ANT2_IN")
	)
	(segment
		(start 75.32785 101.60995)
		(end 80.32785 101.60995)
		(width 0.2032)
		(layer "In3.Cu")
		(net "ANT2_IN")
	)
	(segment
		(start 142.46233 101.25693)
		(end 143.4148 102.2094)
		(width 0.2032)
		(layer "In3.Cu")
		(net "ANT2_IN")
	)
	(segment
		(start 77.73378 102.81656)
		(end 79.6216 104.70438)
		(width 0.2032)
		(layer "In3.Cu")
		(net "ANT2_IN")
	)
	(segment
		(start 134.5216 101.2162)
		(end 136.1216 102.8162)
		(width 0.2032)
		(layer "In3.Cu")
		(net "ANT2_IN")
	)
	(segment
		(start 74.1898 102.53236)
		(end 74.1898 101.96703)
		(width 0.2032)
		(layer "In3.Cu")
		(net "ANT2_IN")
	)
	(segment
		(start 75.2216 101.7162)
		(end 75.32785 101.60995)
		(width 0.2032)
		(layer "In3.Cu")
		(net "ANT2_IN")
	)
	(segment
		(start 148.4216 105.6162)
		(end 150.1216 105.6162)
		(width 0.2032)
		(layer "In3.Cu")
		(net "ANT2_IN")
	)
	(segment
		(start 74.44063 101.7162)
		(end 75.2216 101.7162)
		(width 0.2032)
		(layer "In3.Cu")
		(net "ANT2_IN")
	)
	(segment
		(start 140.88087 101.25693)
		(end 142.46233 101.25693)
		(width 0.2032)
		(layer "In3.Cu")
		(net "ANT2_IN")
	)
	(segment
		(start 80.86333 113.698)
		(end 80.9034 113.698)
		(width 0.2032)
		(layer "In3.Cu")
		(net "ANT2_IN")
	)
	(segment
		(start 145.0148 102.2094)
		(end 148.4216 105.6162)
		(width 0.2032)
		(layer "In3.Cu")
		(net "ANT2_IN")
	)
	(segment
		(start 80.61039 113.44505)
		(end 80.61039 113.40499)
		(width 0.2032)
		(layer "In3.Cu")
		(net "ANT2_IN")
	)
	(segment
		(start 80.7216 101.2162)
		(end 134.5216 101.2162)
		(width 0.2032)
		(layer "In3.Cu")
		(net "ANT2_IN")
	)
	(segment
		(start 80.9034 113.698)
		(end 81.4216 114.2162)
		(width 0.2032)
		(layer "In3.Cu")
		(net "ANT2_IN")
	)
	(segment
		(start 79.6216 112.4162)
		(end 80.61039 113.40499)
		(width 0.2032)
		(layer "In3.Cu")
		(net "ANT2_IN")
	)
	(segment
		(start 74.1898 102.53236)
		(end 74.474 102.81656)
		(width 0.2032)
		(layer "In3.Cu")
		(net "ANT2_IN")
	)
	(segment
		(start 79.6216 112.4162)
		(end 79.6216 104.70438)
		(width 0.2032)
		(layer "In3.Cu")
		(net "ANT2_IN")
	)
	(segment
		(start 155.04905 103.31041)
		(end 155.04905 102.3375)
		(width 0.2032)
		(layer "F.Cu")
		(net "ANT1_OUT")
	)
	(segment
		(start 154.59667 102.02447)
		(end 154.63555 102.06335)
		(width 0.2032)
		(layer "F.Cu")
		(net "ANT1_OUT")
	)
	(segment
		(start 154.63555 102.06335)
		(end 154.7749 102.06335)
		(width 0.2032)
		(layer "F.Cu")
		(net "ANT1_OUT")
	)
	(segment
		(start 154.7749 102.06335)
		(end 155.04905 102.3375)
		(width 0.2032)
		(layer "F.Cu")
		(net "ANT1_OUT")
	)
	(segment
		(start 80.5216 102.298)
		(end 80.5216 102.1662)
		(width 0.2032)
		(layer "F.Cu")
		(net "ANT1_OUT")
	)
	(segment
		(start 78.9966 102.1662)
		(end 80.5216 102.1662)
		(width 0.2032)
		(layer "F.Cu")
		(net "ANT1_OUT")
	)
	(via
		(at 154.59667 102.02447)
		(size 0.4064)
		(drill 0.2032)
		(layers "F.Cu" "B.Cu")
		(tenting
			(front yes)
			(back yes)
		)
		(net "ANT1_OUT")
	)
	(via
		(at 80.5216 102.298)
		(size 0.4064)
		(drill 0.2032)
		(layers "F.Cu" "B.Cu")
		(net "ANT1_OUT")
	)
	(segment
		(start 134.0216 101.6162)
		(end 136.32495 103.91955)
		(width 0.2032)
		(layer "In3.Cu")
		(net "ANT1_OUT")
	)
	(segment
		(start 80.5216 102.298)
		(end 81.2034 101.6162)
		(width 0.2032)
		(layer "In3.Cu")
		(net "ANT1_OUT")
	)
	(segment
		(start 81.2034 101.6162)
		(end 134.0216 101.6162)
		(width 0.2032)
		(layer "In3.Cu")
		(net "ANT1_OUT")
	)
	(segment
		(start 154.59667 105.44113)
		(end 154.59667 102.02447)
		(width 0.2032)
		(layer "In3.Cu")
		(net "ANT1_OUT")
	)
	(segment
		(start 148.56754 106.26885)
		(end 153.76895 106.26885)
		(width 0.2032)
		(layer "In3.Cu")
		(net "ANT1_OUT")
	)
	(segment
		(start 136.32495 103.91955)
		(end 146.21824 103.91955)
		(width 0.2032)
		(layer "In3.Cu")
		(net "ANT1_OUT")
	)
	(segment
		(start 146.21824 103.91955)
		(end 148.56754 106.26885)
		(width 0.2032)
		(layer "In3.Cu")
		(net "ANT1_OUT")
	)
	(segment
		(start 153.76895 106.26885)
		(end 154.59667 105.44113)
		(width 0.2032)
		(layer "In3.Cu")
		(net "ANT1_OUT")
	)
	(segment
		(start 146.6216 119.5162)
		(end 146.6216 115.3162)
		(width 0.2032)
		(layer "F.Cu")
		(net "ANT1_IO_OUT")
	)
	(segment
		(start 79.9216 103.48064)
		(end 79.9216 102.6662)
		(width 0.2032)
		(layer "F.Cu")
		(net "ANT1_IO_OUT")
	)
	(segment
		(start 143.91723 122.22057)
		(end 146.6216 119.5162)
		(width 0.2032)
		(layer "F.Cu")
		(net "ANT1_IO_OUT")
	)
	(segment
		(start 78.8466 104.0162)
		(end 79.9216 104.0162)
		(width 0.2032)
		(layer "F.Cu")
		(net "ANT1_IO_OUT")
	)
	(segment
		(start 140.46126 122.22057)
		(end 143.91723 122.22057)
		(width 0.2032)
		(layer "F.Cu")
		(net "ANT1_IO_OUT")
	)
	(segment
		(start 78.9966 102.6662)
		(end 79.9216 102.6662)
		(width 0.2032)
		(layer "F.Cu")
		(net "ANT1_IO_OUT")
	)
	(segment
		(start 79.9216 104.0162)
		(end 79.9216 103.48064)
		(width 0.2032)
		(layer "F.Cu")
		(net "ANT1_IO_OUT")
	)
	(via
		(at 79.9216 103.48064)
		(size 0.4064)
		(drill 0.2032)
		(layers "F.Cu" "B.Cu")
		(net "ANT1_IO_OUT")
	)
	(via
		(at 146.6216 115.3162)
		(size 0.4064)
		(drill 0.2032)
		(layers "F.Cu" "B.Cu")
		(tenting
			(front yes)
			(back yes)
		)
		(net "ANT1_IO_OUT")
	)
	(segment
		(start 79.9216 103.48064)
		(end 130.78604 103.48064)
		(width 0.2032)
		(layer "In3.Cu")
		(net "ANT1_IO_OUT")
	)
	(segment
		(start 144.10727 115.39459)
		(end 144.10727 109.10187)
		(width 0.2032)
		(layer "In3.Cu")
		(net "ANT1_IO_OUT")
	)
	(segment
		(start 144.10727 115.39459)
		(end 144.83112 116.11844)
		(width 0.2032)
		(layer "In3.Cu")
		(net "ANT1_IO_OUT")
	)
	(segment
		(start 130.78604 103.48064)
		(end 135.94757 108.64217)
		(width 0.2032)
		(layer "In3.Cu")
		(net "ANT1_IO_OUT")
	)
	(segment
		(start 144.83112 116.11844)
		(end 145.81936 116.11844)
		(width 0.2032)
		(layer "In3.Cu")
		(net "ANT1_IO_OUT")
	)
	(segment
		(start 145.81936 116.11844)
		(end 146.6216 115.3162)
		(width 0.2032)
		(layer "In3.Cu")
		(net "ANT1_IO_OUT")
	)
	(segment
		(start 143.64757 108.64217)
		(end 144.10727 109.10187)
		(width 0.2032)
		(layer "In3.Cu")
		(net "ANT1_IO_OUT")
	)
	(segment
		(start 135.94757 108.64217)
		(end 143.64757 108.64217)
		(width 0.2032)
		(layer "In3.Cu")
		(net "ANT1_IO_OUT")
	)
	(segment
		(start 145.7216 119.09577)
		(end 145.7216 115.7162)
		(width 0.2032)
		(layer "F.Cu")
		(net "ANT1_IO_IN")
	)
	(segment
		(start 145.4216 115.4162)
		(end 145.7216 115.7162)
		(width 0.2032)
		(layer "F.Cu")
		(net "ANT1_IO_IN")
	)
	(segment
		(start 143.09667 121.7207)
		(end 145.7216 119.09577)
		(width 0.2032)
		(layer "F.Cu")
		(net "ANT1_IO_IN")
	)
	(segment
		(start 74.6216 102.1662)
		(end 75.8466 102.1662)
		(width 0.2032)
		(layer "F.Cu")
		(net "ANT1_IO_IN")
	)
	(segment
		(start 74.6216 102.298)
		(end 74.6216 102.1662)
		(width 0.2032)
		(layer "F.Cu")
		(net "ANT1_IO_IN")
	)
	(segment
		(start 140.46126 121.7207)
		(end 143.09667 121.7207)
		(width 0.2032)
		(layer "F.Cu")
		(net "ANT1_IO_IN")
	)
	(via
		(at 145.4216 115.4162)
		(size 0.4064)
		(drill 0.2032)
		(layers "F.Cu" "B.Cu")
		(tenting
			(front yes)
			(back yes)
		)
		(net "ANT1_IO_IN")
	)
	(via
		(at 74.6216 102.298)
		(size 0.4064)
		(drill 0.2032)
		(layers "F.Cu" "B.Cu")
		(net "ANT1_IO_IN")
	)
	(segment
		(start 74.3216 103.2912)
		(end 74.3216 102.298)
		(width 0.2032)
		(layer "B.Cu")
		(net "ANT1_IO_IN")
	)
	(segment
		(start 74.3216 102.298)
		(end 74.6216 102.298)
		(width 0.2032)
		(layer "B.Cu")
		(net "ANT1_IO_IN")
	)
	(segment
		(start 79.84876 102.8071)
		(end 131.26026 102.8071)
		(width 0.2032)
		(layer "In3.Cu")
		(net "ANT1_IO_IN")
	)
	(segment
		(start 74.6216 102.298)
		(end 79.33965 102.298)
		(width 0.2032)
		(layer "In3.Cu")
		(net "ANT1_IO_IN")
	)
	(segment
		(start 131.26026 102.8071)
		(end 136.16936 107.7162)
		(width 0.2032)
		(layer "In3.Cu")
		(net "ANT1_IO_IN")
	)
	(segment
		(start 145.0216 107.7162)
		(end 145.4216 108.1162)
		(width 0.2032)
		(layer "In3.Cu")
		(net "ANT1_IO_IN")
	)
	(segment
		(start 79.33965 102.298)
		(end 79.84876 102.8071)
		(width 0.2032)
		(layer "In3.Cu")
		(net "ANT1_IO_IN")
	)
	(segment
		(start 136.16936 107.7162)
		(end 145.0216 107.7162)
		(width 0.2032)
		(layer "In3.Cu")
		(net "ANT1_IO_IN")
	)
	(segment
		(start 145.4216 115.4162)
		(end 145.4216 108.1162)
		(width 0.2032)
		(layer "In3.Cu")
		(net "ANT1_IO_IN")
	)
	(segment
		(start 78.9966 101.6662)
		(end 81.2216 101.6662)
		(width 0.2032)
		(layer "F.Cu")
		(net "ANT1_IN")
	)
	(segment
		(start 156.54892 104.63709)
		(end 156.54892 103.31041)
		(width 0.2032)
		(layer "F.Cu")
		(net "ANT1_IN")
	)
	(segment
		(start 156.25152 104.96788)
		(end 156.25152 104.93449)
		(width 0.2032)
		(layer "F.Cu")
		(net "ANT1_IN")
	)
	(segment
		(start 81.2216 102.298)
		(end 81.2216 101.6662)
		(width 0.2032)
		(layer "F.Cu")
		(net "ANT1_IN")
	)
	(segment
		(start 156.25152 104.93449)
		(end 156.54892 104.63709)
		(width 0.2032)
		(layer "F.Cu")
		(net "ANT1_IN")
	)
	(via
		(at 81.2216 102.298)
		(size 0.4064)
		(drill 0.2032)
		(layers "F.Cu" "B.Cu")
		(net "ANT1_IN")
	)
	(via
		(at 156.25152 104.96788)
		(size 0.4064)
		(drill 0.2032)
		(layers "F.Cu" "B.Cu")
		(tenting
			(front yes)
			(back yes)
		)
		(net "ANT1_IN")
	)
	(segment
		(start 81.2216 102.298)
		(end 132.1034 102.298)
		(width 0.2032)
		(layer "In3.Cu")
		(net "ANT1_IN")
	)
	(segment
		(start 154.3032 106.9162)
		(end 156.25152 104.96788)
		(width 0.2032)
		(layer "In3.Cu")
		(net "ANT1_IN")
	)
	(segment
		(start 132.1034 102.298)
		(end 136.7216 106.9162)
		(width 0.2032)
		(layer "In3.Cu")
		(net "ANT1_IN")
	)
	(segment
		(start 136.7216 106.9162)
		(end 154.3032 106.9162)
		(width 0.2032)
		(layer "In3.Cu")
		(net "ANT1_IN")
	)
	(segment
		(start 168.73392 105.08816)
		(end 169.04902 105.08816)
		(width 0.2032)
		(layer "F.Cu")
		(net "UART1_TXD")
	)
	(segment
		(start 158.9716 128.7162)
		(end 158.9716 127.7154)
		(width 0.2032)
		(layer "F.Cu")
		(net "UART1_TXD")
	)
	(segment
		(start 158.7716 127.5154)
		(end 158.9716 127.7154)
		(width 0.2032)
		(layer "F.Cu")
		(net "UART1_TXD")
	)
	(segment
		(start 158.7716 125.7662)
		(end 158.8216 125.7162)
		(width 0.2032)
		(layer "F.Cu")
		(net "UART1_TXD")
	)
	(segment
		(start 158.7716 126.5162)
		(end 158.7716 125.7662)
		(width 0.2032)
		(layer "F.Cu")
		(net "UART1_TXD")
	)
	(segment
		(start 158.7716 127.5154)
		(end 158.7716 126.5162)
		(width 0.2032)
		(layer "F.Cu")
		(net "UART1_TXD")
	)
	(segment
		(start 169.04902 105.08816)
		(end 169.04902 103.31041)
		(width 0.2032)
		(layer "F.Cu")
		(net "UART1_TXD")
	)
	(via
		(at 168.73392 105.08816)
		(size 0.4064)
		(drill 0.2032)
		(layers "F.Cu" "B.Cu")
		(net "UART1_TXD")
	)
	(via
		(at 158.8216 125.7162)
		(size 0.4064)
		(drill 0.2032)
		(layers "F.Cu" "B.Cu")
		(net "UART1_TXD")
	)
	(segment
		(start 171.8409 114.57547)
		(end 173.30016 113.1162)
		(width 0.2032)
		(layer "In2.Cu")
		(net "UART1_TXD")
	)
	(segment
		(start 164.97915 125.7162)
		(end 171.8409 118.85445)
		(width 0.2032)
		(layer "In2.Cu")
		(net "UART1_TXD")
	)
	(segment
		(start 168.73392 108.21078)
		(end 169.43933 108.9162)
		(width 0.2032)
		(layer "In2.Cu")
		(net "UART1_TXD")
	)
	(segment
		(start 173.30016 113.1162)
		(end 175.0216 113.1162)
		(width 0.2032)
		(layer "In2.Cu")
		(net "UART1_TXD")
	)
	(segment
		(start 169.43933 108.9162)
		(end 173.6216 108.9162)
		(width 0.2032)
		(layer "In2.Cu")
		(net "UART1_TXD")
	)
	(segment
		(start 168.73392 108.21078)
		(end 168.73392 105.08816)
		(width 0.2032)
		(layer "In2.Cu")
		(net "UART1_TXD")
	)
	(segment
		(start 175.0216 113.1162)
		(end 175.74035 112.39745)
		(width 0.2032)
		(layer "In2.Cu")
		(net "UART1_TXD")
	)
	(segment
		(start 173.6216 108.9162)
		(end 175.74035 111.03495)
		(width 0.2032)
		(layer "In2.Cu")
		(net "UART1_TXD")
	)
	(segment
		(start 175.74035 112.39745)
		(end 175.74035 111.03495)
		(width 0.2032)
		(layer "In2.Cu")
		(net "UART1_TXD")
	)
	(segment
		(start 158.8216 125.7162)
		(end 164.97915 125.7162)
		(width 0.2032)
		(layer "In2.Cu")
		(net "UART1_TXD")
	)
	(segment
		(start 171.8409 118.85445)
		(end 171.8409 114.57547)
		(width 0.2032)
		(layer "In2.Cu")
		(net "UART1_TXD")
	)
	(segment
		(start 172.24667 105.8162)
		(end 172.24667 105.32447)
		(width 0.2032)
		(layer "F.Cu")
		(net "UART1_RXD")
	)
	(segment
		(start 158.8716 132.1162)
		(end 158.9216 132.0662)
		(width 0.2032)
		(layer "F.Cu")
		(net "UART1_RXD")
	)
	(segment
		(start 158.9216 132.0662)
		(end 158.9216 130.3178)
		(width 0.2032)
		(layer "F.Cu")
		(net "UART1_RXD")
	)
	(segment
		(start 164.6216 128.78501)
		(end 164.6216 126.3162)
		(width 0.2032)
		(layer "F.Cu")
		(net "UART1_RXD")
	)
	(segment
		(start 170.54889 105.8162)
		(end 170.54889 103.31041)
		(width 0.2032)
		(layer "F.Cu")
		(net "UART1_RXD")
	)
	(segment
		(start 158.9216 130.3178)
		(end 158.9232 130.3162)
		(width 0.2032)
		(layer "F.Cu")
		(net "UART1_RXD")
	)
	(segment
		(start 170.54889 105.8162)
		(end 172.24667 105.8162)
		(width 0.2032)
		(layer "F.Cu")
		(net "UART1_RXD")
	)
	(segment
		(start 161.2904 132.1162)
		(end 164.6216 128.78501)
		(width 0.2032)
		(layer "F.Cu")
		(net "UART1_RXD")
	)
	(segment
		(start 158.8716 132.1162)
		(end 161.2904 132.1162)
		(width 0.2032)
		(layer "F.Cu")
		(net "UART1_RXD")
	)
	(segment
		(start 158.9232 130.3162)
		(end 158.9716 130.3162)
		(width 0.2032)
		(layer "F.Cu")
		(net "UART1_RXD")
	)
	(via
		(at 164.6216 126.3162)
		(size 0.4064)
		(drill 0.2032)
		(layers "F.Cu" "B.Cu")
		(net "UART1_RXD")
	)
	(via
		(at 172.24667 105.32447)
		(size 0.4064)
		(drill 0.2032)
		(layers "F.Cu" "B.Cu")
		(net "UART1_RXD")
	)
	(segment
		(start 174.50707 107.37788)
		(end 176.5216 109.39241)
		(width 0.2032)
		(layer "In2.Cu")
		(net "UART1_RXD")
	)
	(segment
		(start 173.7021 113.62849)
		(end 175.29028 113.62849)
		(width 0.2032)
		(layer "In2.Cu")
		(net "UART1_RXD")
	)
	(segment
		(start 175.29028 113.62849)
		(end 176.5216 112.39717)
		(width 0.2032)
		(layer "In2.Cu")
		(net "UART1_RXD")
	)
	(segment
		(start 174.30008 107.37788)
		(end 174.50707 107.37788)
		(width 0.2032)
		(layer "In2.Cu")
		(net "UART1_RXD")
	)
	(segment
		(start 172.24667 105.32447)
		(end 174.30008 107.37788)
		(width 0.2032)
		(layer "In2.Cu")
		(net "UART1_RXD")
	)
	(segment
		(start 172.28966 115.04093)
		(end 173.7021 113.62849)
		(width 0.2032)
		(layer "In2.Cu")
		(net "UART1_RXD")
	)
	(segment
		(start 164.6216 126.3162)
		(end 165.15986 126.3162)
		(width 0.2032)
		(layer "In2.Cu")
		(net "UART1_RXD")
	)
	(segment
		(start 176.5216 112.39717)
		(end 176.5216 109.39241)
		(width 0.2032)
		(layer "In2.Cu")
		(net "UART1_RXD")
	)
	(segment
		(start 165.15986 126.3162)
		(end 172.28966 119.1864)
		(width 0.2032)
		(layer "In2.Cu")
		(net "UART1_RXD")
	)
	(segment
		(start 172.28966 119.1864)
		(end 172.28966 115.04093)
		(width 0.2032)
		(layer "In2.Cu")
		(net "UART1_RXD")
	)
	(segment
		(start 77.4716 53.8662)
		(end 78.6716 53.8662)
		(width 0.2032)
		(layer "F.Cu")
		(net "NetD10_1")
	)
	(segment
		(start 77.2216 54.1162)
		(end 77.4716 53.8662)
		(width 0.2032)
		(layer "F.Cu")
		(net "NetD10_1")
	)
	(via
		(at 77.2216 54.1162)
		(size 0.4064)
		(drill 0.2032)
		(layers "F.Cu" "B.Cu")
		(net "NetD10_1")
	)
	(segment
		(start 78.4482 54.1162)
		(end 78.7466 54.4146)
		(width 0.2032)
		(layer "B.Cu")
		(net "NetD10_1")
	)
	(segment
		(start 77.2216 54.1162)
		(end 78.4482 54.1162)
		(width 0.2032)
		(layer "B.Cu")
		(net "NetD10_1")
	)
	(segment
		(start 78.7466 54.4662)
		(end 78.7466 54.4146)
		(width 0.2032)
		(layer "B.Cu")
		(net "NetD10_1")
	)
	(segment
		(start 77.5216 52.1162)
		(end 78.6716 52.1162)
		(width 0.2032)
		(layer "F.Cu")
		(net "NetD9_1")
	)
	(segment
		(start 77.2216 52.4162)
		(end 77.5216 52.1162)
		(width 0.2032)
		(layer "F.Cu")
		(net "NetD9_1")
	)
	(via
		(at 77.2216 52.4162)
		(size 0.4064)
		(drill 0.2032)
		(layers "F.Cu" "B.Cu")
		(net "NetD9_1")
	)
	(segment
		(start 77.2216 52.4162)
		(end 78.4482 52.4162)
		(width 0.2032)
		(layer "B.Cu")
		(net "NetD9_1")
	)
	(segment
		(start 78.7466 52.7162)
		(end 78.7466 52.7146)
		(width 0.2032)
		(layer "B.Cu")
		(net "NetD9_1")
	)
	(segment
		(start 78.4482 52.4162)
		(end 78.7466 52.7146)
		(width 0.2032)
		(layer "B.Cu")
		(net "NetD9_1")
	)
	(segment
		(start 191.7982 128.6896)
		(end 192.0982 128.6896)
		(width 0.2032)
		(layer "F.Cu")
		(net "GPS2_TX")
	)
	(segment
		(start 192.0982 128.6896)
		(end 192.2216 128.5662)
		(width 0.2032)
		(layer "F.Cu")
		(net "GPS2_TX")
	)
	(segment
		(start 189.5898 125.63555)
		(end 189.6878 125.63555)
		(width 0.2032)
		(layer "F.Cu")
		(net "GPS2_TX")
	)
	(segment
		(start 193.0466 128.5412)
		(end 193.2216 128.3662)
		(width 0.2032)
		(layer "F.Cu")
		(net "GPS2_TX")
	)
	(segment
		(start 153.8716 127.8654)
		(end 154.1716 128.1654)
		(width 0.2032)
		(layer "F.Cu")
		(net "GPS2_TX")
	)
	(segment
		(start 153.8716 127.8654)
		(end 153.8716 127.1162)
		(width 0.2032)
		(layer "F.Cu")
		(net "GPS2_TX")
	)
	(segment
		(start 190.5216 129.9662)
		(end 191.7982 128.6896)
		(width 0.2032)
		(layer "F.Cu")
		(net "GPS2_TX")
	)
	(segment
		(start 192.2216 128.5412)
		(end 193.0466 128.5412)
		(width 0.2032)
		(layer "F.Cu")
		(net "GPS2_TX")
	)
	(segment
		(start 154.1716 128.9162)
		(end 154.1716 128.1654)
		(width 0.2032)
		(layer "F.Cu")
		(net "GPS2_TX")
	)
	(segment
		(start 192.2216 128.5662)
		(end 192.2216 128.5412)
		(width 0.2032)
		(layer "F.Cu")
		(net "GPS2_TX")
	)
	(via
		(at 190.5216 129.9662)
		(size 0.4064)
		(drill 0.2032)
		(layers "F.Cu" "B.Cu")
		(net "GPS2_TX")
	)
	(via
		(at 153.8716 127.1162)
		(size 0.4064)
		(drill 0.2032)
		(layers "F.Cu" "B.Cu")
		(net "GPS2_TX")
	)
	(via
		(at 189.5898 125.63555)
		(size 0.4064)
		(drill 0.2032)
		(layers "F.Cu" "B.Cu")
		(net "GPS2_TX")
	)
	(segment
		(start 156.1216 126.28478)
		(end 156.1216 121.2162)
		(width 0.2032)
		(layer "B.Cu")
		(net "GPS2_TX")
	)
	(segment
		(start 158.3216 122.0162)
		(end 158.9216 121.4162)
		(width 0.2032)
		(layer "B.Cu")
		(net "GPS2_TX")
	)
	(segment
		(start 156.1216 121.2162)
		(end 157.2216 120.1162)
		(width 0.2032)
		(layer "B.Cu")
		(net "GPS2_TX")
	)
	(segment
		(start 180.45353 129.84813)
		(end 185.30902 129.84813)
		(width 0.2032)
		(layer "B.Cu")
		(net "GPS2_TX")
	)
	(segment
		(start 185.30902 129.84813)
		(end 189.5216 125.63555)
		(width 0.2032)
		(layer "B.Cu")
		(net "GPS2_TX")
	)
	(segment
		(start 177.7216 127.1162)
		(end 180.45353 129.84813)
		(width 0.2032)
		(layer "B.Cu")
		(net "GPS2_TX")
	)
	(segment
		(start 158.9216 121.4162)
		(end 158.9216 120.7162)
		(width 0.2032)
		(layer "B.Cu")
		(net "GPS2_TX")
	)
	(segment
		(start 158.3216 126.608)
		(end 158.3216 122.0162)
		(width 0.2032)
		(layer "B.Cu")
		(net "GPS2_TX")
	)
	(segment
		(start 189.5898 129.0344)
		(end 190.5216 129.9662)
		(width 0.2032)
		(layer "B.Cu")
		(net "GPS2_TX")
	)
	(segment
		(start 155.29018 127.1162)
		(end 156.1216 126.28478)
		(width 0.2032)
		(layer "B.Cu")
		(net "GPS2_TX")
	)
	(segment
		(start 158.8298 127.1162)
		(end 177.7216 127.1162)
		(width 0.2032)
		(layer "B.Cu")
		(net "GPS2_TX")
	)
	(segment
		(start 189.5216 125.63555)
		(end 189.5898 125.63555)
		(width 0.2032)
		(layer "B.Cu")
		(net "GPS2_TX")
	)
	(segment
		(start 157.2216 120.1162)
		(end 158.3216 120.1162)
		(width 0.2032)
		(layer "B.Cu")
		(net "GPS2_TX")
	)
	(segment
		(start 189.5898 129.0344)
		(end 189.5898 125.63555)
		(width 0.2032)
		(layer "B.Cu")
		(net "GPS2_TX")
	)
	(segment
		(start 153.8716 127.1162)
		(end 155.29018 127.1162)
		(width 0.2032)
		(layer "B.Cu")
		(net "GPS2_TX")
	)
	(segment
		(start 158.3216 126.608)
		(end 158.8298 127.1162)
		(width 0.2032)
		(layer "B.Cu")
		(net "GPS2_TX")
	)
	(segment
		(start 158.3216 120.1162)
		(end 158.9216 120.7162)
		(width 0.2032)
		(layer "B.Cu")
		(net "GPS2_TX")
	)
	(segment
		(start 196.2216 129.3412)
		(end 196.6466 129.3412)
		(width 0.2032)
		(layer "F.Cu")
		(net "GPS2_TP2")
	)
	(segment
		(start 196.8216 130.9662)
		(end 198.0716 132.2162)
		(width 0.2032)
		(layer "F.Cu")
		(net "GPS2_TP2")
	)
	(segment
		(start 195.8482 129.1928)
		(end 196.0982 129.1928)
		(width 0.2032)
		(layer "F.Cu")
		(net "GPS2_TP2")
	)
	(segment
		(start 196.0982 129.1928)
		(end 196.2216 129.3162)
		(width 0.2032)
		(layer "F.Cu")
		(net "GPS2_TP2")
	)
	(segment
		(start 196.2216 129.3412)
		(end 196.2216 129.3162)
		(width 0.2032)
		(layer "F.Cu")
		(net "GPS2_TP2")
	)
	(segment
		(start 196.8216 130.9662)
		(end 196.8216 129.5162)
		(width 0.2032)
		(layer "F.Cu")
		(net "GPS2_TP2")
	)
	(segment
		(start 196.6466 129.3412)
		(end 196.8216 129.5162)
		(width 0.2032)
		(layer "F.Cu")
		(net "GPS2_TP2")
	)
	(segment
		(start 140.46126 128.22056)
		(end 143.34668 128.22056)
		(width 0.2032)
		(layer "F.Cu")
		(net "GPS2_TP2")
	)
	(segment
		(start 194.9216 128.2662)
		(end 195.8482 129.1928)
		(width 0.2032)
		(layer "F.Cu")
		(net "GPS2_TP2")
	)
	(segment
		(start 143.34668 128.22056)
		(end 143.34668 128.13566)
		(width 0.2032)
		(layer "F.Cu")
		(net "GPS2_TP2")
	)
	(via
		(at 143.34668 128.13566)
		(size 0.4064)
		(drill 0.2032)
		(layers "F.Cu" "B.Cu")
		(tenting
			(front yes)
			(back yes)
		)
		(net "GPS2_TP2")
	)
	(via
		(at 198.0716 132.2162)
		(size 0.4064)
		(drill 0.2032)
		(layers "F.Cu" "B.Cu")
		(net "GPS2_TP2")
	)
	(segment
		(start 162.48163 128.97623)
		(end 163.17735 129.67195)
		(width 0.2032)
		(layer "In3.Cu")
		(net "GPS2_TP2")
	)
	(segment
		(start 189.24836 130.74296)
		(end 190.07226 131.56686)
		(width 0.2032)
		(layer "In3.Cu")
		(net "GPS2_TP2")
	)
	(segment
		(start 197.42226 131.56686)
		(end 198.0716 132.2162)
		(width 0.2032)
		(layer "In3.Cu")
		(net "GPS2_TP2")
	)
	(segment
		(start 198.0716 132.2162)
		(end 198.0716 132.2162)
		(width 0.2032)
		(layer "In3.Cu")
		(net "GPS2_TP2")
	)
	(segment
		(start 148.91342 127.73731)
		(end 156.72951 127.73731)
		(width 0.2032)
		(layer "In3.Cu")
		(net "GPS2_TP2")
	)
	(segment
		(start 177.77735 129.67195)
		(end 178.84836 130.74296)
		(width 0.2032)
		(layer "In3.Cu")
		(net "GPS2_TP2")
	)
	(segment
		(start 157.96844 128.97623)
		(end 162.48163 128.97623)
		(width 0.2032)
		(layer "In3.Cu")
		(net "GPS2_TP2")
	)
	(segment
		(start 143.34668 128.13566)
		(end 148.51506 128.13566)
		(width 0.2032)
		(layer "In3.Cu")
		(net "GPS2_TP2")
	)
	(segment
		(start 178.84836 130.74296)
		(end 189.24836 130.74296)
		(width 0.2032)
		(layer "In3.Cu")
		(net "GPS2_TP2")
	)
	(segment
		(start 148.51506 128.13566)
		(end 148.91342 127.73731)
		(width 0.2032)
		(layer "In3.Cu")
		(net "GPS2_TP2")
	)
	(segment
		(start 190.07226 131.56686)
		(end 197.42226 131.56686)
		(width 0.2032)
		(layer "In3.Cu")
		(net "GPS2_TP2")
	)
	(segment
		(start 156.72951 127.73731)
		(end 157.96844 128.97623)
		(width 0.2032)
		(layer "In3.Cu")
		(net "GPS2_TP2")
	)
	(segment
		(start 163.17735 129.67195)
		(end 177.77735 129.67195)
		(width 0.2032)
		(layer "In3.Cu")
		(net "GPS2_TP2")
	)
	(segment
		(start 197.2716 134.9162)
		(end 197.2966 134.9162)
		(width 0.2032)
		(layer "F.Cu")
		(net "GPS2_TP1")
	)
	(segment
		(start 197.3341 133.9537)
		(end 197.3716 133.9162)
		(width 0.2032)
		(layer "F.Cu")
		(net "GPS2_TP1")
	)
	(segment
		(start 140.46126 128.72068)
		(end 143.92608 128.72068)
		(width 0.2032)
		(layer "F.Cu")
		(net "GPS2_TP1")
	)
	(segment
		(start 197.1482 135.11289)
		(end 197.1482 135.0396)
		(width 0.2032)
		(layer "F.Cu")
		(net "GPS2_TP1")
	)
	(segment
		(start 197.3341 134.8787)
		(end 197.3341 133.9537)
		(width 0.2032)
		(layer "F.Cu")
		(net "GPS2_TP1")
	)
	(segment
		(start 143.92608 128.72068)
		(end 144.4216 129.2162)
		(width 0.2032)
		(layer "F.Cu")
		(net "GPS2_TP1")
	)
	(segment
		(start 196.1716 135.8162)
		(end 196.60823 135.37957)
		(width 0.2032)
		(layer "F.Cu")
		(net "GPS2_TP1")
	)
	(segment
		(start 196.88151 135.37957)
		(end 197.1482 135.11289)
		(width 0.2032)
		(layer "F.Cu")
		(net "GPS2_TP1")
	)
	(segment
		(start 197.1482 135.0396)
		(end 197.2716 134.9162)
		(width 0.2032)
		(layer "F.Cu")
		(net "GPS2_TP1")
	)
	(segment
		(start 197.2966 134.9162)
		(end 197.3341 134.8787)
		(width 0.2032)
		(layer "F.Cu")
		(net "GPS2_TP1")
	)
	(segment
		(start 196.60823 135.37957)
		(end 196.88151 135.37957)
		(width 0.2032)
		(layer "F.Cu")
		(net "GPS2_TP1")
	)
	(via
		(at 197.3716 133.9162)
		(size 0.4064)
		(drill 0.2032)
		(layers "F.Cu" "B.Cu")
		(net "GPS2_TP1")
	)
	(via
		(at 144.4216 129.2162)
		(size 0.4064)
		(drill 0.2032)
		(layers "F.Cu" "B.Cu")
		(tenting
			(front yes)
			(back yes)
		)
		(net "GPS2_TP1")
	)
	(segment
		(start 189.06507 133.47051)
		(end 196.92591 133.47051)
		(width 0.2032)
		(layer "In3.Cu")
		(net "GPS2_TP1")
	)
	(segment
		(start 145.08519 129.87979)
		(end 149.70939 129.87979)
		(width 0.2032)
		(layer "In3.Cu")
		(net "GPS2_TP1")
	)
	(segment
		(start 149.70939 129.87979)
		(end 150.3458 130.5162)
		(width 0.2032)
		(layer "In3.Cu")
		(net "GPS2_TP1")
	)
	(segment
		(start 144.4216 129.2162)
		(end 145.08519 129.87979)
		(width 0.2032)
		(layer "In3.Cu")
		(net "GPS2_TP1")
	)
	(segment
		(start 161.53413 130.5162)
		(end 162.73413 131.7162)
		(width 0.2032)
		(layer "In3.Cu")
		(net "GPS2_TP1")
	)
	(segment
		(start 187.31077 131.7162)
		(end 189.06507 133.47051)
		(width 0.2032)
		(layer "In3.Cu")
		(net "GPS2_TP1")
	)
	(segment
		(start 162.73413 131.7162)
		(end 187.31077 131.7162)
		(width 0.2032)
		(layer "In3.Cu")
		(net "GPS2_TP1")
	)
	(segment
		(start 150.3458 130.5162)
		(end 161.53413 130.5162)
		(width 0.2032)
		(layer "In3.Cu")
		(net "GPS2_TP1")
	)
	(segment
		(start 196.92591 133.47051)
		(end 197.3716 133.9162)
		(width 0.2032)
		(layer "In3.Cu")
		(net "GPS2_TP1")
	)
	(segment
		(start 154.6216 131.7162)
		(end 154.6216 130.9662)
		(width 0.2032)
		(layer "F.Cu")
		(net "GPS2_RX")
	)
	(segment
		(start 154.40945 131.87337)
		(end 154.46443 131.87337)
		(width 0.2032)
		(layer "F.Cu")
		(net "GPS2_RX")
	)
	(segment
		(start 154.1716 130.5162)
		(end 154.3684 130.5162)
		(width 0.2032)
		(layer "F.Cu")
		(net "GPS2_RX")
	)
	(segment
		(start 191.1482 135.0428)
		(end 191.3982 135.0428)
		(width 0.2032)
		(layer "F.Cu")
		(net "GPS2_RX")
	)
	(segment
		(start 154.37 130.7146)
		(end 154.6216 130.9662)
		(width 0.2032)
		(layer "F.Cu")
		(net "GPS2_RX")
	)
	(segment
		(start 154.46443 131.87337)
		(end 154.6216 131.7162)
		(width 0.2032)
		(layer "F.Cu")
		(net "GPS2_RX")
	)
	(segment
		(start 189.3591 134.3287)
		(end 190.3841 134.3287)
		(width 0.2032)
		(layer "F.Cu")
		(net "GPS2_RX")
	)
	(segment
		(start 154.24002 132.0428)
		(end 154.40945 131.87337)
		(width 0.2032)
		(layer "F.Cu")
		(net "GPS2_RX")
	)
	(segment
		(start 153.945 132.0428)
		(end 154.24002 132.0428)
		(width 0.2032)
		(layer "F.Cu")
		(net "GPS2_RX")
	)
	(segment
		(start 153.7716 132.2162)
		(end 153.945 132.0428)
		(width 0.2032)
		(layer "F.Cu")
		(net "GPS2_RX")
	)
	(segment
		(start 191.3982 135.0428)
		(end 191.5716 135.2162)
		(width 0.2032)
		(layer "F.Cu")
		(net "GPS2_RX")
	)
	(segment
		(start 154.37 130.7146)
		(end 154.37 130.5178)
		(width 0.2032)
		(layer "F.Cu")
		(net "GPS2_RX")
	)
	(segment
		(start 190.4216 134.3162)
		(end 191.1482 135.0428)
		(width 0.2032)
		(layer "F.Cu")
		(net "GPS2_RX")
	)
	(segment
		(start 189.3216 134.38922)
		(end 189.3216 134.3662)
		(width 0.2032)
		(layer "F.Cu")
		(net "GPS2_RX")
	)
	(segment
		(start 189.3216 134.3662)
		(end 189.3591 134.3287)
		(width 0.2032)
		(layer "F.Cu")
		(net "GPS2_RX")
	)
	(segment
		(start 190.3841 134.3287)
		(end 190.4216 134.2912)
		(width 0.2032)
		(layer "F.Cu")
		(net "GPS2_RX")
	)
	(segment
		(start 190.4216 134.3162)
		(end 190.4216 134.2912)
		(width 0.2032)
		(layer "F.Cu")
		(net "GPS2_RX")
	)
	(segment
		(start 154.3684 130.5162)
		(end 154.37 130.5178)
		(width 0.2032)
		(layer "F.Cu")
		(net "GPS2_RX")
	)
	(via
		(at 189.3216 134.38922)
		(size 0.4064)
		(drill 0.2032)
		(layers "F.Cu" "B.Cu")
		(net "GPS2_RX")
	)
	(via
		(at 154.46443 131.87337)
		(size 0.4064)
		(drill 0.2032)
		(layers "F.Cu" "B.Cu")
		(net "GPS2_RX")
	)
	(segment
		(start 154.46443 131.87337)
		(end 156.50727 133.9162)
		(width 0.2032)
		(layer "B.Cu")
		(net "GPS2_RX")
	)
	(segment
		(start 156.50727 133.9162)
		(end 185.06957 133.9162)
		(width 0.2032)
		(layer "B.Cu")
		(net "GPS2_RX")
	)
	(segment
		(start 185.06957 133.9162)
		(end 185.54259 134.38922)
		(width 0.2032)
		(layer "B.Cu")
		(net "GPS2_RX")
	)
	(segment
		(start 185.54259 134.38922)
		(end 189.3216 134.38922)
		(width 0.2032)
		(layer "B.Cu")
		(net "GPS2_RX")
	)
	(segment
		(start 140.46126 127.22056)
		(end 143.34668 127.22056)
		(width 0.2032)
		(layer "F.Cu")
		(net "GPS2_RST")
	)
	(segment
		(start 143.34668 127.22056)
		(end 143.34668 127.11966)
		(width 0.2032)
		(layer "F.Cu")
		(net "GPS2_RST")
	)
	(segment
		(start 212.5216 134.2162)
		(end 212.5592 134.2162)
		(width 0.2032)
		(layer "F.Cu")
		(net "GPS2_RST")
	)
	(segment
		(start 200.9716 130.8412)
		(end 201.0216 130.8412)
		(width 0.2032)
		(layer "F.Cu")
		(net "GPS2_RST")
	)
	(segment
		(start 212.5216 134.2162)
		(end 212.5216 132.6162)
		(width 0.2032)
		(layer "F.Cu")
		(net "GPS2_RST")
	)
	(segment
		(start 200.9716 130.8412)
		(end 200.9716 129.3162)
		(width 0.2032)
		(layer "F.Cu")
		(net "GPS2_RST")
	)
	(segment
		(start 203.7216 119.9412)
		(end 205.2216 119.9412)
		(width 0.2032)
		(layer "F.Cu")
		(net "GPS2_RST")
	)
	(segment
		(start 205.2216 121.7662)
		(end 205.2216 119.9412)
		(width 0.2032)
		(layer "F.Cu")
		(net "GPS2_RST")
	)
	(via
		(at 201.0216 130.8412)
		(size 0.4064)
		(drill 0.2032)
		(layers "F.Cu" "B.Cu")
		(net "GPS2_RST")
	)
	(via
		(at 212.5216 132.6162)
		(size 0.4064)
		(drill 0.2032)
		(layers "F.Cu" "B.Cu")
		(net "GPS2_RST")
	)
	(via
		(at 143.34668 127.11966)
		(size 0.4064)
		(drill 0.2032)
		(layers "F.Cu" "B.Cu")
		(tenting
			(front yes)
			(back yes)
		)
		(net "GPS2_RST")
	)
	(via
		(at 203.7216 119.9412)
		(size 0.4064)
		(drill 0.2032)
		(layers "F.Cu" "B.Cu")
		(net "GPS2_RST")
	)
	(segment
		(start 198.5216 140.79717)
		(end 198.5216 135.54005)
		(width 0.2032)
		(layer "In3.Cu")
		(net "GPS2_RST")
	)
	(segment
		(start 185.1898 129.348)
		(end 188.71302 129.348)
		(width 0.2032)
		(layer "In3.Cu")
		(net "GPS2_RST")
	)
	(segment
		(start 203.7216 125.9162)
		(end 203.7216 119.9412)
		(width 0.2032)
		(layer "In3.Cu")
		(net "GPS2_RST")
	)
	(segment
		(start 201.0216 130.8412)
		(end 201.0216 129.7287)
		(width 0.2032)
		(layer "In3.Cu")
		(net "GPS2_RST")
	)
	(segment
		(start 209.3077 135.8301)
		(end 212.5216 132.6162)
		(width 0.2032)
		(layer "In3.Cu")
		(net "GPS2_RST")
	)
	(segment
		(start 180.3216 130.1162)
		(end 184.4216 130.1162)
		(width 0.2032)
		(layer "In3.Cu")
		(net "GPS2_RST")
	)
	(segment
		(start 191.50936 130.49937)
		(end 197.06342 130.49937)
		(width 0.2032)
		(layer "In3.Cu")
		(net "GPS2_RST")
	)
	(segment
		(start 198.5216 140.79717)
		(end 198.74063 141.0162)
		(width 0.2032)
		(layer "In3.Cu")
		(net "GPS2_RST")
	)
	(segment
		(start 188.71302 129.348)
		(end 189.76302 130.398)
		(width 0.2032)
		(layer "In3.Cu")
		(net "GPS2_RST")
	)
	(segment
		(start 197.8341 129.7287)
		(end 201.0216 129.7287)
		(width 0.2032)
		(layer "In3.Cu")
		(net "GPS2_RST")
	)
	(segment
		(start 191.40798 130.398)
		(end 191.50936 130.49937)
		(width 0.2032)
		(layer "In3.Cu")
		(net "GPS2_RST")
	)
	(segment
		(start 201.0216 128.6162)
		(end 203.7216 125.9162)
		(width 0.2032)
		(layer "In3.Cu")
		(net "GPS2_RST")
	)
	(segment
		(start 203.0216 141.0162)
		(end 208.2077 135.8301)
		(width 0.2032)
		(layer "In3.Cu")
		(net "GPS2_RST")
	)
	(segment
		(start 198.74063 141.0162)
		(end 203.0216 141.0162)
		(width 0.2032)
		(layer "In3.Cu")
		(net "GPS2_RST")
	)
	(segment
		(start 143.34668 127.11966)
		(end 150.11813 127.11966)
		(width 0.2032)
		(layer "In3.Cu")
		(net "GPS2_RST")
	)
	(segment
		(start 160.6216 127.5162)
		(end 177.7216 127.5162)
		(width 0.2032)
		(layer "In3.Cu")
		(net "GPS2_RST")
	)
	(segment
		(start 197.06342 130.49937)
		(end 197.8341 129.7287)
		(width 0.2032)
		(layer "In3.Cu")
		(net "GPS2_RST")
	)
	(segment
		(start 198.5216 135.54005)
		(end 201.0216 133.04005)
		(width 0.2032)
		(layer "In3.Cu")
		(net "GPS2_RST")
	)
	(segment
		(start 150.9216 126.3162)
		(end 159.4216 126.3162)
		(width 0.2032)
		(layer "In3.Cu")
		(net "GPS2_RST")
	)
	(segment
		(start 184.4216 130.1162)
		(end 185.1898 129.348)
		(width 0.2032)
		(layer "In3.Cu")
		(net "GPS2_RST")
	)
	(segment
		(start 208.2077 135.8301)
		(end 209.3077 135.8301)
		(width 0.2032)
		(layer "In3.Cu")
		(net "GPS2_RST")
	)
	(segment
		(start 201.0216 129.7287)
		(end 201.0216 128.6162)
		(width 0.2032)
		(layer "In3.Cu")
		(net "GPS2_RST")
	)
	(segment
		(start 150.11813 127.11966)
		(end 150.9216 126.3162)
		(width 0.2032)
		(layer "In3.Cu")
		(net "GPS2_RST")
	)
	(segment
		(start 159.4216 126.3162)
		(end 160.6216 127.5162)
		(width 0.2032)
		(layer "In3.Cu")
		(net "GPS2_RST")
	)
	(segment
		(start 201.0216 133.04005)
		(end 201.0216 130.8412)
		(width 0.2032)
		(layer "In3.Cu")
		(net "GPS2_RST")
	)
	(segment
		(start 177.7216 127.5162)
		(end 180.3216 130.1162)
		(width 0.2032)
		(layer "In3.Cu")
		(net "GPS2_RST")
	)
	(segment
		(start 189.76302 130.398)
		(end 191.40798 130.398)
		(width 0.2032)
		(layer "In3.Cu")
		(net "GPS2_RST")
	)
	(segment
		(start 74.9216 101.6662)
		(end 74.9216 101.1662)
		(width 0.2032)
		(layer "F.Cu")
		(net "NetR25_1")
	)
	(segment
		(start 74.9216 100.6162)
		(end 76.1216 100.6162)
		(width 0.2032)
		(layer "F.Cu")
		(net "NetR25_1")
	)
	(segment
		(start 74.9216 101.1662)
		(end 75.8466 101.1662)
		(width 0.2032)
		(layer "F.Cu")
		(net "NetR25_1")
	)
	(segment
		(start 76.1216 99.7162)
		(end 76.2216 99.8162)
		(width 0.2032)
		(layer "F.Cu")
		(net "NetR25_1")
	)
	(segment
		(start 76.1216 100.6162)
		(end 76.1216 99.7162)
		(width 0.2032)
		(layer "F.Cu")
		(net "NetR25_1")
	)
	(segment
		(start 74.9216 101.6662)
		(end 75.8466 101.6662)
		(width 0.2032)
		(layer "F.Cu")
		(net "NetR25_1")
	)
	(segment
		(start 74.9216 101.1662)
		(end 74.9216 100.6162)
		(width 0.2032)
		(layer "F.Cu")
		(net "NetR25_1")
	)
	(segment
		(start 229.5216 114.9162)
		(end 229.5216 113.4662)
		(width 0.2032)
		(layer "F.Cu")
		(net "NetR13_1")
	)
	(segment
		(start 229.5216 113.4662)
		(end 229.8216 113.1662)
		(width 0.2032)
		(layer "F.Cu")
		(net "NetR13_1")
	)
	(segment
		(start 123.9216 115.0162)
		(end 124.13832 115.23291)
		(width 0.2032)
		(layer "F.Cu")
		(net "MAC_PPS_IN1-")
	)
	(segment
		(start 128.8166 82.4212)
		(end 128.8216 82.4162)
		(width 0.2032)
		(layer "F.Cu")
		(net "MAC_PPS_IN1-")
	)
	(segment
		(start 124.13832 115.23291)
		(end 125.25657 115.23291)
		(width 0.2032)
		(layer "F.Cu")
		(net "MAC_PPS_IN1-")
	)
	(segment
		(start 128.8166 83.9162)
		(end 128.8166 82.4212)
		(width 0.2032)
		(layer "F.Cu")
		(net "MAC_PPS_IN1-")
	)
	(via
		(at 128.8216 82.4162)
		(size 0.4064)
		(drill 0.2032)
		(layers "F.Cu" "B.Cu")
		(net "MAC_PPS_IN1-")
	)
	(via
		(at 123.9216 115.0162)
		(size 0.4064)
		(drill 0.2032)
		(layers "F.Cu" "B.Cu")
		(locked yes)
		(tenting
			(front yes)
			(back yes)
		)
		(net "MAC_PPS_IN1-")
	)
	(segment
		(start 128.8216 82.4162)
		(end 129.5216 83.1162)
		(width 0.2032)
		(layer "B.Cu")
		(net "MAC_PPS_IN1-")
	)
	(segment
		(start 123.5898 105.28103)
		(end 129.9914 98.87943)
		(width 0.2032)
		(layer "B.Cu")
		(net "MAC_PPS_IN1-")
	)
	(segment
		(start 125.2216 88.07983)
		(end 129.5216 83.77983)
		(width 0.2032)
		(layer "B.Cu")
		(net "MAC_PPS_IN1-")
	)
	(segment
		(start 123.5898 114.62958)
		(end 123.5898 105.28103)
		(width 0.2032)
		(layer "B.Cu")
		(net "MAC_PPS_IN1-")
	)
	(segment
		(start 125.2216 91.88317)
		(end 129.9914 96.65297)
		(width 0.2032)
		(layer "B.Cu")
		(net "MAC_PPS_IN1-")
	)
	(segment
		(start 125.2216 91.88317)
		(end 125.2216 88.07983)
		(width 0.2032)
		(layer "B.Cu")
		(net "MAC_PPS_IN1-")
	)
	(segment
		(start 123.5898 114.62958)
		(end 123.9216 114.96138)
		(width 0.2032)
		(layer "B.Cu")
		(net "MAC_PPS_IN1-")
	)
	(segment
		(start 129.5216 83.77983)
		(end 129.5216 83.1162)
		(width 0.2032)
		(layer "B.Cu")
		(net "MAC_PPS_IN1-")
	)
	(segment
		(start 123.9216 115.0162)
		(end 123.9216 114.96138)
		(width 0.2032)
		(layer "B.Cu")
		(net "MAC_PPS_IN1-")
	)
	(segment
		(start 129.9914 98.87943)
		(end 129.9914 96.65297)
		(width 0.2032)
		(layer "B.Cu")
		(net "MAC_PPS_IN1-")
	)
	(segment
		(start 85.1944 96.389)
		(end 86.5944 96.389)
		(width 0.3048)
		(layer "B.Cu")
		(net "MAC_FREQ_CTRL")
	)
	(segment
		(start 86.5944 96.389)
		(end 86.9216 96.7162)
		(width 0.3048)
		(layer "B.Cu")
		(net "MAC_FREQ_CTRL")
	)
	(segment
		(start 84.0216 94.3162)
		(end 84.0216 92.9162)
		(width 0.3048)
		(layer "B.Cu")
		(net "MAC_FREQ_CTRL")
	)
	(segment
		(start 84.0216 95.2162)
		(end 85.1944 96.389)
		(width 0.3048)
		(layer "B.Cu")
		(net "MAC_FREQ_CTRL")
	)
	(segment
		(start 84.0216 95.2162)
		(end 84.0216 94.3162)
		(width 0.3048)
		(layer "B.Cu")
		(net "MAC_FREQ_CTRL")
	)
	(segment
		(start 160.46971 106.6162)
		(end 162.04903 105.03687)
		(width 0.2032)
		(layer "F.Cu")
		(net "FPGA_MAC_PPS_OUT-")
	)
	(segment
		(start 141.3966 103.9162)
		(end 141.50006 103.81273)
		(width 0.2032)
		(layer "F.Cu")
		(net "FPGA_MAC_PPS_OUT-")
	)
	(segment
		(start 141.3966 105.0162)
		(end 141.3966 103.9162)
		(width 0.2032)
		(layer "F.Cu")
		(net "FPGA_MAC_PPS_OUT-")
	)
	(segment
		(start 141.50006 103.81273)
		(end 141.50006 103.43774)
		(width 0.2032)
		(layer "F.Cu")
		(net "FPGA_MAC_PPS_OUT-")
	)
	(segment
		(start 160.4216 106.6162)
		(end 160.46971 106.6162)
		(width 0.2032)
		(layer "F.Cu")
		(net "FPGA_MAC_PPS_OUT-")
	)
	(segment
		(start 142.92 103.9162)
		(end 142.9216 103.9178)
		(width 0.2032)
		(layer "F.Cu")
		(net "FPGA_MAC_PPS_OUT-")
	)
	(segment
		(start 141.3966 103.9162)
		(end 142.92 103.9162)
		(width 0.2032)
		(layer "F.Cu")
		(net "FPGA_MAC_PPS_OUT-")
	)
	(segment
		(start 162.04903 105.03687)
		(end 162.04903 103.31041)
		(width 0.2032)
		(layer "F.Cu")
		(net "FPGA_MAC_PPS_OUT-")
	)
	(segment
		(start 142.9216 104.0662)
		(end 142.9216 103.9178)
		(width 0.2032)
		(layer "F.Cu")
		(net "FPGA_MAC_PPS_OUT-")
	)
	(segment
		(start 141.50006 103.43774)
		(end 141.9216 103.0162)
		(width 0.2032)
		(layer "F.Cu")
		(net "FPGA_MAC_PPS_OUT-")
	)
	(via
		(at 160.4216 106.6162)
		(size 0.4064)
		(drill 0.2032)
		(layers "F.Cu" "B.Cu")
		(tenting
			(front yes)
			(back yes)
		)
		(net "FPGA_MAC_PPS_OUT-")
	)
	(via
		(at 141.9216 103.0162)
		(size 0.4064)
		(drill 0.2032)
		(layers "F.Cu" "B.Cu")
		(net "FPGA_MAC_PPS_OUT-")
	)
	(segment
		(start 159.7216 107.3162)
		(end 160.4216 106.6162)
		(width 0.2032)
		(layer "In2.Cu")
		(net "FPGA_MAC_PPS_OUT-")
	)
	(segment
		(start 149.74063 107.3162)
		(end 159.7216 107.3162)
		(width 0.2032)
		(layer "In2.Cu")
		(net "FPGA_MAC_PPS_OUT-")
	)
	(segment
		(start 149.6216 107.19717)
		(end 149.74063 107.3162)
		(width 0.2032)
		(layer "In2.Cu")
		(net "FPGA_MAC_PPS_OUT-")
	)
	(segment
		(start 147.5148 102.2094)
		(end 149.6216 104.3162)
		(width 0.2032)
		(layer "In2.Cu")
		(net "FPGA_MAC_PPS_OUT-")
	)
	(segment
		(start 142.64909 103.0162)
		(end 143.45589 102.2094)
		(width 0.2032)
		(layer "In2.Cu")
		(net "FPGA_MAC_PPS_OUT-")
	)
	(segment
		(start 141.9216 103.0162)
		(end 142.64909 103.0162)
		(width 0.2032)
		(layer "In2.Cu")
		(net "FPGA_MAC_PPS_OUT-")
	)
	(segment
		(start 143.45589 102.2094)
		(end 147.5148 102.2094)
		(width 0.2032)
		(layer "In2.Cu")
		(net "FPGA_MAC_PPS_OUT-")
	)
	(segment
		(start 149.6216 107.19717)
		(end 149.6216 104.3162)
		(width 0.2032)
		(layer "In2.Cu")
		(net "FPGA_MAC_PPS_OUT-")
	)
	(segment
		(start 164.5489 105.2162)
		(end 164.5489 103.31041)
		(width 0.2032)
		(layer "F.Cu")
		(net "FPGA_MAC_PPS_IN1-")
	)
	(segment
		(start 164.2216 105.2162)
		(end 164.5489 105.2162)
		(width 0.2032)
		(layer "F.Cu")
		(net "FPGA_MAC_PPS_IN1-")
	)
	(segment
		(start 130.0866 90.3512)
		(end 130.0866 88.7162)
		(width 0.2032)
		(layer "F.Cu")
		(net "FPGA_MAC_PPS_IN1-")
	)
	(via
		(at 164.2216 105.2162)
		(size 0.4064)
		(drill 0.2032)
		(layers "F.Cu" "B.Cu")
		(tenting
			(front yes)
			(back yes)
		)
		(net "FPGA_MAC_PPS_IN1-")
	)
	(via
		(at 173.5216 104.2162)
		(size 0.4064)
		(drill 0.2032)
		(layers "F.Cu" "B.Cu")
		(net "FPGA_MAC_PPS_IN1-")
	)
	(via
		(at 130.0866 90.3512)
		(size 0.4064)
		(drill 0.2032)
		(layers "F.Cu" "B.Cu")
		(net "FPGA_MAC_PPS_IN1-")
	)
	(segment
		(start 130.0716 88.8162)
		(end 130.0791 88.8237)
		(width 0.2032)
		(layer "B.Cu")
		(net "FPGA_MAC_PPS_IN1-")
	)
	(segment
		(start 130.0791 90.3437)
		(end 130.0791 88.8237)
		(width 0.2032)
		(layer "B.Cu")
		(net "FPGA_MAC_PPS_IN1-")
	)
	(segment
		(start 130.0791 90.3437)
		(end 130.0866 90.3512)
		(width 0.2032)
		(layer "B.Cu")
		(net "FPGA_MAC_PPS_IN1-")
	)
	(segment
		(start 172.7216 103.4162)
		(end 173.5216 104.2162)
		(width 0.2032)
		(layer "In2.Cu")
		(net "FPGA_MAC_PPS_IN1-")
	)
	(segment
		(start 160.5216 93.17338)
		(end 160.5216 90.69806)
		(width 0.2032)
		(layer "In2.Cu")
		(net "FPGA_MAC_PPS_IN1-")
	)
	(segment
		(start 141.7216 97.8162)
		(end 143.1216 96.4162)
		(width 0.2032)
		(layer "In2.Cu")
		(net "FPGA_MAC_PPS_IN1-")
	)
	(segment
		(start 143.1216 96.4162)
		(end 148.6216 96.4162)
		(width 0.2032)
		(layer "In2.Cu")
		(net "FPGA_MAC_PPS_IN1-")
	)
	(segment
		(start 120.03222 91.00557)
		(end 122.06867 88.96913)
		(width 0.2032)
		(layer "In2.Cu")
		(net "FPGA_MAC_PPS_IN1-")
	)
	(segment
		(start 128.70453 88.96913)
		(end 130.0866 90.3512)
		(width 0.2032)
		(layer "In2.Cu")
		(net "FPGA_MAC_PPS_IN1-")
	)
	(segment
		(start 161.18027 93.83205)
		(end 163.33745 93.83205)
		(width 0.2032)
		(layer "In2.Cu")
		(net "FPGA_MAC_PPS_IN1-")
	)
	(segment
		(start 120.6216 103.26981)
		(end 120.6216 97.4162)
		(width 0.2032)
		(layer "In2.Cu")
		(net "FPGA_MAC_PPS_IN1-")
	)
	(segment
		(start 122.06867 88.96913)
		(end 128.70453 88.96913)
		(width 0.2032)
		(layer "In2.Cu")
		(net "FPGA_MAC_PPS_IN1-")
	)
	(segment
		(start 135.59546 97.8162)
		(end 141.7216 97.8162)
		(width 0.2032)
		(layer "In2.Cu")
		(net "FPGA_MAC_PPS_IN1-")
	)
	(segment
		(start 120.83244 103.48064)
		(end 129.93102 103.48064)
		(width 0.2032)
		(layer "In2.Cu")
		(net "FPGA_MAC_PPS_IN1-")
	)
	(segment
		(start 163.33745 93.83205)
		(end 164.56517 95.05977)
		(width 0.2032)
		(layer "In2.Cu")
		(net "FPGA_MAC_PPS_IN1-")
	)
	(segment
		(start 150.69777 85.92681)
		(end 151.51468 85.1099)
		(width 0.2032)
		(layer "In2.Cu")
		(net "FPGA_MAC_PPS_IN1-")
	)
	(segment
		(start 171.76517 95.05977)
		(end 172.7216 96.0162)
		(width 0.2032)
		(layer "In2.Cu")
		(net "FPGA_MAC_PPS_IN1-")
	)
	(segment
		(start 160.5216 93.17338)
		(end 161.18027 93.83205)
		(width 0.2032)
		(layer "In2.Cu")
		(net "FPGA_MAC_PPS_IN1-")
	)
	(segment
		(start 151.51468 85.1099)
		(end 157.2153 85.1099)
		(width 0.2032)
		(layer "In2.Cu")
		(net "FPGA_MAC_PPS_IN1-")
	)
	(segment
		(start 172.7216 103.4162)
		(end 172.7216 96.0162)
		(width 0.2032)
		(layer "In2.Cu")
		(net "FPGA_MAC_PPS_IN1-")
	)
	(segment
		(start 148.6216 96.4162)
		(end 150.69777 94.34003)
		(width 0.2032)
		(layer "In2.Cu")
		(net "FPGA_MAC_PPS_IN1-")
	)
	(segment
		(start 120.6216 103.26981)
		(end 120.83244 103.48064)
		(width 0.2032)
		(layer "In2.Cu")
		(net "FPGA_MAC_PPS_IN1-")
	)
	(segment
		(start 157.2153 85.1099)
		(end 158.1216 86.0162)
		(width 0.2032)
		(layer "In2.Cu")
		(net "FPGA_MAC_PPS_IN1-")
	)
	(segment
		(start 158.1216 88.29806)
		(end 158.1216 86.0162)
		(width 0.2032)
		(layer "In2.Cu")
		(net "FPGA_MAC_PPS_IN1-")
	)
	(segment
		(start 120.03222 96.82682)
		(end 120.6216 97.4162)
		(width 0.2032)
		(layer "In2.Cu")
		(net "FPGA_MAC_PPS_IN1-")
	)
	(segment
		(start 129.93102 103.48064)
		(end 135.59546 97.8162)
		(width 0.2032)
		(layer "In2.Cu")
		(net "FPGA_MAC_PPS_IN1-")
	)
	(segment
		(start 150.69777 94.34003)
		(end 150.69777 85.92681)
		(width 0.2032)
		(layer "In2.Cu")
		(net "FPGA_MAC_PPS_IN1-")
	)
	(segment
		(start 164.56517 95.05977)
		(end 171.76517 95.05977)
		(width 0.2032)
		(layer "In2.Cu")
		(net "FPGA_MAC_PPS_IN1-")
	)
	(segment
		(start 120.03222 96.82682)
		(end 120.03222 91.00557)
		(width 0.2032)
		(layer "In2.Cu")
		(net "FPGA_MAC_PPS_IN1-")
	)
	(segment
		(start 158.1216 88.29806)
		(end 160.5216 90.69806)
		(width 0.2032)
		(layer "In2.Cu")
		(net "FPGA_MAC_PPS_IN1-")
	)
	(segment
		(start 172.43067 103.12527)
		(end 172.43067 101.02527)
		(width 0.2032)
		(layer "In3.Cu")
		(net "FPGA_MAC_PPS_IN1-")
	)
	(segment
		(start 164.2216 105.2162)
		(end 167.17399 102.26381)
		(width 0.2032)
		(layer "In3.Cu")
		(net "FPGA_MAC_PPS_IN1-")
	)
	(segment
		(start 172.43067 103.12527)
		(end 173.5216 104.2162)
		(width 0.2032)
		(layer "In3.Cu")
		(net "FPGA_MAC_PPS_IN1-")
	)
	(segment
		(start 167.17399 100.66381)
		(end 167.88914 99.94866)
		(width 0.2032)
		(layer "In3.Cu")
		(net "FPGA_MAC_PPS_IN1-")
	)
	(segment
		(start 167.88914 99.94866)
		(end 171.35406 99.94866)
		(width 0.2032)
		(layer "In3.Cu")
		(net "FPGA_MAC_PPS_IN1-")
	)
	(segment
		(start 167.17399 102.26381)
		(end 167.17399 100.66381)
		(width 0.2032)
		(layer "In3.Cu")
		(net "FPGA_MAC_PPS_IN1-")
	)
	(segment
		(start 171.35406 99.94866)
		(end 172.43067 101.02527)
		(width 0.2032)
		(layer "In3.Cu")
		(net "FPGA_MAC_PPS_IN1-")
	)
	(segment
		(start 145.7216 103.3162)
		(end 145.7466 103.3162)
		(width 0.2032)
		(layer "F.Cu")
		(net "FPGA_MAC_PPS_IN0-")
	)
	(segment
		(start 146.2216 104.4162)
		(end 146.2466 104.4162)
		(width 0.2032)
		(layer "F.Cu")
		(net "FPGA_MAC_PPS_IN0-")
	)
	(segment
		(start 145.7466 103.9412)
		(end 146.2216 104.4162)
		(width 0.2032)
		(layer "F.Cu")
		(net "FPGA_MAC_PPS_IN0-")
	)
	(segment
		(start 159.4216 108.3162)
		(end 163.04903 104.68877)
		(width 0.2032)
		(layer "F.Cu")
		(net "FPGA_MAC_PPS_IN0-")
	)
	(segment
		(start 145.7466 103.9412)
		(end 145.7466 103.3162)
		(width 0.2032)
		(layer "F.Cu")
		(net "FPGA_MAC_PPS_IN0-")
	)
	(segment
		(start 163.04903 104.68877)
		(end 163.04903 103.31041)
		(width 0.2032)
		(layer "F.Cu")
		(net "FPGA_MAC_PPS_IN0-")
	)
	(segment
		(start 144.9716 104.0662)
		(end 145.7216 103.3162)
		(width 0.2032)
		(layer "F.Cu")
		(net "FPGA_MAC_PPS_IN0-")
	)
	(segment
		(start 146.2466 105.15733)
		(end 146.2466 104.4162)
		(width 0.2032)
		(layer "F.Cu")
		(net "FPGA_MAC_PPS_IN0-")
	)
	(segment
		(start 144.5216 104.0662)
		(end 144.9716 104.0662)
		(width 0.2032)
		(layer "F.Cu")
		(net "FPGA_MAC_PPS_IN0-")
	)
	(via
		(at 159.4216 108.3162)
		(size 0.4064)
		(drill 0.2032)
		(layers "F.Cu" "B.Cu")
		(tenting
			(front yes)
			(back yes)
		)
		(net "FPGA_MAC_PPS_IN0-")
	)
	(via
		(at 146.2466 105.15733)
		(size 0.4064)
		(drill 0.2032)
		(layers "F.Cu" "B.Cu")
		(net "FPGA_MAC_PPS_IN0-")
	)
	(segment
		(start 146.2466 103.5912)
		(end 146.5534 103.2844)
		(width 0.2032)
		(layer "In2.Cu")
		(net "FPGA_MAC_PPS_IN0-")
	)
	(segment
		(start 147.9898 106.3844)
		(end 147.9898 103.40343)
		(width 0.2032)
		(layer "In2.Cu")
		(net "FPGA_MAC_PPS_IN0-")
	)
	(segment
		(start 147.9898 106.3844)
		(end 149.9216 108.3162)
		(width 0.2032)
		(layer "In2.Cu")
		(net "FPGA_MAC_PPS_IN0-")
	)
	(segment
		(start 146.2466 105.15733)
		(end 146.2466 103.5912)
		(width 0.2032)
		(layer "In2.Cu")
		(net "FPGA_MAC_PPS_IN0-")
	)
	(segment
		(start 146.5534 103.2844)
		(end 147.87077 103.2844)
		(width 0.2032)
		(layer "In2.Cu")
		(net "FPGA_MAC_PPS_IN0-")
	)
	(segment
		(start 147.87077 103.2844)
		(end 147.9898 103.40343)
		(width 0.2032)
		(layer "In2.Cu")
		(net "FPGA_MAC_PPS_IN0-")
	)
	(segment
		(start 149.9216 108.3162)
		(end 159.4216 108.3162)
		(width 0.2032)
		(layer "In2.Cu")
		(net "FPGA_MAC_PPS_IN0-")
	)
	(segment
		(start 154.54892 104.48888)
		(end 154.54892 103.31041)
		(width 0.2032)
		(layer "F.Cu")
		(net "MAC_RF_OUT")
	)
	(segment
		(start 154.04905 104.9162)
		(end 154.1216 104.9162)
		(width 0.2032)
		(layer "F.Cu")
		(net "MAC_RF_OUT")
	)
	(segment
		(start 154.1216 104.9162)
		(end 154.54892 104.48888)
		(width 0.2032)
		(layer "F.Cu")
		(net "MAC_RF_OUT")
	)
	(segment
		(start 154.04905 104.9162)
		(end 154.04905 103.31041)
		(width 0.2032)
		(layer "F.Cu")
		(net "MAC_RF_OUT")
	)
	(segment
		(start 154.02168 103.31041)
		(end 154.04905 103.31041)
		(width 0.2032)
		(layer "F.Cu")
		(net "MAC_RF_OUT")
	)
	(via
		(at 154.1216 104.9162)
		(size 0.4064)
		(drill 0.2032)
		(layers "F.Cu" "B.Cu")
		(tenting
			(front yes)
			(back yes)
		)
		(net "MAC_RF_OUT")
	)
	(segment
		(start 119.64092 120.69688)
		(end 130.54092 120.69688)
		(width 0.2032)
		(layer "B.Cu")
		(net "MAC_RF_OUT")
	)
	(segment
		(start 132.6216 117.35459)
		(end 136.80455 113.17165)
		(width 0.2032)
		(layer "B.Cu")
		(net "MAC_RF_OUT")
	)
	(segment
		(start 136.80455 105.91455)
		(end 141.4029 101.3162)
		(width 0.2032)
		(layer "B.Cu")
		(net "MAC_RF_OUT")
	)
	(segment
		(start 148.50931 106.79717)
		(end 148.62834 106.9162)
		(width 0.2032)
		(layer "B.Cu")
		(net "MAC_RF_OUT")
	)
	(segment
		(start 108.9216 131.4162)
		(end 119.64092 120.69688)
		(width 0.2032)
		(layer "B.Cu")
		(net "MAC_RF_OUT")
	)
	(segment
		(start 90.5216 131.4162)
		(end 108.9216 131.4162)
		(width 0.2032)
		(layer "B.Cu")
		(net "MAC_RF_OUT")
	)
	(segment
		(start 147.4216 102.83523)
		(end 147.4216 101.3162)
		(width 0.2032)
		(layer "B.Cu")
		(net "MAC_RF_OUT")
	)
	(segment
		(start 148.62834 106.9162)
		(end 153.62214 106.9162)
		(width 0.2032)
		(layer "B.Cu")
		(net "MAC_RF_OUT")
	)
	(segment
		(start 141.4029 101.3162)
		(end 147.4216 101.3162)
		(width 0.2032)
		(layer "B.Cu")
		(net "MAC_RF_OUT")
	)
	(segment
		(start 136.80455 113.17165)
		(end 136.80455 105.91455)
		(width 0.2032)
		(layer "B.Cu")
		(net "MAC_RF_OUT")
	)
	(segment
		(start 148.50931 106.79717)
		(end 148.50931 103.92294)
		(width 0.2032)
		(layer "B.Cu")
		(net "MAC_RF_OUT")
	)
	(segment
		(start 130.54092 120.69688)
		(end 132.6216 118.6162)
		(width 0.2032)
		(layer "B.Cu")
		(net "MAC_RF_OUT")
	)
	(segment
		(start 147.4216 102.83523)
		(end 148.50931 103.92294)
		(width 0.2032)
		(layer "B.Cu")
		(net "MAC_RF_OUT")
	)
	(segment
		(start 153.62214 106.9162)
		(end 154.1216 106.41674)
		(width 0.2032)
		(layer "B.Cu")
		(net "MAC_RF_OUT")
	)
	(segment
		(start 86.9216 137.3162)
		(end 86.9216 135.0162)
		(width 0.2032)
		(layer "B.Cu")
		(net "MAC_RF_OUT")
	)
	(segment
		(start 86.9216 135.0162)
		(end 90.5216 131.4162)
		(width 0.2032)
		(layer "B.Cu")
		(net "MAC_RF_OUT")
	)
	(segment
		(start 132.6216 118.6162)
		(end 132.6216 117.35459)
		(width 0.2032)
		(layer "B.Cu")
		(net "MAC_RF_OUT")
	)
	(segment
		(start 154.1216 106.41674)
		(end 154.1216 104.9162)
		(width 0.2032)
		(layer "B.Cu")
		(net "MAC_RF_OUT")
	)
	(segment
		(start 189.5216 120.72318)
		(end 189.5216 119.9162)
		(width 0.2032)
		(layer "F.Cu")
		(net "EXT_EEPROM_WP")
	)
	(segment
		(start 180.8216 107.5162)
		(end 180.8216 107.49496)
		(width 0.2032)
		(layer "F.Cu")
		(net "EXT_EEPROM_WP")
	)
	(segment
		(start 180.8216 107.49496)
		(end 181.85985 106.45672)
		(width 0.2032)
		(layer "F.Cu")
		(net "EXT_EEPROM_WP")
	)
	(segment
		(start 181.85985 106.45672)
		(end 181.85985 106.18241)
		(width 0.2032)
		(layer "F.Cu")
		(net "EXT_EEPROM_WP")
	)
	(segment
		(start 188.08397 120.72318)
		(end 189.5216 120.72318)
		(width 0.2032)
		(layer "F.Cu")
		(net "EXT_EEPROM_WP")
	)
	(via
		(at 189.5216 119.9162)
		(size 0.4064)
		(drill 0.2032)
		(layers "F.Cu" "B.Cu")
		(tenting
			(front yes)
			(back yes)
		)
		(net "EXT_EEPROM_WP")
	)
	(via
		(at 180.8216 107.5162)
		(size 0.4064)
		(drill 0.2032)
		(layers "F.Cu" "B.Cu")
		(net "EXT_EEPROM_WP")
	)
	(segment
		(start 181.12819 107.2646)
		(end 181.63644 107.2646)
		(width 0.2032)
		(layer "B.Cu")
		(net "EXT_EEPROM_WP")
	)
	(segment
		(start 180.87659 107.5162)
		(end 181.12819 107.2646)
		(width 0.2032)
		(layer "B.Cu")
		(net "EXT_EEPROM_WP")
	)
	(segment
		(start 181.63644 107.2646)
		(end 181.90985 106.9912)
		(width 0.2032)
		(layer "B.Cu")
		(net "EXT_EEPROM_WP")
	)
	(segment
		(start 180.8216 107.5162)
		(end 180.87659 107.5162)
		(width 0.2032)
		(layer "B.Cu")
		(net "EXT_EEPROM_WP")
	)
	(segment
		(start 183.5216 118.0162)
		(end 188.3384 118.0162)
		(width 0.2032)
		(layer "In3.Cu")
		(net "EXT_EEPROM_WP")
	)
	(segment
		(start 179.7216 108.60019)
		(end 180.8136 107.5082)
		(width 0.2032)
		(layer "In3.Cu")
		(net "EXT_EEPROM_WP")
	)
	(segment
		(start 179.7216 114.2162)
		(end 183.5216 118.0162)
		(width 0.2032)
		(layer "In3.Cu")
		(net "EXT_EEPROM_WP")
	)
	(segment
		(start 179.7216 114.2162)
		(end 179.7216 108.60019)
		(width 0.2032)
		(layer "In3.Cu")
		(net "EXT_EEPROM_WP")
	)
	(segment
		(start 189.5216 119.9162)
		(end 189.5216 119.1994)
		(width 0.2032)
		(layer "In3.Cu")
		(net "EXT_EEPROM_WP")
	)
	(segment
		(start 188.3384 118.0162)
		(end 189.5216 119.1994)
		(width 0.2032)
		(layer "In3.Cu")
		(net "EXT_EEPROM_WP")
	)
	(segment
		(start 109.4216 50.7428)
		(end 109.4216 50.7412)
		(width 0.2032)
		(layer "F.Cu")
		(net "GPS1_TX")
	)
	(segment
		(start 109.2982 50.8662)
		(end 109.4216 50.7428)
		(width 0.2032)
		(layer "F.Cu")
		(net "GPS1_TX")
	)
	(segment
		(start 171.04901 98.0162)
		(end 172.1216 98.0162)
		(width 0.2032)
		(layer "F.Cu")
		(net "GPS1_TX")
	)
	(segment
		(start 110.3466 50.7412)
		(end 110.5216 50.5662)
		(width 0.2032)
		(layer "F.Cu")
		(net "GPS1_TX")
	)
	(segment
		(start 171.04901 99.26063)
		(end 171.04901 98.0162)
		(width 0.2032)
		(layer "F.Cu")
		(net "GPS1_TX")
	)
	(segment
		(start 109.4216 50.7412)
		(end 110.3466 50.7412)
		(width 0.2032)
		(layer "F.Cu")
		(net "GPS1_TX")
	)
	(segment
		(start 110.5216 50.5662)
		(end 110.5216 50.5162)
		(width 0.2032)
		(layer "F.Cu")
		(net "GPS1_TX")
	)
	(segment
		(start 108.3216 50.8662)
		(end 109.2982 50.8662)
		(width 0.2032)
		(layer "F.Cu")
		(net "GPS1_TX")
	)
	(via
		(at 110.5216 50.5162)
		(size 0.4064)
		(drill 0.2032)
		(layers "F.Cu" "B.Cu")
		(net "GPS1_TX")
	)
	(via
		(at 172.1216 98.0162)
		(size 0.4064)
		(drill 0.2032)
		(layers "F.Cu" "B.Cu")
		(net "GPS1_TX")
	)
	(segment
		(start 120.1216 59.9162)
		(end 134.9216 59.9162)
		(width 0.2032)
		(layer "In3.Cu")
		(net "GPS1_TX")
	)
	(segment
		(start 179.10729 98.07835)
		(end 181.09471 100.06576)
		(width 0.2032)
		(layer "In3.Cu")
		(net "GPS1_TX")
	)
	(segment
		(start 175.4216 101.3162)
		(end 180.71194 101.3162)
		(width 0.2032)
		(layer "In3.Cu")
		(net "GPS1_TX")
	)
	(segment
		(start 154.4216 80.7162)
		(end 167.5466 93.8412)
		(width 0.2032)
		(layer "In3.Cu")
		(net "GPS1_TX")
	)
	(segment
		(start 111.7216 53.1162)
		(end 111.7216 51.7162)
		(width 0.2032)
		(layer "In3.Cu")
		(net "GPS1_TX")
	)
	(segment
		(start 114.1216 55.5162)
		(end 115.7216 55.5162)
		(width 0.2032)
		(layer "In3.Cu")
		(net "GPS1_TX")
	)
	(segment
		(start 173.27186 93.8412)
		(end 177.50901 98.07835)
		(width 0.2032)
		(layer "In3.Cu")
		(net "GPS1_TX")
	)
	(segment
		(start 111.7216 53.1162)
		(end 114.1216 55.5162)
		(width 0.2032)
		(layer "In3.Cu")
		(net "GPS1_TX")
	)
	(segment
		(start 172.1216 98.0162)
		(end 175.4216 101.3162)
		(width 0.2032)
		(layer "In3.Cu")
		(net "GPS1_TX")
	)
	(segment
		(start 110.5216 50.5162)
		(end 111.7216 51.7162)
		(width 0.2032)
		(layer "In3.Cu")
		(net "GPS1_TX")
	)
	(segment
		(start 181.09471 100.93343)
		(end 181.09471 100.06576)
		(width 0.2032)
		(layer "In3.Cu")
		(net "GPS1_TX")
	)
	(segment
		(start 134.9216 59.9162)
		(end 154.4216 79.4162)
		(width 0.2032)
		(layer "In3.Cu")
		(net "GPS1_TX")
	)
	(segment
		(start 115.7216 55.5162)
		(end 120.1216 59.9162)
		(width 0.2032)
		(layer "In3.Cu")
		(net "GPS1_TX")
	)
	(segment
		(start 154.4216 80.7162)
		(end 154.4216 79.4162)
		(width 0.2032)
		(layer "In3.Cu")
		(net "GPS1_TX")
	)
	(segment
		(start 167.5466 93.8412)
		(end 173.27186 93.8412)
		(width 0.2032)
		(layer "In3.Cu")
		(net "GPS1_TX")
	)
	(segment
		(start 177.50901 98.07835)
		(end 179.10729 98.07835)
		(width 0.2032)
		(layer "In3.Cu")
		(net "GPS1_TX")
	)
	(segment
		(start 180.71194 101.3162)
		(end 181.09471 100.93343)
		(width 0.2032)
		(layer "In3.Cu")
		(net "GPS1_TX")
	)
	(segment
		(start 111.1216 58.6662)
		(end 112.1716 58.6662)
		(width 0.2032)
		(layer "F.Cu")
		(net "GPS1_TP1")
	)
	(segment
		(start 112.1716 58.6662)
		(end 112.4216 58.4162)
		(width 0.2032)
		(layer "F.Cu")
		(net "GPS1_TP1")
	)
	(segment
		(start 112.4216 58.3912)
		(end 112.4591 58.4287)
		(width 0.2032)
		(layer "F.Cu")
		(net "GPS1_TP1")
	)
	(segment
		(start 188.08397 117.72318)
		(end 189.3216 117.72318)
		(width 0.2032)
		(layer "F.Cu")
		(net "GPS1_TP1")
	)
	(segment
		(start 189.3216 117.72318)
		(end 189.3216 117.48336)
		(width 0.2032)
		(layer "F.Cu")
		(net "GPS1_TP1")
	)
	(segment
		(start 112.4216 58.4162)
		(end 112.4216 58.3912)
		(width 0.2032)
		(layer "F.Cu")
		(net "GPS1_TP1")
	)
	(segment
		(start 189.3216 117.48336)
		(end 190.09745 117.48336)
		(width 0.2032)
		(layer "F.Cu")
		(net "GPS1_TP1")
	)
	(segment
		(start 112.4591 58.4287)
		(end 113.3841 58.4287)
		(width 0.2032)
		(layer "F.Cu")
		(net "GPS1_TP1")
	)
	(via
		(at 190.09745 117.48336)
		(size 0.4064)
		(drill 0.2032)
		(layers "F.Cu" "B.Cu")
		(tenting
			(front yes)
			(back yes)
		)
		(net "GPS1_TP1")
	)
	(via
		(at 113.4216 58.4662)
		(size 0.4064)
		(drill 0.2032)
		(layers "F.Cu" "B.Cu")
		(net "GPS1_TP1")
	)
	(via
		(at 181.2216 113.9162)
		(size 0.4064)
		(drill 0.2032)
		(layers "F.Cu" "B.Cu")
		(net "GPS1_TP1")
	)
	(segment
		(start 206.1216 75.249)
		(end 206.1216 65.0162)
		(width 0.2032)
		(layer "B.Cu")
		(net "GPS1_TP1")
	)
	(segment
		(start 206.1216 65.0162)
		(end 206.7216 64.4162)
		(width 0.2032)
		(layer "B.Cu")
		(net "GPS1_TP1")
	)
	(segment
		(start 181.8216 98.3162)
		(end 182.86113 97.27667)
		(width 0.2032)
		(layer "B.Cu")
		(net "GPS1_TP1")
	)
	(segment
		(start 180.6216 114.5162)
		(end 181.2216 113.9162)
		(width 0.2032)
		(layer "B.Cu")
		(net "GPS1_TP1")
	)
	(segment
		(start 112.6466 57.23523)
		(end 112.86564 57.0162)
		(width 0.2032)
		(layer "B.Cu")
		(net "GPS1_TP1")
	)
	(segment
		(start 112.86564 57.0162)
		(end 113.7216 57.0162)
		(width 0.2032)
		(layer "B.Cu")
		(net "GPS1_TP1")
	)
	(segment
		(start 125.58363 67.6162)
		(end 129.4216 67.6162)
		(width 0.2032)
		(layer "B.Cu")
		(net "GPS1_TP1")
	)
	(segment
		(start 114.3518 58.1464)
		(end 119.7216 63.5162)
		(width 0.2032)
		(layer "B.Cu")
		(net "GPS1_TP1")
	)
	(segment
		(start 113.7216 57.0162)
		(end 114.3518 57.6464)
		(width 0.2032)
		(layer "B.Cu")
		(net "GPS1_TP1")
	)
	(segment
		(start 112.6466 57.6912)
		(end 113.4216 58.4662)
		(width 0.2032)
		(layer "B.Cu")
		(net "GPS1_TP1")
	)
	(segment
		(start 119.7216 63.5162)
		(end 121.48363 63.5162)
		(width 0.2032)
		(layer "B.Cu")
		(net "GPS1_TP1")
	)
	(segment
		(start 193.04369 95.8162)
		(end 201.6216 95.8162)
		(width 0.2032)
		(layer "B.Cu")
		(net "GPS1_TP1")
	)
	(segment
		(start 192.99564 95.76815)
		(end 193.04369 95.8162)
		(width 0.2032)
		(layer "B.Cu")
		(net "GPS1_TP1")
	)
	(segment
		(start 170.2216 106.10303)
		(end 170.8216 106.70303)
		(width 0.2032)
		(layer "B.Cu")
		(net "GPS1_TP1")
	)
	(segment
		(start 166.2216 56.0162)
		(end 171.2216 51.0162)
		(width 0.2032)
		(layer "B.Cu")
		(net "GPS1_TP1")
	)
	(segment
		(start 114.3518 58.1464)
		(end 114.3518 57.6464)
		(width 0.2032)
		(layer "B.Cu")
		(net "GPS1_TP1")
	)
	(segment
		(start 170.8216 108.69405)
		(end 176.64375 114.5162)
		(width 0.2032)
		(layer "B.Cu")
		(net "GPS1_TP1")
	)
	(segment
		(start 182.86113 97.27667)
		(end 182.86113 96.48277)
		(width 0.2032)
		(layer "B.Cu")
		(net "GPS1_TP1")
	)
	(segment
		(start 170.8216 108.69405)
		(end 170.8216 106.70303)
		(width 0.2032)
		(layer "B.Cu")
		(net "GPS1_TP1")
	)
	(segment
		(start 201.6216 95.8162)
		(end 203.3216 94.1162)
		(width 0.2032)
		(layer "B.Cu")
		(net "GPS1_TP1")
	)
	(segment
		(start 203.9216 51.0162)
		(end 206.7216 53.8162)
		(width 0.2032)
		(layer "B.Cu")
		(net "GPS1_TP1")
	)
	(segment
		(start 183.57575 95.76815)
		(end 192.99564 95.76815)
		(width 0.2032)
		(layer "B.Cu")
		(net "GPS1_TP1")
	)
	(segment
		(start 182.86113 96.48277)
		(end 183.57575 95.76815)
		(width 0.2032)
		(layer "B.Cu")
		(net "GPS1_TP1")
	)
	(segment
		(start 206.7216 64.4162)
		(end 206.7216 53.8162)
		(width 0.2032)
		(layer "B.Cu")
		(net "GPS1_TP1")
	)
	(segment
		(start 203.3216 78.04901)
		(end 206.1216 75.249)
		(width 0.2032)
		(layer "B.Cu")
		(net "GPS1_TP1")
	)
	(segment
		(start 129.4216 67.6162)
		(end 141.0216 56.0162)
		(width 0.2032)
		(layer "B.Cu")
		(net "GPS1_TP1")
	)
	(segment
		(start 203.3216 94.1162)
		(end 203.3216 78.04901)
		(width 0.2032)
		(layer "B.Cu")
		(net "GPS1_TP1")
	)
	(segment
		(start 171.2216 51.0162)
		(end 203.9216 51.0162)
		(width 0.2032)
		(layer "B.Cu")
		(net "GPS1_TP1")
	)
	(segment
		(start 112.6466 57.6912)
		(end 112.6466 57.23523)
		(width 0.2032)
		(layer "B.Cu")
		(net "GPS1_TP1")
	)
	(segment
		(start 170.2216 106.10303)
		(end 170.2216 104.2162)
		(width 0.2032)
		(layer "B.Cu")
		(net "GPS1_TP1")
	)
	(segment
		(start 141.0216 56.0162)
		(end 166.2216 56.0162)
		(width 0.2032)
		(layer "B.Cu")
		(net "GPS1_TP1")
	)
	(segment
		(start 121.48363 63.5162)
		(end 125.58363 67.6162)
		(width 0.2032)
		(layer "B.Cu")
		(net "GPS1_TP1")
	)
	(segment
		(start 176.64375 114.5162)
		(end 180.6216 114.5162)
		(width 0.2032)
		(layer "B.Cu")
		(net "GPS1_TP1")
	)
	(segment
		(start 170.2216 104.2162)
		(end 176.1216 98.3162)
		(width 0.2032)
		(layer "B.Cu")
		(net "GPS1_TP1")
	)
	(segment
		(start 176.1216 98.3162)
		(end 181.8216 98.3162)
		(width 0.2032)
		(layer "B.Cu")
		(net "GPS1_TP1")
	)
	(segment
		(start 183.4565 114.88147)
		(end 184.99123 116.4162)
		(width 0.2032)
		(layer "In3.Cu")
		(net "GPS1_TP1")
	)
	(segment
		(start 189.03029 116.4162)
		(end 190.09745 117.48336)
		(width 0.2032)
		(layer "In3.Cu")
		(net "GPS1_TP1")
	)
	(segment
		(start 182.18687 114.88147)
		(end 183.4565 114.88147)
		(width 0.2032)
		(layer "In3.Cu")
		(net "GPS1_TP1")
	)
	(segment
		(start 184.99123 116.4162)
		(end 189.03029 116.4162)
		(width 0.2032)
		(layer "In3.Cu")
		(net "GPS1_TP1")
	)
	(segment
		(start 181.2216 113.9162)
		(end 182.18687 114.88147)
		(width 0.2032)
		(layer "In3.Cu")
		(net "GPS1_TP1")
	)
	(segment
		(start 106.59831 58.1162)
		(end 107.9716 58.1162)
		(width 0.2032)
		(layer "F.Cu")
		(net "GPS1_RX")
	)
	(segment
		(start 106.295 57.81289)
		(end 106.295 57.7396)
		(width 0.2032)
		(layer "F.Cu")
		(net "GPS1_RX")
	)
	(segment
		(start 106.1466 57.6162)
		(end 106.1591 57.6037)
		(width 0.2032)
		(layer "F.Cu")
		(net "GPS1_RX")
	)
	(segment
		(start 171.04901 105.01188)
		(end 171.07168 105.01188)
		(width 0.2032)
		(layer "F.Cu")
		(net "GPS1_RX")
	)
	(segment
		(start 106.295 57.81289)
		(end 106.59831 58.1162)
		(width 0.2032)
		(layer "F.Cu")
		(net "GPS1_RX")
	)
	(segment
		(start 171.04901 105.01188)
		(end 171.04901 103.31041)
		(width 0.2032)
		(layer "F.Cu")
		(net "GPS1_RX")
	)
	(segment
		(start 106.1591 57.6037)
		(end 106.1591 56.7287)
		(width 0.2032)
		(layer "F.Cu")
		(net "GPS1_RX")
	)
	(segment
		(start 106.1716 57.6162)
		(end 106.295 57.7396)
		(width 0.2032)
		(layer "F.Cu")
		(net "GPS1_RX")
	)
	(via
		(at 171.07168 105.01188)
		(size 0.4064)
		(drill 0.2032)
		(layers "F.Cu" "B.Cu")
		(tenting
			(front yes)
			(back yes)
		)
		(net "GPS1_RX")
	)
	(via
		(at 106.1716 56.7162)
		(size 0.4064)
		(drill 0.2032)
		(layers "F.Cu" "B.Cu")
		(net "GPS1_RX")
	)
	(via
		(at 180.5216 100.7162)
		(size 0.4064)
		(drill 0.2032)
		(layers "F.Cu" "B.Cu")
		(net "GPS1_RX")
	)
	(segment
		(start 195.082 107.0558)
		(end 196.8216 105.3162)
		(width 0.2032)
		(layer "B.Cu")
		(net "GPS1_RX")
	)
	(segment
		(start 183.53996 111.94784)
		(end 183.53996 108.44799)
		(width 0.2032)
		(layer "B.Cu")
		(net "GPS1_RX")
	)
	(segment
		(start 172.11124 107.93413)
		(end 174.3216 110.14449)
		(width 0.2032)
		(layer "B.Cu")
		(net "GPS1_RX")
	)
	(segment
		(start 185.55816 107.0558)
		(end 195.082 107.0558)
		(width 0.2032)
		(layer "B.Cu")
		(net "GPS1_RX")
	)
	(segment
		(start 183.53996 108.44799)
		(end 184.16596 108.44799)
		(width 0.2032)
		(layer "B.Cu")
		(net "GPS1_RX")
	)
	(segment
		(start 183.40161 103.59621)
		(end 196.70257 103.59621)
		(width 0.2032)
		(layer "B.Cu")
		(net "GPS1_RX")
	)
	(segment
		(start 174.3216 110.95186)
		(end 174.3216 110.14449)
		(width 0.2032)
		(layer "B.Cu")
		(net "GPS1_RX")
	)
	(segment
		(start 182.58502 112.90278)
		(end 183.53996 111.94784)
		(width 0.2032)
		(layer "B.Cu")
		(net "GPS1_RX")
	)
	(segment
		(start 174.88594 111.5162)
		(end 176.61505 111.5162)
		(width 0.2032)
		(layer "B.Cu")
		(net "GPS1_RX")
	)
	(segment
		(start 196.70257 103.59621)
		(end 196.8216 103.71525)
		(width 0.2032)
		(layer "B.Cu")
		(net "GPS1_RX")
	)
	(segment
		(start 184.16596 108.44799)
		(end 185.55816 107.0558)
		(width 0.2032)
		(layer "B.Cu")
		(net "GPS1_RX")
	)
	(segment
		(start 176.61505 111.5162)
		(end 178.00164 112.90278)
		(width 0.2032)
		(layer "B.Cu")
		(net "GPS1_RX")
	)
	(segment
		(start 171.07168 105.01188)
		(end 172.11124 106.05144)
		(width 0.2032)
		(layer "B.Cu")
		(net "GPS1_RX")
	)
	(segment
		(start 174.3216 110.95186)
		(end 174.88594 111.5162)
		(width 0.2032)
		(layer "B.Cu")
		(net "GPS1_RX")
	)
	(segment
		(start 172.11124 107.93413)
		(end 172.11124 106.05144)
		(width 0.2032)
		(layer "B.Cu")
		(net "GPS1_RX")
	)
	(segment
		(start 196.8216 105.3162)
		(end 196.8216 103.71525)
		(width 0.2032)
		(layer "B.Cu")
		(net "GPS1_RX")
	)
	(segment
		(start 180.5216 100.7162)
		(end 183.40161 103.59621)
		(width 0.2032)
		(layer "B.Cu")
		(net "GPS1_RX")
	)
	(segment
		(start 178.00164 112.90278)
		(end 182.58502 112.90278)
		(width 0.2032)
		(layer "B.Cu")
		(net "GPS1_RX")
	)
	(segment
		(start 109.26104 57.3912)
		(end 110.03604 56.6162)
		(width 0.2032)
		(layer "In3.Cu")
		(net "GPS1_RX")
	)
	(segment
		(start 119.57825 61.0844)
		(end 134.8898 61.0844)
		(width 0.2032)
		(layer "In3.Cu")
		(net "GPS1_RX")
	)
	(segment
		(start 106.1716 56.7162)
		(end 106.8466 57.3912)
		(width 0.2032)
		(layer "In3.Cu")
		(net "GPS1_RX")
	)
	(segment
		(start 167.28468 94.20951)
		(end 173.15486 94.20951)
		(width 0.2032)
		(layer "In3.Cu")
		(net "GPS1_RX")
	)
	(segment
		(start 106.8466 57.3912)
		(end 109.26104 57.3912)
		(width 0.2032)
		(layer "In3.Cu")
		(net "GPS1_RX")
	)
	(segment
		(start 113.7216 56.6162)
		(end 114.3034 57.198)
		(width 0.2032)
		(layer "In3.Cu")
		(net "GPS1_RX")
	)
	(segment
		(start 110.03604 56.6162)
		(end 113.7216 56.6162)
		(width 0.2032)
		(layer "In3.Cu")
		(net "GPS1_RX")
	)
	(segment
		(start 153.3216 80.24644)
		(end 153.3216 79.5162)
		(width 0.2032)
		(layer "In3.Cu")
		(net "GPS1_RX")
	)
	(segment
		(start 179.81664 100.01124)
		(end 179.81664 99.58228)
		(width 0.2032)
		(layer "In3.Cu")
		(net "GPS1_RX")
	)
	(segment
		(start 179.81664 100.01124)
		(end 180.5216 100.7162)
		(width 0.2032)
		(layer "In3.Cu")
		(net "GPS1_RX")
	)
	(segment
		(start 134.8898 61.0844)
		(end 153.3216 79.5162)
		(width 0.2032)
		(layer "In3.Cu")
		(net "GPS1_RX")
	)
	(segment
		(start 179.15056 98.9162)
		(end 179.81664 99.58228)
		(width 0.2032)
		(layer "In3.Cu")
		(net "GPS1_RX")
	)
	(segment
		(start 173.15486 94.20951)
		(end 177.86155 98.9162)
		(width 0.2032)
		(layer "In3.Cu")
		(net "GPS1_RX")
	)
	(segment
		(start 177.86155 98.9162)
		(end 179.15056 98.9162)
		(width 0.2032)
		(layer "In3.Cu")
		(net "GPS1_RX")
	)
	(segment
		(start 153.3216 80.24644)
		(end 167.28468 94.20951)
		(width 0.2032)
		(layer "In3.Cu")
		(net "GPS1_RX")
	)
	(segment
		(start 115.69185 57.198)
		(end 119.57825 61.0844)
		(width 0.2032)
		(layer "In3.Cu")
		(net "GPS1_RX")
	)
	(segment
		(start 114.3034 57.198)
		(end 115.69185 57.198)
		(width 0.2032)
		(layer "In3.Cu")
		(net "GPS1_RX")
	)
	(segment
		(start 124.5576 156.99168)
		(end 124.5576 152.2186)
		(width 0.127)
		(layer "B.Cu")
		(net "NetC44_1")
	)
	(segment
		(start 124.5416 157.7576)
		(end 124.5576 157.7416)
		(width 0.2032)
		(layer "B.Cu")
		(net "NetC44_1")
	)
	(arc
		(start 124.54159 152.25723)
		(mid 124.545749 152.236321)
		(end 124.557593 152.218594)
		(width 0.127)
		(layer "B.Cu")
		(net "NetC44_1")
	)
	(arc
		(start 124.5576 156.99168)
		(mid 124.548243 157.038719)
		(end 124.521598 157.078598)
		(width 0.127)
		(layer "B.Cu")
		(net "NetC44_1")
	)
	(segment
		(start 125.5736 156.95305)
		(end 125.5736 152.2186)
		(width 0.127)
		(layer "B.Cu")
		(net "NetC45_1")
	)
	(arc
		(start 125.5736 156.95305)
		(mid 125.560085 157.020995)
		(end 125.521597 157.078597)
		(width 0.127)
		(layer "B.Cu")
		(net "NetC45_1")
	)
	(segment
		(start 127.5802 156.93711)
		(end 127.5802 152.2186)
		(width 0.127)
		(layer "B.Cu")
		(net "NetC46_1")
	)
	(arc
		(start 127.5802 157.66439)
		(mid 127.570187 157.714783)
		(end 127.541671 157.757521)
		(width 0.127)
		(layer "B.Cu")
		(net "NetC46_1")
	)
	(arc
		(start 127.5802 156.93711)
		(mid 127.564968 157.013685)
		(end 127.521592 157.078602)
		(width 0.127)
		(layer "B.Cu")
		(net "NetC46_1")
	)
	(segment
		(start 128.6724 156.71451)
		(end 128.6724 152.2186)
		(width 0.127)
		(layer "B.Cu")
		(net "NetC47_1")
	)
	(arc
		(start 128.6724 156.71451)
		(mid 128.633206 156.911554)
		(end 128.521589 157.078599)
		(width 0.127)
		(layer "B.Cu")
		(net "NetC47_1")
	)
	(segment
		(start 132.5586 156.98923)
		(end 132.5586 152.2186)
		(width 0.127)
		(layer "B.Cu")
		(net "NetC48_1")
	)
	(arc
		(start 132.5586 156.98923)
		(mid 132.548979 157.037597)
		(end 132.521581 157.078601)
		(width 0.127)
		(layer "B.Cu")
		(net "NetC48_1")
	)
	(arc
		(start 132.5586 157.71651)
		(mid 132.554177 157.738744)
		(end 132.541583 157.757593)
		(width 0.127)
		(layer "B.Cu")
		(net "NetC48_1")
	)
	(segment
		(start 136.4956 157.01589)
		(end 136.4956 152.2186)
		(width 0.127)
		(layer "B.Cu")
		(net "NetC50_1")
	)
	(arc
		(start 136.521574 157.078596)
		(mid 136.502351 157.049826)
		(end 136.4956 157.01589)
		(width 0.127)
		(layer "B.Cu")
		(net "NetC50_1")
	)
	(arc
		(start 136.495597 152.218603)
		(mid 136.529622 152.269524)
		(end 136.541569 152.32959)
		(width 0.127)
		(layer "B.Cu")
		(net "NetC50_1")
	)
	(segment
		(start 137.3846 156.74792)
		(end 137.3846 152.2186)
		(width 0.127)
		(layer "B.Cu")
		(net "NetC51_1")
	)
	(arc
		(start 137.5411 157.757133)
		(mid 137.425268 157.583426)
		(end 137.3846 157.37864)
		(width 0.127)
		(layer "B.Cu")
		(net "NetC51_1")
	)
	(arc
		(start 137.521572 157.078598)
		(mid 137.420198 156.926882)
		(end 137.384601 156.74792)
		(width 0.127)
		(layer "B.Cu")
		(net "NetC51_1")
	)
	(segment
		(start 140.5596 156.98678)
		(end 140.5596 152.2186)
		(width 0.127)
		(layer "B.Cu")
		(net "NetC52_1")
	)
	(arc
		(start 140.54157 152.26214)
		(mid 140.546257 152.238578)
		(end 140.559603 152.218603)
		(width 0.127)
		(layer "B.Cu")
		(net "NetC52_1")
	)
	(arc
		(start 140.55961 156.98678)
		(mid 140.549725 157.036475)
		(end 140.521575 157.078605)
		(width 0.127)
		(layer "B.Cu")
		(net "NetC52_1")
	)
	(arc
		(start 140.5596 157.71406)
		(mid 140.554913 157.737622)
		(end 140.541567 157.757597)
		(width 0.127)
		(layer "B.Cu")
		(net "NetC52_1")
	)
	(segment
		(start 141.5756 156.94814)
		(end 141.5756 152.2186)
		(width 0.127)
		(layer "B.Cu")
		(net "NetC53_1")
	)
	(segment
		(start 141.54156 157.7576)
		(end 141.5756 157.72356)
		(width 0.2032)
		(layer "B.Cu")
		(net "NetC53_1")
	)
	(arc
		(start 141.5756 156.94814)
		(mid 141.561557 157.018741)
		(end 141.521564 157.078594)
		(width 0.127)
		(layer "B.Cu")
		(net "NetC53_1")
	)
	(arc
		(start 141.54156 152.30077)
		(mid 141.550406 152.256298)
		(end 141.575597 152.218597)
		(width 0.127)
		(layer "B.Cu")
		(net "NetC53_1")
	)
	(segment
		(start 77.1216 55.7162)
		(end 77.2216 55.6162)
		(width 0.2032)
		(layer "F.Cu")
		(net "NetD11_1")
	)
	(segment
		(start 77.2216 55.6162)
		(end 78.6716 55.6162)
		(width 0.2032)
		(layer "F.Cu")
		(net "NetD11_1")
	)
	(via
		(at 77.1216 55.7162)
		(size 0.4064)
		(drill 0.2032)
		(layers "F.Cu" "B.Cu")
		(net "NetD11_1")
	)
	(segment
		(start 78.3732 55.8428)
		(end 78.4482 55.8428)
		(width 0.2032)
		(layer "B.Cu")
		(net "NetD11_1")
	)
	(segment
		(start 78.7466 56.2162)
		(end 78.7466 56.1412)
		(width 0.2032)
		(layer "B.Cu")
		(net "NetD11_1")
	)
	(segment
		(start 77.1216 55.7162)
		(end 78.2466 55.7162)
		(width 0.2032)
		(layer "B.Cu")
		(net "NetD11_1")
	)
	(segment
		(start 78.2466 55.7162)
		(end 78.3732 55.8428)
		(width 0.2032)
		(layer "B.Cu")
		(net "NetD11_1")
	)
	(segment
		(start 78.4482 55.8428)
		(end 78.7466 56.1412)
		(width 0.2032)
		(layer "B.Cu")
		(net "NetD11_1")
	)
	(segment
		(start 122.0836 149.22907)
		(end 122.58681 148.72586)
		(width 0.2032)
		(layer "F.Cu")
		(net "NetP2_B17")
	)
	(segment
		(start 106.2466 143.5162)
		(end 108.2216 143.5162)
		(width 0.2032)
		(layer "F.Cu")
		(net "NetP2_B17")
	)
	(segment
		(start 122.58681 148.72586)
		(end 122.69206 148.72586)
		(width 0.2032)
		(layer "F.Cu")
		(net "NetP2_B17")
	)
	(segment
		(start 106.3466 143.3162)
		(end 106.39664 143.36624)
		(width 0.2032)
		(layer "F.Cu")
		(net "NetP2_B17")
	)
	(segment
		(start 129.3716 152.8786)
		(end 129.3716 148.75718)
		(width 0.2032)
		(layer "F.Cu")
		(net "NetP2_B17")
	)
	(segment
		(start 122.70172 148.7162)
		(end 129.35463 148.7162)
		(width 0.2032)
		(layer "F.Cu")
		(net "NetP2_B17")
	)
	(segment
		(start 128.52159 157.0786)
		(end 128.5716 157.02859)
		(width 0.2032)
		(layer "F.Cu")
		(net "NetP2_B17")
	)
	(segment
		(start 128.5716 157.02859)
		(end 128.5716 153.6786)
		(width 0.2032)
		(layer "F.Cu")
		(net "NetP2_B17")
	)
	(segment
		(start 122.69206 148.72586)
		(end 122.70172 148.7162)
		(width 0.2032)
		(layer "F.Cu")
		(net "NetP2_B17")
	)
	(segment
		(start 128.5716 153.6786)
		(end 129.3716 152.8786)
		(width 0.2032)
		(layer "F.Cu")
		(net "NetP2_B17")
	)
	(via
		(at 122.0836 149.22907)
		(size 0.4064)
		(drill 0.2032)
		(layers "F.Cu" "B.Cu")
		(net "NetP2_B17")
	)
	(via
		(at 108.2216 143.5162)
		(size 0.4064)
		(drill 0.2032)
		(layers "F.Cu" "B.Cu")
		(net "NetP2_B17")
	)
	(arc
		(start 129.354741 148.716304)
		(mid 129.367227 148.73507)
		(end 129.37161 148.75718)
		(width 0.2032)
		(layer "F.Cu")
		(net "NetP2_B17")
	)
	(arc
		(start 129.354634 148.716196)
		(mid 129.354687 148.71625)
		(end 129.354741 148.716303)
		(width 0.2032)
		(layer "F.Cu")
		(net "NetP2_B17")
	)
	(segment
		(start 119.7216 143.5162)
		(end 123.6216 147.4162)
		(width 0.2032)
		(layer "B.Cu")
		(net "NetP2_B17")
	)
	(segment
		(start 123.00873 149.22907)
		(end 123.6216 148.6162)
		(width 0.2032)
		(layer "B.Cu")
		(net "NetP2_B17")
	)
	(segment
		(start 123.6216 148.6162)
		(end 123.6216 147.4162)
		(width 0.2032)
		(layer "B.Cu")
		(net "NetP2_B17")
	)
	(segment
		(start 122.0836 149.22907)
		(end 123.00873 149.22907)
		(width 0.2032)
		(layer "B.Cu")
		(net "NetP2_B17")
	)
	(segment
		(start 108.2216 143.5162)
		(end 119.7216 143.5162)
		(width 0.2032)
		(layer "B.Cu")
		(net "NetP2_B17")
	)
	(segment
		(start 122.51321 148.29406)
		(end 129.39946 148.29406)
		(width 0.2032)
		(layer "F.Cu")
		(net "NetP2_B31")
	)
	(segment
		(start 129.8216 148.7162)
		(end 142.35257 148.7162)
		(width 0.2032)
		(layer "F.Cu")
		(net "NetP2_B31")
	)
	(segment
		(start 106.2466 144.6162)
		(end 108.03381 144.6162)
		(width 0.2032)
		(layer "F.Cu")
		(net "NetP2_B31")
	)
	(segment
		(start 142.35257 148.7162)
		(end 142.4716 148.83523)
		(width 0.2032)
		(layer "F.Cu")
		(net "NetP2_B31")
	)
	(segment
		(start 142.4716 156.53334)
		(end 142.4716 148.83523)
		(width 0.2032)
		(layer "F.Cu")
		(net "NetP2_B31")
	)
	(segment
		(start 142.54156 157.2623)
		(end 142.5916 157.21226)
		(width 0.2032)
		(layer "F.Cu")
		(net "NetP2_B31")
	)
	(segment
		(start 142.4716 156.53334)
		(end 142.52156 156.5833)
		(width 0.2032)
		(layer "F.Cu")
		(net "NetP2_B31")
	)
	(segment
		(start 129.39946 148.29406)
		(end 129.8216 148.7162)
		(width 0.2032)
		(layer "F.Cu")
		(net "NetP2_B31")
	)
	(via
		(at 122.51321 148.29406)
		(size 0.4064)
		(drill 0.2032)
		(layers "F.Cu" "B.Cu")
		(net "NetP2_B31")
	)
	(via
		(at 108.08482 144.56518)
		(size 0.4064)
		(drill 0.2032)
		(layers "F.Cu" "B.Cu")
		(net "NetP2_B31")
	)
	(segment
		(start 118.78433 144.56518)
		(end 122.51321 148.29406)
		(width 0.2032)
		(layer "B.Cu")
		(net "NetP2_B31")
	)
	(segment
		(start 108.08482 144.56518)
		(end 118.78433 144.56518)
		(width 0.2032)
		(layer "B.Cu")
		(net "NetP2_B31")
	)
	(segment
		(start 115.95572 90.2662)
		(end 115.98072 90.2662)
		(width 0.2032)
		(layer "F.Cu")
		(net "SENS_I2C_SDA")
	)
	(segment
		(start 115.14322 89.5162)
		(end 115.20572 89.5162)
		(width 0.2032)
		(layer "F.Cu")
		(net "SENS_I2C_SDA")
	)
	(segment
		(start 89.61944 90.02939)
		(end 89.61944 87.56371)
		(width 0.2032)
		(layer "F.Cu")
		(net "SENS_I2C_SDA")
	)
	(segment
		(start 172.2466 117.7162)
		(end 172.6982 118.1678)
		(width 0.2032)
		(layer "F.Cu")
		(net "SENS_I2C_SDA")
	)
	(segment
		(start 89.61944 87.56371)
		(end 91.38187 87.56371)
		(width 0.2032)
		(layer "F.Cu")
		(net "SENS_I2C_SDA")
	)
	(segment
		(start 81.92926 68.66847)
		(end 83.5116 68.66847)
		(width 0.2032)
		(layer "F.Cu")
		(net "SENS_I2C_SDA")
	)
	(segment
		(start 169.42457 96.22332)
		(end 169.42457 94.6162)
		(width 0.2032)
		(layer "F.Cu")
		(net "SENS_I2C_SDA")
	)
	(segment
		(start 172.7232 118.1678)
		(end 172.9216 118.3662)
		(width 0.2032)
		(layer "F.Cu")
		(net "SENS_I2C_SDA")
	)
	(segment
		(start 105.27869 89.44208)
		(end 105.27869 88.74208)
		(width 0.2032)
		(layer "F.Cu")
		(net "SENS_I2C_SDA")
	)
	(segment
		(start 171.2966 117.2912)
		(end 171.2966 116.4412)
		(width 0.2032)
		(layer "F.Cu")
		(net "SENS_I2C_SDA")
	)
	(segment
		(start 115.20572 89.5162)
		(end 115.95572 90.2662)
		(width 0.2032)
		(layer "F.Cu")
		(net "SENS_I2C_SDA")
	)
	(segment
		(start 172.6982 118.1678)
		(end 172.7232 118.1678)
		(width 0.2032)
		(layer "F.Cu")
		(net "SENS_I2C_SDA")
	)
	(segment
		(start 171.7216 117.7162)
		(end 172.2466 117.7162)
		(width 0.2032)
		(layer "F.Cu")
		(net "SENS_I2C_SDA")
	)
	(segment
		(start 104.9037 89.81708)
		(end 105.27869 89.44208)
		(width 0.2032)
		(layer "F.Cu")
		(net "SENS_I2C_SDA")
	)
	(segment
		(start 171.2966 117.2912)
		(end 171.7216 117.7162)
		(width 0.2032)
		(layer "F.Cu")
		(net "SENS_I2C_SDA")
	)
	(via
		(at 172.9216 118.3662)
		(size 0.4064)
		(drill 0.2032)
		(layers "F.Cu" "B.Cu")
		(net "SENS_I2C_SDA")
	)
	(via
		(at 81.92926 68.66847)
		(size 0.4064)
		(drill 0.2032)
		(layers "F.Cu" "B.Cu")
		(net "SENS_I2C_SDA")
	)
	(via
		(at 226.6216 76.5162)
		(size 0.4064)
		(drill 0.2032)
		(layers "F.Cu" "B.Cu")
		(net "SENS_I2C_SDA")
	)
	(via
		(at 104.9037 89.81708)
		(size 0.4064)
		(drill 0.2032)
		(layers "F.Cu" "B.Cu")
		(net "SENS_I2C_SDA")
	)
	(via
		(at 169.42457 96.22332)
		(size 0.4064)
		(drill 0.2032)
		(layers "F.Cu" "B.Cu")
		(net "SENS_I2C_SDA")
	)
	(via
		(at 179.1351 99.5114)
		(size 0.4064)
		(drill 0.2032)
		(layers "F.Cu" "B.Cu")
		(net "SENS_I2C_SDA")
	)
	(via
		(at 89.61944 90.02939)
		(size 0.4064)
		(drill 0.2032)
		(layers "F.Cu" "B.Cu")
		(tenting
			(front yes)
			(back yes)
		)
		(net "SENS_I2C_SDA")
	)
	(via
		(at 115.98072 90.2662)
		(size 0.4064)
		(drill 0.2032)
		(layers "F.Cu" "B.Cu")
		(net "SENS_I2C_SDA")
	)
	(segment
		(start 184.41214 109.13575)
		(end 185.8317 107.7162)
		(width 0.2032)
		(layer "B.Cu")
		(net "SENS_I2C_SDA")
	)
	(segment
		(start 225.61664 79.0162)
		(end 227.5216 79.0162)
		(width 0.2032)
		(layer "B.Cu")
		(net "SENS_I2C_SDA")
	)
	(segment
		(start 173.42 119.38912)
		(end 173.97728 119.9464)
		(width 0.2032)
		(layer "B.Cu")
		(net "SENS_I2C_SDA")
	)
	(segment
		(start 185.8317 107.7162)
		(end 199.3216 107.7162)
		(width 0.2032)
		(layer "B.Cu")
		(net "SENS_I2C_SDA")
	)
	(segment
		(start 226.20216 77.33564)
		(end 226.20216 76.93564)
		(width 0.2032)
		(layer "B.Cu")
		(net "SENS_I2C_SDA")
	)
	(segment
		(start 104.9037 89.81708)
		(end 104.9037 89.80642)
		(width 0.2032)
		(layer "B.Cu")
		(net "SENS_I2C_SDA")
	)
	(segment
		(start 226.20216 76.93564)
		(end 226.6216 76.5162)
		(width 0.2032)
		(layer "B.Cu")
		(net "SENS_I2C_SDA")
	)
	(segment
		(start 173.42 119.38912)
		(end 173.42 118.8646)
		(width 0.2032)
		(layer "B.Cu")
		(net "SENS_I2C_SDA")
	)
	(segment
		(start 103.6216 90.4162)
		(end 103.6216 89.30427)
		(width 0.2032)
		(layer "B.Cu")
		(net "SENS_I2C_SDA")
	)
	(segment
		(start 221.06633 85.97147)
		(end 221.06633 84.73844)
		(width 0.2032)
		(layer "B.Cu")
		(net "SENS_I2C_SDA")
	)
	(segment
		(start 179.1351 99.613)
		(end 181.5184 99.613)
		(width 0.2032)
		(layer "B.Cu")
		(net "SENS_I2C_SDA")
	)
	(segment
		(start 172.9216 118.3662)
		(end 173.42 118.8646)
		(width 0.2032)
		(layer "B.Cu")
		(net "SENS_I2C_SDA")
	)
	(segment
		(start 178.2518 116.3162)
		(end 179.2518 115.3162)
		(width 0.2032)
		(layer "B.Cu")
		(net "SENS_I2C_SDA")
	)
	(segment
		(start 103.6216 90.4162)
		(end 106.6216 93.4162)
		(width 0.2032)
		(layer "B.Cu")
		(net "SENS_I2C_SDA")
	)
	(segment
		(start 115.98072 92.45708)
		(end 115.98072 90.2662)
		(width 0.2032)
		(layer "B.Cu")
		(net "SENS_I2C_SDA")
	)
	(segment
		(start 228.4216 78.1162)
		(end 228.4216 77.73212)
		(width 0.2032)
		(layer "B.Cu")
		(net "SENS_I2C_SDA")
	)
	(segment
		(start 199.3216 107.7162)
		(end 221.06633 85.97147)
		(width 0.2032)
		(layer "B.Cu")
		(net "SENS_I2C_SDA")
	)
	(segment
		(start 218.40418 83.50434)
		(end 219.43346 83.50434)
		(width 0.2032)
		(layer "B.Cu")
		(net "SENS_I2C_SDA")
	)
	(segment
		(start 224.96478 77.97302)
		(end 225.56478 77.97302)
		(width 0.2032)
		(layer "B.Cu")
		(net "SENS_I2C_SDA")
	)
	(segment
		(start 115.0216 93.4162)
		(end 115.98072 92.45708)
		(width 0.2032)
		(layer "B.Cu")
		(net "SENS_I2C_SDA")
	)
	(segment
		(start 224.62439 81.18038)
		(end 224.62439 80.00844)
		(width 0.2032)
		(layer "B.Cu")
		(net "SENS_I2C_SDA")
	)
	(segment
		(start 227.80148 77.112)
		(end 228.4216 77.73212)
		(width 0.2032)
		(layer "B.Cu")
		(net "SENS_I2C_SDA")
	)
	(segment
		(start 173.97728 119.9464)
		(end 174.82759 119.9464)
		(width 0.2032)
		(layer "B.Cu")
		(net "SENS_I2C_SDA")
	)
	(segment
		(start 178.2518 116.52219)
		(end 178.2518 116.3162)
		(width 0.2032)
		(layer "B.Cu")
		(net "SENS_I2C_SDA")
	)
	(segment
		(start 224.62439 80.00844)
		(end 225.61664 79.0162)
		(width 0.2032)
		(layer "B.Cu")
		(net "SENS_I2C_SDA")
	)
	(segment
		(start 225.56478 77.97302)
		(end 226.20216 77.33564)
		(width 0.2032)
		(layer "B.Cu")
		(net "SENS_I2C_SDA")
	)
	(segment
		(start 103.74063 89.18524)
		(end 104.28251 89.18524)
		(width 0.2032)
		(layer "B.Cu")
		(net "SENS_I2C_SDA")
	)
	(segment
		(start 103.6216 89.30427)
		(end 103.74063 89.18524)
		(width 0.2032)
		(layer "B.Cu")
		(net "SENS_I2C_SDA")
	)
	(segment
		(start 184.3318 102.42639)
		(end 199.48213 102.42639)
		(width 0.2032)
		(layer "B.Cu")
		(net "SENS_I2C_SDA")
	)
	(segment
		(start 179.2518 115.3162)
		(end 182.20906 115.3162)
		(width 0.2032)
		(layer "B.Cu")
		(net "SENS_I2C_SDA")
	)
	(segment
		(start 226.6216 76.5162)
		(end 227.2174 77.112)
		(width 0.2032)
		(layer "B.Cu")
		(net "SENS_I2C_SDA")
	)
	(segment
		(start 199.48213 102.42639)
		(end 218.40418 83.50434)
		(width 0.2032)
		(layer "B.Cu")
		(net "SENS_I2C_SDA")
	)
	(segment
		(start 174.82759 119.9464)
		(end 178.2518 116.52219)
		(width 0.2032)
		(layer "B.Cu")
		(net "SENS_I2C_SDA")
	)
	(segment
		(start 106.6216 93.4162)
		(end 115.0216 93.4162)
		(width 0.2032)
		(layer "B.Cu")
		(net "SENS_I2C_SDA")
	)
	(segment
		(start 181.5184 99.613)
		(end 184.3318 102.42639)
		(width 0.2032)
		(layer "B.Cu")
		(net "SENS_I2C_SDA")
	)
	(segment
		(start 104.28251 89.18524)
		(end 104.9037 89.80642)
		(width 0.2032)
		(layer "B.Cu")
		(net "SENS_I2C_SDA")
	)
	(segment
		(start 227.5216 79.0162)
		(end 228.4216 78.1162)
		(width 0.2032)
		(layer "B.Cu")
		(net "SENS_I2C_SDA")
	)
	(segment
		(start 179.1351 99.613)
		(end 179.1351 99.5114)
		(width 0.2032)
		(layer "B.Cu")
		(net "SENS_I2C_SDA")
	)
	(segment
		(start 184.41214 113.11311)
		(end 184.41214 109.13575)
		(width 0.2032)
		(layer "B.Cu")
		(net "SENS_I2C_SDA")
	)
	(segment
		(start 227.2174 77.112)
		(end 227.80148 77.112)
		(width 0.2032)
		(layer "B.Cu")
		(net "SENS_I2C_SDA")
	)
	(segment
		(start 182.20906 115.3162)
		(end 184.41214 113.11311)
		(width 0.2032)
		(layer "B.Cu")
		(net "SENS_I2C_SDA")
	)
	(segment
		(start 221.06633 84.73844)
		(end 224.62439 81.18038)
		(width 0.2032)
		(layer "B.Cu")
		(net "SENS_I2C_SDA")
	)
	(segment
		(start 219.43346 83.50434)
		(end 224.96478 77.97302)
		(width 0.2032)
		(layer "B.Cu")
		(net "SENS_I2C_SDA")
	)
	(segment
		(start 84.27387 68.66847)
		(end 89.61944 74.01404)
		(width 0.2032)
		(layer "In3.Cu")
		(net "SENS_I2C_SDA")
	)
	(segment
		(start 81.92926 68.66847)
		(end 84.27387 68.66847)
		(width 0.2032)
		(layer "In3.Cu")
		(net "SENS_I2C_SDA")
	)
	(segment
		(start 173.05508 95.48272)
		(end 177.08377 99.5114)
		(width 0.2032)
		(layer "In3.Cu")
		(net "SENS_I2C_SDA")
	)
	(segment
		(start 90.46358 89.18524)
		(end 104.28251 89.18524)
		(width 0.2032)
		(layer "In3.Cu")
		(net "SENS_I2C_SDA")
	)
	(segment
		(start 168.13318 98.44151)
		(end 169.42457 97.15012)
		(width 0.2032)
		(layer "In3.Cu")
		(net "SENS_I2C_SDA")
	)
	(segment
		(start 115.98072 89.05708)
		(end 117.1216 87.9162)
		(width 0.2032)
		(layer "In3.Cu")
		(net "SENS_I2C_SDA")
	)
	(segment
		(start 89.61944 90.02939)
		(end 90.46358 89.18524)
		(width 0.2032)
		(layer "In3.Cu")
		(net "SENS_I2C_SDA")
	)
	(segment
		(start 135.8854 94.08)
		(end 135.8854 84.12947)
		(width 0.2032)
		(layer "In3.Cu")
		(net "SENS_I2C_SDA")
	)
	(segment
		(start 135.8854 94.08)
		(end 136.4216 94.6162)
		(width 0.2032)
		(layer "In3.Cu")
		(net "SENS_I2C_SDA")
	)
	(segment
		(start 173.05508 95.48272)
		(end 173.05508 95.48271)
		(width 0.2032)
		(layer "In3.Cu")
		(net "SENS_I2C_SDA")
	)
	(segment
		(start 145.4856 97.6802)
		(end 152.00764 97.6802)
		(width 0.2032)
		(layer "In3.Cu")
		(net "SENS_I2C_SDA")
	)
	(segment
		(start 104.28251 89.18524)
		(end 104.9037 89.80642)
		(width 0.2032)
		(layer "In3.Cu")
		(net "SENS_I2C_SDA")
	)
	(segment
		(start 129.4613 87.9162)
		(end 133.77391 83.60359)
		(width 0.2032)
		(layer "In3.Cu")
		(net "SENS_I2C_SDA")
	)
	(segment
		(start 153.57164 96.1162)
		(end 161.3216 96.1162)
		(width 0.2032)
		(layer "In3.Cu")
		(net "SENS_I2C_SDA")
	)
	(segment
		(start 163.64691 98.44151)
		(end 168.13318 98.44151)
		(width 0.2032)
		(layer "In3.Cu")
		(net "SENS_I2C_SDA")
	)
	(segment
		(start 177.08377 99.5114)
		(end 179.1351 99.5114)
		(width 0.2032)
		(layer "In3.Cu")
		(net "SENS_I2C_SDA")
	)
	(segment
		(start 133.77391 83.60359)
		(end 135.35952 83.60359)
		(width 0.2032)
		(layer "In3.Cu")
		(net "SENS_I2C_SDA")
	)
	(segment
		(start 115.98072 90.2662)
		(end 115.98072 89.05708)
		(width 0.2032)
		(layer "In3.Cu")
		(net "SENS_I2C_SDA")
	)
	(segment
		(start 117.1216 87.9162)
		(end 129.4613 87.9162)
		(width 0.2032)
		(layer "In3.Cu")
		(net "SENS_I2C_SDA")
	)
	(segment
		(start 152.00764 97.6802)
		(end 153.57164 96.1162)
		(width 0.2032)
		(layer "In3.Cu")
		(net "SENS_I2C_SDA")
	)
	(segment
		(start 161.3216 96.1162)
		(end 163.64691 98.44151)
		(width 0.2032)
		(layer "In3.Cu")
		(net "SENS_I2C_SDA")
	)
	(segment
		(start 104.9037 89.81708)
		(end 104.9037 89.80642)
		(width 0.2032)
		(layer "In3.Cu")
		(net "SENS_I2C_SDA")
	)
	(segment
		(start 172.95837 95.386)
		(end 173.05508 95.48271)
		(width 0.2032)
		(layer "In3.Cu")
		(net "SENS_I2C_SDA")
	)
	(segment
		(start 169.42457 97.15012)
		(end 169.42457 96.22332)
		(width 0.2032)
		(layer "In3.Cu")
		(net "SENS_I2C_SDA")
	)
	(segment
		(start 89.61944 90.02939)
		(end 89.61944 74.01404)
		(width 0.2032)
		(layer "In3.Cu")
		(net "SENS_I2C_SDA")
	)
	(segment
		(start 135.35952 83.60359)
		(end 135.8854 84.12947)
		(width 0.2032)
		(layer "In3.Cu")
		(net "SENS_I2C_SDA")
	)
	(segment
		(start 136.4216 94.6162)
		(end 142.4216 94.6162)
		(width 0.2032)
		(layer "In3.Cu")
		(net "SENS_I2C_SDA")
	)
	(segment
		(start 170.26189 95.386)
		(end 172.95837 95.386)
		(width 0.2032)
		(layer "In3.Cu")
		(net "SENS_I2C_SDA")
	)
	(segment
		(start 169.42457 96.22332)
		(end 170.26189 95.386)
		(width 0.2032)
		(layer "In3.Cu")
		(net "SENS_I2C_SDA")
	)
	(segment
		(start 142.4216 94.6162)
		(end 145.4856 97.6802)
		(width 0.2032)
		(layer "In3.Cu")
		(net "SENS_I2C_SDA")
	)
	(segment
		(start 172.4131 116.046)
		(end 172.4131 115.6396)
		(width 0.2032)
		(layer "F.Cu")
		(net "SENS_I2C_SCL")
	)
	(segment
		(start 90.20686 90.19231)
		(end 90.20686 88.06371)
		(width 0.2032)
		(layer "F.Cu")
		(net "SENS_I2C_SCL")
	)
	(segment
		(start 104.62869 89.29208)
		(end 104.62869 88.74208)
		(width 0.2032)
		(layer "F.Cu")
		(net "SENS_I2C_SCL")
	)
	(segment
		(start 172.1466 115.5912)
		(end 172.3647 115.5912)
		(width 0.2032)
		(layer "F.Cu")
		(net "SENS_I2C_SCL")
	)
	(segment
		(start 170.69457 96.3162)
		(end 170.69457 94.6162)
		(width 0.2032)
		(layer "F.Cu")
		(net "SENS_I2C_SCL")
	)
	(segment
		(start 104.20369 89.71708)
		(end 104.62869 89.29208)
		(width 0.2032)
		(layer "F.Cu")
		(net "SENS_I2C_SCL")
	)
	(segment
		(start 174.1216 118.3912)
		(end 174.1216 117.7545)
		(width 0.2032)
		(layer "F.Cu")
		(net "SENS_I2C_SCL")
	)
	(segment
		(start 114.35413 90.0396)
		(end 114.35413 89.6021)
		(width 0.2032)
		(layer "F.Cu")
		(net "SENS_I2C_SCL")
	)
	(segment
		(start 170.69457 96.3162)
		(end 170.7216 96.3162)
		(width 0.2032)
		(layer "F.Cu")
		(net "SENS_I2C_SCL")
	)
	(segment
		(start 114.35413 90.0396)
		(end 114.78072 90.4662)
		(width 0.2032)
		(layer "F.Cu")
		(net "SENS_I2C_SCL")
	)
	(segment
		(start 114.78072 90.4662)
		(end 115.18072 90.4662)
		(width 0.2032)
		(layer "F.Cu")
		(net "SENS_I2C_SCL")
	)
	(segment
		(start 81.9216 69.93847)
		(end 83.5116 69.93847)
		(width 0.2032)
		(layer "F.Cu")
		(net "SENS_I2C_SCL")
	)
	(segment
		(start 90.20686 88.06371)
		(end 91.38187 88.06371)
		(width 0.2032)
		(layer "F.Cu")
		(net "SENS_I2C_SCL")
	)
	(segment
		(start 115.18072 90.4662)
		(end 115.38072 90.6662)
		(width 0.2032)
		(layer "F.Cu")
		(net "SENS_I2C_SCL")
	)
	(segment
		(start 174.1216 118.4162)
		(end 174.1216 118.3912)
		(width 0.2032)
		(layer "F.Cu")
		(net "SENS_I2C_SCL")
	)
	(segment
		(start 227.9266 77.84778)
		(end 227.9266 76.3162)
		(width 0.2032)
		(layer "F.Cu")
		(net "SENS_I2C_SCL")
	)
	(segment
		(start 172.4131 116.046)
		(end 174.1216 117.7545)
		(width 0.2032)
		(layer "F.Cu")
		(net "SENS_I2C_SCL")
	)
	(segment
		(start 114.33072 89.5787)
		(end 114.35413 89.6021)
		(width 0.2032)
		(layer "F.Cu")
		(net "SENS_I2C_SCL")
	)
	(segment
		(start 172.3647 115.5912)
		(end 172.4131 115.6396)
		(width 0.2032)
		(layer "F.Cu")
		(net "SENS_I2C_SCL")
	)
	(via
		(at 115.38072 90.6662)
		(size 0.4064)
		(drill 0.2032)
		(layers "F.Cu" "B.Cu")
		(net "SENS_I2C_SCL")
	)
	(via
		(at 227.9266 77.84778)
		(size 0.4064)
		(drill 0.2032)
		(layers "F.Cu" "B.Cu")
		(net "SENS_I2C_SCL")
	)
	(via
		(at 178.75026 100.00935)
		(size 0.4064)
		(drill 0.2032)
		(layers "F.Cu" "B.Cu")
		(net "SENS_I2C_SCL")
	)
	(via
		(at 104.20369 89.71708)
		(size 0.4064)
		(drill 0.2032)
		(layers "F.Cu" "B.Cu")
		(net "SENS_I2C_SCL")
	)
	(via
		(at 90.20686 90.19231)
		(size 0.4064)
		(drill 0.2032)
		(layers "F.Cu" "B.Cu")
		(tenting
			(front yes)
			(back yes)
		)
		(net "SENS_I2C_SCL")
	)
	(via
		(at 170.7216 96.3162)
		(size 0.4064)
		(drill 0.2032)
		(layers "F.Cu" "B.Cu")
		(net "SENS_I2C_SCL")
	)
	(via
		(at 174.1216 118.4162)
		(size 0.4064)
		(drill 0.2032)
		(layers "F.Cu" "B.Cu")
		(net "SENS_I2C_SCL")
	)
	(via
		(at 81.9216 69.93847)
		(size 0.4064)
		(drill 0.2032)
		(layers "F.Cu" "B.Cu")
		(net "SENS_I2C_SCL")
	)
	(segment
		(start 178.80633 99.9432)
		(end 181.38163 99.9432)
		(width 0.2032)
		(layer "B.Cu")
		(net "SENS_I2C_SCL")
	)
	(segment
		(start 184.08194 112.97634)
		(end 184.08194 108.99898)
		(width 0.2032)
		(layer "B.Cu")
		(net "SENS_I2C_SCL")
	)
	(segment
		(start 219.57023 83.83454)
		(end 225.10155 78.30322)
		(width 0.2032)
		(layer "B.Cu")
		(net "SENS_I2C_SCL")
	)
	(segment
		(start 179.11503 114.986)
		(end 182.07229 114.986)
		(width 0.2032)
		(layer "B.Cu")
		(net "SENS_I2C_SCL")
	)
	(segment
		(start 115.38072 92.17437)
		(end 115.38072 90.6662)
		(width 0.2032)
		(layer "B.Cu")
		(net "SENS_I2C_SCL")
	)
	(segment
		(start 227.08838 78.686)
		(end 227.9266 77.84778)
		(width 0.2032)
		(layer "B.Cu")
		(net "SENS_I2C_SCL")
	)
	(segment
		(start 199.18483 107.386)
		(end 220.73613 85.8347)
		(width 0.2032)
		(layer "B.Cu")
		(net "SENS_I2C_SCL")
	)
	(segment
		(start 177.9216 116.38542)
		(end 177.9216 116.17943)
		(width 0.2032)
		(layer "B.Cu")
		(net "SENS_I2C_SCL")
	)
	(segment
		(start 220.73613 85.8347)
		(end 220.73613 84.60167)
		(width 0.2032)
		(layer "B.Cu")
		(net "SENS_I2C_SCL")
	)
	(segment
		(start 225.70155 78.30322)
		(end 226.15699 77.84778)
		(width 0.2032)
		(layer "B.Cu")
		(net "SENS_I2C_SCL")
	)
	(segment
		(start 181.38163 99.9432)
		(end 184.19503 102.75659)
		(width 0.2032)
		(layer "B.Cu")
		(net "SENS_I2C_SCL")
	)
	(segment
		(start 174.69082 119.6162)
		(end 177.9216 116.38542)
		(width 0.2032)
		(layer "B.Cu")
		(net "SENS_I2C_SCL")
	)
	(segment
		(start 104.20369 89.72773)
		(end 104.20369 89.71708)
		(width 0.2032)
		(layer "B.Cu")
		(net "SENS_I2C_SCL")
	)
	(segment
		(start 174.11405 119.6162)
		(end 174.69082 119.6162)
		(width 0.2032)
		(layer "B.Cu")
		(net "SENS_I2C_SCL")
	)
	(segment
		(start 224.29419 79.87167)
		(end 225.47987 78.686)
		(width 0.2032)
		(layer "B.Cu")
		(net "SENS_I2C_SCL")
	)
	(segment
		(start 178.75793 99.9916)
		(end 178.80633 99.9432)
		(width 0.2032)
		(layer "B.Cu")
		(net "SENS_I2C_SCL")
	)
	(segment
		(start 220.73613 84.60167)
		(end 224.29419 81.04361)
		(width 0.2032)
		(layer "B.Cu")
		(net "SENS_I2C_SCL")
	)
	(segment
		(start 226.15699 77.84778)
		(end 227.9266 77.84778)
		(width 0.2032)
		(layer "B.Cu")
		(net "SENS_I2C_SCL")
	)
	(segment
		(start 173.7502 119.25235)
		(end 174.11405 119.6162)
		(width 0.2032)
		(layer "B.Cu")
		(net "SENS_I2C_SCL")
	)
	(segment
		(start 173.7502 118.7876)
		(end 174.1216 118.4162)
		(width 0.2032)
		(layer "B.Cu")
		(net "SENS_I2C_SCL")
	)
	(segment
		(start 182.07229 114.986)
		(end 184.08194 112.97634)
		(width 0.2032)
		(layer "B.Cu")
		(net "SENS_I2C_SCL")
	)
	(segment
		(start 185.69493 107.386)
		(end 199.18483 107.386)
		(width 0.2032)
		(layer "B.Cu")
		(net "SENS_I2C_SCL")
	)
	(segment
		(start 218.54095 83.83454)
		(end 219.57023 83.83454)
		(width 0.2032)
		(layer "B.Cu")
		(net "SENS_I2C_SCL")
	)
	(segment
		(start 104.20369 89.72773)
		(end 107.49216 93.0162)
		(width 0.2032)
		(layer "B.Cu")
		(net "SENS_I2C_SCL")
	)
	(segment
		(start 184.08194 108.99898)
		(end 185.69493 107.386)
		(width 0.2032)
		(layer "B.Cu")
		(net "SENS_I2C_SCL")
	)
	(segment
		(start 184.19503 102.75659)
		(end 199.6189 102.75659)
		(width 0.2032)
		(layer "B.Cu")
		(net "SENS_I2C_SCL")
	)
	(segment
		(start 114.53889 93.0162)
		(end 115.38072 92.17437)
		(width 0.2032)
		(layer "B.Cu")
		(net "SENS_I2C_SCL")
	)
	(segment
		(start 177.9216 116.17943)
		(end 179.11503 114.986)
		(width 0.2032)
		(layer "B.Cu")
		(net "SENS_I2C_SCL")
	)
	(segment
		(start 225.10155 78.30322)
		(end 225.70155 78.30322)
		(width 0.2032)
		(layer "B.Cu")
		(net "SENS_I2C_SCL")
	)
	(segment
		(start 199.6189 102.75659)
		(end 218.54095 83.83454)
		(width 0.2032)
		(layer "B.Cu")
		(net "SENS_I2C_SCL")
	)
	(segment
		(start 225.47987 78.686)
		(end 227.08838 78.686)
		(width 0.2032)
		(layer "B.Cu")
		(net "SENS_I2C_SCL")
	)
	(segment
		(start 178.75026 100.00935)
		(end 178.75793 100.00168)
		(width 0.2032)
		(layer "B.Cu")
		(net "SENS_I2C_SCL")
	)
	(segment
		(start 224.29419 81.04361)
		(end 224.29419 79.87167)
		(width 0.2032)
		(layer "B.Cu")
		(net "SENS_I2C_SCL")
	)
	(segment
		(start 178.75793 100.00168)
		(end 178.75793 99.9916)
		(width 0.2032)
		(layer "B.Cu")
		(net "SENS_I2C_SCL")
	)
	(segment
		(start 173.7502 119.25235)
		(end 173.7502 118.7876)
		(width 0.2032)
		(layer "B.Cu")
		(net "SENS_I2C_SCL")
	)
	(segment
		(start 107.49216 93.0162)
		(end 114.53889 93.0162)
		(width 0.2032)
		(layer "B.Cu")
		(net "SENS_I2C_SCL")
	)
	(segment
		(start 115.41252 90.698)
		(end 116.15958 90.698)
		(width 0.2032)
		(layer "In3.Cu")
		(net "SENS_I2C_SCL")
	)
	(segment
		(start 133.5216 84.32287)
		(end 133.56272 84.32287)
		(width 0.2032)
		(layer "In3.Cu")
		(net "SENS_I2C_SCL")
	)
	(segment
		(start 170.7216 97.6162)
		(end 170.7216 96.3162)
		(width 0.2032)
		(layer "In3.Cu")
		(net "SENS_I2C_SCL")
	)
	(segment
		(start 144.89784 98.06585)
		(end 152.29018 98.06585)
		(width 0.2032)
		(layer "In3.Cu")
		(net "SENS_I2C_SCL")
	)
	(segment
		(start 118.74031 88.2662)
		(end 119.3821 88.908)
		(width 0.2032)
		(layer "In3.Cu")
		(net "SENS_I2C_SCL")
	)
	(segment
		(start 177.11475 100.00935)
		(end 178.75026 100.00935)
		(width 0.2032)
		(layer "In3.Cu")
		(net "SENS_I2C_SCL")
	)
	(segment
		(start 157.61883 97.3162)
		(end 158.34149 96.59354)
		(width 0.2032)
		(layer "In3.Cu")
		(net "SENS_I2C_SCL")
	)
	(segment
		(start 133.56272 84.32287)
		(end 133.9518 83.93379)
		(width 0.2032)
		(layer "In3.Cu")
		(net "SENS_I2C_SCL")
	)
	(segment
		(start 136.28669 94.94826)
		(end 141.78025 94.94826)
		(width 0.2032)
		(layer "In3.Cu")
		(net "SENS_I2C_SCL")
	)
	(segment
		(start 152.29018 98.06585)
		(end 153.76249 96.59354)
		(width 0.2032)
		(layer "In3.Cu")
		(net "SENS_I2C_SCL")
	)
	(segment
		(start 155.5216 97.3162)
		(end 157.61883 97.3162)
		(width 0.2032)
		(layer "In3.Cu")
		(net "SENS_I2C_SCL")
	)
	(segment
		(start 154.79894 96.59354)
		(end 155.5216 97.3162)
		(width 0.2032)
		(layer "In3.Cu")
		(net "SENS_I2C_SCL")
	)
	(segment
		(start 169.56234 98.77545)
		(end 170.7216 97.6162)
		(width 0.2032)
		(layer "In3.Cu")
		(net "SENS_I2C_SCL")
	)
	(segment
		(start 170.528 95.7162)
		(end 172.8216 95.7162)
		(width 0.2032)
		(layer "In3.Cu")
		(net "SENS_I2C_SCL")
	)
	(segment
		(start 90.20686 90.19231)
		(end 90.82115 89.57803)
		(width 0.2032)
		(layer "In3.Cu")
		(net "SENS_I2C_SCL")
	)
	(segment
		(start 116.41554 90.44204)
		(end 116.41554 89.42073)
		(width 0.2032)
		(layer "In3.Cu")
		(net "SENS_I2C_SCL")
	)
	(segment
		(start 89.24063 90.60978)
		(end 89.78939 90.60978)
		(width 0.2032)
		(layer "In3.Cu")
		(net "SENS_I2C_SCL")
	)
	(segment
		(start 117.57006 88.2662)
		(end 118.74031 88.2662)
		(width 0.2032)
		(layer "In3.Cu")
		(net "SENS_I2C_SCL")
	)
	(segment
		(start 89.78939 90.60978)
		(end 90.20686 90.19231)
		(width 0.2032)
		(layer "In3.Cu")
		(net "SENS_I2C_SCL")
	)
	(segment
		(start 135.5552 94.21677)
		(end 135.5552 84.26624)
		(width 0.2032)
		(layer "In3.Cu")
		(net "SENS_I2C_SCL")
	)
	(segment
		(start 170.528 96.06761)
		(end 170.528 95.7162)
		(width 0.2032)
		(layer "In3.Cu")
		(net "SENS_I2C_SCL")
	)
	(segment
		(start 172.8216 95.7162)
		(end 177.11475 100.00935)
		(width 0.2032)
		(layer "In3.Cu")
		(net "SENS_I2C_SCL")
	)
	(segment
		(start 89.1216 90.49075)
		(end 89.24063 90.60978)
		(width 0.2032)
		(layer "In3.Cu")
		(net "SENS_I2C_SCL")
	)
	(segment
		(start 170.528 96.06761)
		(end 170.7216 96.26121)
		(width 0.2032)
		(layer "In3.Cu")
		(net "SENS_I2C_SCL")
	)
	(segment
		(start 116.15958 90.698)
		(end 116.41554 90.44204)
		(width 0.2032)
		(layer "In3.Cu")
		(net "SENS_I2C_SCL")
	)
	(segment
		(start 128.93647 88.908)
		(end 133.5216 84.32287)
		(width 0.2032)
		(layer "In3.Cu")
		(net "SENS_I2C_SCL")
	)
	(segment
		(start 141.78025 94.94826)
		(end 144.89784 98.06585)
		(width 0.2032)
		(layer "In3.Cu")
		(net "SENS_I2C_SCL")
	)
	(segment
		(start 115.38072 90.6662)
		(end 115.41252 90.698)
		(width 0.2032)
		(layer "In3.Cu")
		(net "SENS_I2C_SCL")
	)
	(segment
		(start 135.22275 83.93379)
		(end 135.5552 84.26624)
		(width 0.2032)
		(layer "In3.Cu")
		(net "SENS_I2C_SCL")
	)
	(segment
		(start 158.34149 96.59354)
		(end 161.09894 96.59354)
		(width 0.2032)
		(layer "In3.Cu")
		(net "SENS_I2C_SCL")
	)
	(segment
		(start 93.00375 89.57803)
		(end 93.1428 89.71708)
		(width 0.2032)
		(layer "In3.Cu")
		(net "SENS_I2C_SCL")
	)
	(segment
		(start 161.09894 96.59354)
		(end 163.28085 98.77545)
		(width 0.2032)
		(layer "In3.Cu")
		(net "SENS_I2C_SCL")
	)
	(segment
		(start 90.82115 89.57803)
		(end 93.00375 89.57803)
		(width 0.2032)
		(layer "In3.Cu")
		(net "SENS_I2C_SCL")
	)
	(segment
		(start 170.7216 96.3162)
		(end 170.7216 96.26121)
		(width 0.2032)
		(layer "In3.Cu")
		(net "SENS_I2C_SCL")
	)
	(segment
		(start 89.1216 90.49075)
		(end 89.1216 74.3162)
		(width 0.2032)
		(layer "In3.Cu")
		(net "SENS_I2C_SCL")
	)
	(segment
		(start 116.41554 89.42073)
		(end 117.57006 88.2662)
		(width 0.2032)
		(layer "In3.Cu")
		(net "SENS_I2C_SCL")
	)
	(segment
		(start 163.28085 98.77545)
		(end 169.56234 98.77545)
		(width 0.2032)
		(layer "In3.Cu")
		(net "SENS_I2C_SCL")
	)
	(segment
		(start 84.74387 69.93847)
		(end 89.1216 74.3162)
		(width 0.2032)
		(layer "In3.Cu")
		(net "SENS_I2C_SCL")
	)
	(segment
		(start 133.9518 83.93379)
		(end 135.22275 83.93379)
		(width 0.2032)
		(layer "In3.Cu")
		(net "SENS_I2C_SCL")
	)
	(segment
		(start 119.3821 88.908)
		(end 128.93647 88.908)
		(width 0.2032)
		(layer "In3.Cu")
		(net "SENS_I2C_SCL")
	)
	(segment
		(start 93.1428 89.71708)
		(end 104.20369 89.71708)
		(width 0.2032)
		(layer "In3.Cu")
		(net "SENS_I2C_SCL")
	)
	(segment
		(start 135.5552 94.21677)
		(end 136.28669 94.94826)
		(width 0.2032)
		(layer "In3.Cu")
		(net "SENS_I2C_SCL")
	)
	(segment
		(start 81.9216 69.93847)
		(end 84.74387 69.93847)
		(width 0.2032)
		(layer "In3.Cu")
		(net "SENS_I2C_SCL")
	)
	(segment
		(start 153.76249 96.59354)
		(end 154.79894 96.59354)
		(width 0.2032)
		(layer "In3.Cu")
		(net "SENS_I2C_SCL")
	)
	(segment
		(start 96.82374 80.4162)
		(end 97.0716 80.4162)
		(width 0.254)
		(layer "F.Cu")
		(net "NetD4_1")
	)
	(segment
		(start 97.0716 80.4162)
		(end 97.0716 78.5162)
		(width 0.254)
		(layer "F.Cu")
		(net "NetD4_1")
	)
	(segment
		(start 133.54158 157.7576)
		(end 133.5746 157.72458)
		(width 0.2032)
		(layer "B.Cu")
		(net "NetC49_1")
	)
	(segment
		(start 133.5746 156.9506)
		(end 133.5746 152.2186)
		(width 0.127)
		(layer "B.Cu")
		(net "NetC49_1")
	)
	(arc
		(start 133.5746 157.67788)
		(mid 133.566018 157.721024)
		(end 133.541579 157.757599)
		(width 0.127)
		(layer "B.Cu")
		(net "NetC49_1")
	)
	(arc
		(start 133.5746 156.9506)
		(mid 133.560821 157.019873)
		(end 133.52158 157.0786)
		(width 0.127)
		(layer "B.Cu")
		(net "NetC49_1")
	)
	(segment
		(start 153.19535 98.46434)
		(end 153.19535 98.39099)
		(width 0.2032)
		(layer "F.Cu")
		(net "MAC_USB_PWR")
	)
	(segment
		(start 153.48072 98.25708)
		(end 154.3216 97.4162)
		(width 0.2032)
		(layer "F.Cu")
		(net "MAC_USB_PWR")
	)
	(segment
		(start 153.04905 98.61065)
		(end 153.19535 98.46434)
		(width 0.2032)
		(layer "F.Cu")
		(net "MAC_USB_PWR")
	)
	(segment
		(start 129.25657 115.74091)
		(end 130.49133 115.74091)
		(width 0.2032)
		(layer "F.Cu")
		(net "MAC_USB_PWR")
	)
	(segment
		(start 153.04905 99.26063)
		(end 153.04905 98.61065)
		(width 0.2032)
		(layer "F.Cu")
		(net "MAC_USB_PWR")
	)
	(segment
		(start 153.19535 98.39099)
		(end 153.32927 98.25708)
		(width 0.2032)
		(layer "F.Cu")
		(net "MAC_USB_PWR")
	)
	(segment
		(start 130.49133 115.74091)
		(end 130.76661 116.0162)
		(width 0.2032)
		(layer "F.Cu")
		(net "MAC_USB_PWR")
	)
	(segment
		(start 153.32927 98.25708)
		(end 153.48072 98.25708)
		(width 0.2032)
		(layer "F.Cu")
		(net "MAC_USB_PWR")
	)
	(segment
		(start 130.76661 116.0162)
		(end 130.8216 116.0162)
		(width 0.2032)
		(layer "F.Cu")
		(net "MAC_USB_PWR")
	)
	(via
		(at 130.8216 116.0162)
		(size 0.4064)
		(drill 0.2032)
		(layers "F.Cu" "B.Cu")
		(net "MAC_USB_PWR")
	)
	(via
		(at 154.3216 97.4162)
		(size 0.4064)
		(drill 0.2032)
		(layers "F.Cu" "B.Cu")
		(tenting
			(front yes)
			(back yes)
		)
		(net "MAC_USB_PWR")
	)
	(segment
		(start 131.9216 116.1162)
		(end 132.63631 115.40149)
		(width 0.2032)
		(layer "In2.Cu")
		(net "MAC_USB_PWR")
	)
	(segment
		(start 130.8216 116.0162)
		(end 131.34909 116.0162)
		(width 0.2032)
		(layer "In2.Cu")
		(net "MAC_USB_PWR")
	)
	(segment
		(start 153.67195 98.06585)
		(end 154.3216 97.4162)
		(width 0.2032)
		(layer "In2.Cu")
		(net "MAC_USB_PWR")
	)
	(segment
		(start 132.63631 115.40149)
		(end 132.63631 114.61916)
		(width 0.2032)
		(layer "In2.Cu")
		(net "MAC_USB_PWR")
	)
	(segment
		(start 132.63631 114.61916)
		(end 134.36789 112.88758)
		(width 0.2032)
		(layer "In2.Cu")
		(net "MAC_USB_PWR")
	)
	(segment
		(start 134.36789 107.76991)
		(end 144.07195 98.06585)
		(width 0.2032)
		(layer "In2.Cu")
		(net "MAC_USB_PWR")
	)
	(segment
		(start 144.07195 98.06585)
		(end 153.67195 98.06585)
		(width 0.2032)
		(layer "In2.Cu")
		(net "MAC_USB_PWR")
	)
	(segment
		(start 131.34909 116.0162)
		(end 131.44909 116.1162)
		(width 0.2032)
		(layer "In2.Cu")
		(net "MAC_USB_PWR")
	)
	(segment
		(start 134.36789 112.88758)
		(end 134.36789 107.76991)
		(width 0.2032)
		(layer "In2.Cu")
		(net "MAC_USB_PWR")
	)
	(segment
		(start 131.44909 116.1162)
		(end 131.9216 116.1162)
		(width 0.2032)
		(layer "In2.Cu")
		(net "MAC_USB_PWR")
	)
	(segment
		(start 130.2104 115.20951)
		(end 130.58344 114.83647)
		(width 0.2032)
		(layer "F.Cu")
		(net "MAC_USB-")
	)
	(segment
		(start 129.27997 115.20951)
		(end 130.2104 115.20951)
		(width 0.2032)
		(layer "F.Cu")
		(net "MAC_USB-")
	)
	(segment
		(start 169.4216 97.87119)
		(end 169.54889 97.99848)
		(width 0.2032)
		(layer "F.Cu")
		(net "MAC_USB-")
	)
	(segment
		(start 169.4216 97.87119)
		(end 169.4216 97.8162)
		(width 0.2032)
		(layer "F.Cu")
		(net "MAC_USB-")
	)
	(segment
		(start 169.54889 99.26063)
		(end 169.54889 97.99848)
		(width 0.2032)
		(layer "F.Cu")
		(net "MAC_USB-")
	)
	(segment
		(start 129.25657 115.23291)
		(end 129.27997 115.20951)
		(width 0.2032)
		(layer "F.Cu")
		(net "MAC_USB-")
	)
	(via
		(at 130.58344 114.83647)
		(size 0.4064)
		(drill 0.2032)
		(layers "F.Cu" "B.Cu")
		(locked yes)
		(net "MAC_USB-")
	)
	(via
		(at 169.4216 97.8162)
		(size 0.4064)
		(drill 0.2032)
		(layers "F.Cu" "B.Cu")
		(tenting
			(front yes)
			(back yes)
		)
		(net "MAC_USB-")
	)
	(segment
		(start 167.64287 97.08979)
		(end 169.16659 97.08979)
		(width 0.2032)
		(layer "In2.Cu")
		(net "MAC_USB-")
	)
	(segment
		(start 169.385 97.7796)
		(end 169.4216 97.8162)
		(width 0.2032)
		(layer "In2.Cu")
		(net "MAC_USB-")
	)
	(segment
		(start 152.68591 85.47966)
		(end 154.44576 85.47966)
		(width 0.2032)
		(layer "In2.Cu")
		(net "MAC_USB-")
	)
	(segment
		(start 165.90444 98.82822)
		(end 167.64287 97.08979)
		(width 0.2032)
		(layer "In2.Cu")
		(net "MAC_USB-")
	)
	(segment
		(start 151.74332 93.99448)
		(end 152.0216 93.7162)
		(width 0.2032)
		(layer "In2.Cu")
		(net "MAC_USB-")
	)
	(segment
		(start 157.1646 90.7592)
		(end 165.23362 98.82822)
		(width 0.2032)
		(layer "In2.Cu")
		(net "MAC_USB-")
	)
	(segment
		(start 130.17345 114.42647)
		(end 130.58344 114.83647)
		(width 0.2032)
		(layer "In2.Cu")
		(net "MAC_USB-")
	)
	(segment
		(start 149.1441 96.7937)
		(end 149.3216 96.6162)
		(width 0.2032)
		(layer "In2.Cu")
		(net "MAC_USB-")
	)
	(segment
		(start 149.3216 96.30554)
		(end 151.63267 93.99448)
		(width 0.2032)
		(layer "In2.Cu")
		(net "MAC_USB-")
	)
	(segment
		(start 130.79517 113.09467)
		(end 130.79517 109.47566)
		(width 0.2032)
		(layer "In2.Cu")
		(net "MAC_USB-")
	)
	(segment
		(start 165.23362 98.82822)
		(end 165.90444 98.82822)
		(width 0.2032)
		(layer "In2.Cu")
		(net "MAC_USB-")
	)
	(segment
		(start 152.0216 86.14396)
		(end 152.68591 85.47966)
		(width 0.2032)
		(layer "In2.Cu")
		(net "MAC_USB-")
	)
	(segment
		(start 154.44576 85.47966)
		(end 157.4216 88.4555)
		(width 0.2032)
		(layer "In2.Cu")
		(net "MAC_USB-")
	)
	(segment
		(start 169.16659 97.08979)
		(end 169.385 97.3082)
		(width 0.2032)
		(layer "In2.Cu")
		(net "MAC_USB-")
	)
	(segment
		(start 157.1646 90.7592)
		(end 157.1646 89.89285)
		(width 0.2032)
		(layer "In2.Cu")
		(net "MAC_USB-")
	)
	(segment
		(start 169.385 97.7796)
		(end 169.385 97.3082)
		(width 0.2032)
		(layer "In2.Cu")
		(net "MAC_USB-")
	)
	(segment
		(start 157.4216 89.63585)
		(end 157.4216 88.4555)
		(width 0.2032)
		(layer "In2.Cu")
		(net "MAC_USB-")
	)
	(segment
		(start 130.79517 109.47566)
		(end 143.47713 96.7937)
		(width 0.2032)
		(layer "In2.Cu")
		(net "MAC_USB-")
	)
	(segment
		(start 152.0216 93.7162)
		(end 152.0216 86.14396)
		(width 0.2032)
		(layer "In2.Cu")
		(net "MAC_USB-")
	)
	(segment
		(start 157.1646 89.89285)
		(end 157.4216 89.63585)
		(width 0.2032)
		(layer "In2.Cu")
		(net "MAC_USB-")
	)
	(segment
		(start 130.17345 113.71639)
		(end 130.79517 113.09467)
		(width 0.2032)
		(layer "In2.Cu")
		(net "MAC_USB-")
	)
	(segment
		(start 149.3216 96.6162)
		(end 149.3216 96.30554)
		(width 0.2032)
		(layer "In2.Cu")
		(net "MAC_USB-")
	)
	(segment
		(start 151.63267 93.99448)
		(end 151.74332 93.99448)
		(width 0.2032)
		(layer "In2.Cu")
		(net "MAC_USB-")
	)
	(segment
		(start 143.47713 96.7937)
		(end 149.1441 96.7937)
		(width 0.2032)
		(layer "In2.Cu")
		(net "MAC_USB-")
	)
	(segment
		(start 130.17345 114.42647)
		(end 130.17345 113.71639)
		(width 0.2032)
		(layer "In2.Cu")
		(net "MAC_USB-")
	)
	(segment
		(start 129.25657 114.72491)
		(end 130.03157 114.72491)
		(width 0.2032)
		(layer "F.Cu")
		(net "MAC_USB+")
	)
	(segment
		(start 130.03157 114.72491)
		(end 130.60525 114.15124)
		(width 0.2032)
		(layer "F.Cu")
		(net "MAC_USB+")
	)
	(segment
		(start 130.60525 114.15124)
		(end 130.60525 114.11184)
		(width 0.2032)
		(layer "F.Cu")
		(net "MAC_USB+")
	)
	(segment
		(start 169.04902 99.26063)
		(end 169.04902 98.29028)
		(width 0.2032)
		(layer "F.Cu")
		(net "MAC_USB+")
	)
	(segment
		(start 168.28441 97.52567)
		(end 169.04902 98.29028)
		(width 0.2032)
		(layer "F.Cu")
		(net "MAC_USB+")
	)
	(via
		(at 130.60525 114.11184)
		(size 0.4064)
		(drill 0.2032)
		(layers "F.Cu" "B.Cu")
		(locked yes)
		(net "MAC_USB+")
	)
	(via
		(at 168.28441 97.52567)
		(size 0.4064)
		(drill 0.2032)
		(layers "F.Cu" "B.Cu")
		(net "MAC_USB+")
	)
	(segment
		(start 164.97975 99.35532)
		(end 167.76145 99.35532)
		(width 0.2032)
		(layer "In2.Cu")
		(net "MAC_USB+")
	)
	(segment
		(start 152.4216 94.5162)
		(end 152.4216 86.3162)
		(width 0.2032)
		(layer "In2.Cu")
		(net "MAC_USB+")
	)
	(segment
		(start 149.9216 96.8239)
		(end 149.9216 96.3162)
		(width 0.2032)
		(layer "In2.Cu")
		(net "MAC_USB+")
	)
	(segment
		(start 152.92794 85.80986)
		(end 154.21526 85.80986)
		(width 0.2032)
		(layer "In2.Cu")
		(net "MAC_USB+")
	)
	(segment
		(start 143.6139 97.1239)
		(end 149.6216 97.1239)
		(width 0.2032)
		(layer "In2.Cu")
		(net "MAC_USB+")
	)
	(segment
		(start 156.7518 91.12737)
		(end 156.7518 88.3464)
		(width 0.2032)
		(layer "In2.Cu")
		(net "MAC_USB+")
	)
	(segment
		(start 154.21526 85.80986)
		(end 156.7518 88.3464)
		(width 0.2032)
		(layer "In2.Cu")
		(net "MAC_USB+")
	)
	(segment
		(start 131.12537 109.61243)
		(end 143.6139 97.1239)
		(width 0.2032)
		(layer "In2.Cu")
		(net "MAC_USB+")
	)
	(segment
		(start 150.9216 95.3162)
		(end 151.6216 95.3162)
		(width 0.2032)
		(layer "In2.Cu")
		(net "MAC_USB+")
	)
	(segment
		(start 149.6216 97.1239)
		(end 149.9216 96.8239)
		(width 0.2032)
		(layer "In2.Cu")
		(net "MAC_USB+")
	)
	(segment
		(start 167.76145 99.35532)
		(end 168.28441 98.83236)
		(width 0.2032)
		(layer "In2.Cu")
		(net "MAC_USB+")
	)
	(segment
		(start 131.12537 113.59171)
		(end 131.12537 109.61243)
		(width 0.2032)
		(layer "In2.Cu")
		(net "MAC_USB+")
	)
	(segment
		(start 149.9216 96.3162)
		(end 150.9216 95.3162)
		(width 0.2032)
		(layer "In2.Cu")
		(net "MAC_USB+")
	)
	(segment
		(start 152.4216 86.3162)
		(end 152.92794 85.80986)
		(width 0.2032)
		(layer "In2.Cu")
		(net "MAC_USB+")
	)
	(segment
		(start 168.28441 98.83236)
		(end 168.28441 97.52567)
		(width 0.2032)
		(layer "In2.Cu")
		(net "MAC_USB+")
	)
	(segment
		(start 151.6216 95.3162)
		(end 152.4216 94.5162)
		(width 0.2032)
		(layer "In2.Cu")
		(net "MAC_USB+")
	)
	(segment
		(start 156.7518 91.12737)
		(end 164.97975 99.35532)
		(width 0.2032)
		(layer "In2.Cu")
		(net "MAC_USB+")
	)
	(segment
		(start 130.60525 114.11184)
		(end 131.12537 113.59171)
		(width 0.2032)
		(layer "In2.Cu")
		(net "MAC_USB+")
	)
	(segment
		(start 155.7216 113.2162)
		(end 156.0684 113.563)
		(width 0.2032)
		(layer "F.Cu")
		(net "MAC_TX")
	)
	(segment
		(start 155.4716 115.2162)
		(end 155.6684 115.2162)
		(width 0.2032)
		(layer "F.Cu")
		(net "MAC_TX")
	)
	(segment
		(start 155.6684 115.2162)
		(end 156.0684 114.8162)
		(width 0.2032)
		(layer "F.Cu")
		(net "MAC_TX")
	)
	(segment
		(start 156.0684 114.8162)
		(end 156.0684 113.563)
		(width 0.2032)
		(layer "F.Cu")
		(net "MAC_TX")
	)
	(segment
		(start 154.4716 113.2162)
		(end 155.7216 113.2162)
		(width 0.2032)
		(layer "F.Cu")
		(net "MAC_TX")
	)
	(via
		(at 155.7216 113.2162)
		(size 0.4064)
		(drill 0.2032)
		(layers "F.Cu" "B.Cu")
		(net "MAC_TX")
	)
	(segment
		(start 118.00577 138.60036)
		(end 118.00577 131.63203)
		(width 0.2032)
		(layer "B.Cu")
		(net "MAC_TX")
	)
	(segment
		(start 118.00577 131.63203)
		(end 124.5216 125.1162)
		(width 0.2032)
		(layer "B.Cu")
		(net "MAC_TX")
	)
	(segment
		(start 118.00577 138.60036)
		(end 119.4216 140.0162)
		(width 0.2032)
		(layer "B.Cu")
		(net "MAC_TX")
	)
	(segment
		(start 142.21995 123.7162)
		(end 145.71995 120.2162)
		(width 0.2032)
		(layer "B.Cu")
		(net "MAC_TX")
	)
	(segment
		(start 124.5216 125.1162)
		(end 132.2216 125.1162)
		(width 0.2032)
		(layer "B.Cu")
		(net "MAC_TX")
	)
	(segment
		(start 153.19823 120.2162)
		(end 154.0216 119.39283)
		(width 0.2032)
		(layer "B.Cu")
		(net "MAC_TX")
	)
	(segment
		(start 145.71995 120.2162)
		(end 153.19823 120.2162)
		(width 0.2032)
		(layer "B.Cu")
		(net "MAC_TX")
	)
	(segment
		(start 155.7216 113.2162)
		(end 157.7216 115.2162)
		(width 0.2032)
		(layer "B.Cu")
		(net "MAC_TX")
	)
	(segment
		(start 154.0216 119.39283)
		(end 154.0216 117.4162)
		(width 0.2032)
		(layer "B.Cu")
		(net "MAC_TX")
	)
	(segment
		(start 157.1216 116.9162)
		(end 157.7216 116.3162)
		(width 0.2032)
		(layer "B.Cu")
		(net "MAC_TX")
	)
	(segment
		(start 154.0216 117.4162)
		(end 154.5216 116.9162)
		(width 0.2032)
		(layer "B.Cu")
		(net "MAC_TX")
	)
	(segment
		(start 132.2216 125.1162)
		(end 133.6216 123.7162)
		(width 0.2032)
		(layer "B.Cu")
		(net "MAC_TX")
	)
	(segment
		(start 133.6216 123.7162)
		(end 142.21995 123.7162)
		(width 0.2032)
		(layer "B.Cu")
		(net "MAC_TX")
	)
	(segment
		(start 157.7216 116.3162)
		(end 157.7216 115.2162)
		(width 0.2032)
		(layer "B.Cu")
		(net "MAC_TX")
	)
	(segment
		(start 154.5216 116.9162)
		(end 157.1216 116.9162)
		(width 0.2032)
		(layer "B.Cu")
		(net "MAC_TX")
	)
	(segment
		(start 154.4716 118.8162)
		(end 156.2716 118.8162)
		(width 0.2032)
		(layer "F.Cu")
		(net "MAC_RX")
	)
	(segment
		(start 156.2716 118.8162)
		(end 157.1716 117.9162)
		(width 0.2032)
		(layer "F.Cu")
		(net "MAC_RX")
	)
	(segment
		(start 156.0716 116.8162)
		(end 157.1716 117.9162)
		(width 0.2032)
		(layer "F.Cu")
		(net "MAC_RX")
	)
	(segment
		(start 155.4716 116.8162)
		(end 156.0716 116.8162)
		(width 0.2032)
		(layer "F.Cu")
		(net "MAC_RX")
	)
	(via
		(at 157.1716 117.9162)
		(size 0.4064)
		(drill 0.2032)
		(layers "F.Cu" "B.Cu")
		(net "MAC_RX")
	)
	(segment
		(start 127.70261 142.33519)
		(end 137.8216 132.2162)
		(width 0.2032)
		(layer "B.Cu")
		(net "MAC_RX")
	)
	(segment
		(start 124.74059 142.33519)
		(end 127.70261 142.33519)
		(width 0.2032)
		(layer "B.Cu")
		(net "MAC_RX")
	)
	(segment
		(start 152.7216 122.3662)
		(end 157.1716 117.9162)
		(width 0.2032)
		(layer "B.Cu")
		(net "MAC_RX")
	)
	(segment
		(start 152.7216 127.0162)
		(end 152.7216 122.3662)
		(width 0.2032)
		(layer "B.Cu")
		(net "MAC_RX")
	)
	(segment
		(start 122.4216 140.0162)
		(end 124.74059 142.33519)
		(width 0.2032)
		(layer "B.Cu")
		(net "MAC_RX")
	)
	(segment
		(start 151.0216 128.7162)
		(end 152.7216 127.0162)
		(width 0.2032)
		(layer "B.Cu")
		(net "MAC_RX")
	)
	(segment
		(start 150.8216 132.2162)
		(end 151.0216 132.0162)
		(width 0.2032)
		(layer "B.Cu")
		(net "MAC_RX")
	)
	(segment
		(start 137.8216 132.2162)
		(end 150.8216 132.2162)
		(width 0.2032)
		(layer "B.Cu")
		(net "MAC_RX")
	)
	(segment
		(start 151.0216 132.0162)
		(end 151.0216 128.7162)
		(width 0.2032)
		(layer "B.Cu")
		(net "MAC_RX")
	)
	(segment
		(start 122.7166 90.34083)
		(end 122.7166 88.4662)
		(width 0.2032)
		(layer "F.Cu")
		(net "MAC_PPS_OUT-")
	)
	(segment
		(start 124.48157 119.29691)
		(end 125.25657 119.29691)
		(width 0.2032)
		(layer "F.Cu")
		(net "MAC_PPS_OUT-")
	)
	(segment
		(start 123.96228 119.8162)
		(end 124.48157 119.29691)
		(width 0.2032)
		(layer "F.Cu")
		(net "MAC_PPS_OUT-")
	)
	(segment
		(start 123.9216 119.8162)
		(end 123.96228 119.8162)
		(width 0.2032)
		(layer "F.Cu")
		(net "MAC_PPS_OUT-")
	)
	(via
		(at 123.9216 119.8162)
		(size 0.4064)
		(drill 0.2032)
		(layers "F.Cu" "B.Cu")
		(locked yes)
		(tenting
			(front yes)
			(back yes)
		)
		(net "MAC_PPS_OUT-")
	)
	(via
		(at 122.7166 90.34083)
		(size 0.4064)
		(drill 0.2032)
		(layers "F.Cu" "B.Cu")
		(net "MAC_PPS_OUT-")
	)
	(segment
		(start 118.3914 114.14057)
		(end 123.19431 118.94349)
		(width 0.2032)
		(layer "B.Cu")
		(net "MAC_PPS_OUT-")
	)
	(segment
		(start 123.5216 91.34923)
		(end 123.5216 91.14583)
		(width 0.2032)
		(layer "B.Cu")
		(net "MAC_PPS_OUT-")
	)
	(segment
		(start 122.7166 90.34083)
		(end 122.7166 88.3362)
		(width 0.2032)
		(layer "B.Cu")
		(net "MAC_PPS_OUT-")
	)
	(segment
		(start 118.3914 114.14057)
		(end 118.3914 96.47943)
		(width 0.2032)
		(layer "B.Cu")
		(net "MAC_PPS_OUT-")
	)
	(segment
		(start 123.19431 119.08891)
		(end 123.9216 119.8162)
		(width 0.2032)
		(layer "B.Cu")
		(net "MAC_PPS_OUT-")
	)
	(segment
		(start 122.7166 90.34083)
		(end 123.5216 91.14583)
		(width 0.2032)
		(layer "B.Cu")
		(net "MAC_PPS_OUT-")
	)
	(segment
		(start 118.3914 96.47943)
		(end 123.5216 91.34923)
		(width 0.2032)
		(layer "B.Cu")
		(net "MAC_PPS_OUT-")
	)
	(segment
		(start 123.19431 119.08891)
		(end 123.19431 118.94349)
		(width 0.2032)
		(layer "B.Cu")
		(net "MAC_PPS_OUT-")
	)
	(segment
		(start 123.88813 119.17033)
		(end 123.89052 119.17033)
		(width 0.2032)
		(layer "F.Cu")
		(net "MAC_PPS_OUT+")
	)
	(segment
		(start 123.9866 90.2335)
		(end 123.9866 88.4662)
		(width 0.2032)
		(layer "F.Cu")
		(net "MAC_PPS_OUT+")
	)
	(segment
		(start 124.24853 118.81232)
		(end 125.23317 118.81232)
		(width 0.2032)
		(layer "F.Cu")
		(net "MAC_PPS_OUT+")
	)
	(segment
		(start 125.23317 118.81232)
		(end 125.25657 118.78891)
		(width 0.2032)
		(layer "F.Cu")
		(net "MAC_PPS_OUT+")
	)
	(segment
		(start 123.89052 119.17033)
		(end 124.24853 118.81232)
		(width 0.2032)
		(layer "F.Cu")
		(net "MAC_PPS_OUT+")
	)
	(via
		(at 123.88813 119.17033)
		(size 0.4064)
		(drill 0.2032)
		(layers "F.Cu" "B.Cu")
		(locked yes)
		(tenting
			(front yes)
			(back yes)
		)
		(net "MAC_PPS_OUT+")
	)
	(via
		(at 123.9866 90.2335)
		(size 0.4064)
		(drill 0.2032)
		(layers "F.Cu" "B.Cu")
		(net "MAC_PPS_OUT+")
	)
	(segment
		(start 123.9866 90.2335)
		(end 123.9866 88.3562)
		(width 0.2032)
		(layer "B.Cu")
		(net "MAC_PPS_OUT+")
	)
	(segment
		(start 118.7216 114.0038)
		(end 123.88813 119.17033)
		(width 0.2032)
		(layer "B.Cu")
		(net "MAC_PPS_OUT+")
	)
	(segment
		(start 123.9866 91.3512)
		(end 123.9866 90.2335)
		(width 0.2032)
		(layer "B.Cu")
		(net "MAC_PPS_OUT+")
	)
	(segment
		(start 118.7216 96.6162)
		(end 123.9866 91.3512)
		(width 0.2032)
		(layer "B.Cu")
		(net "MAC_PPS_OUT+")
	)
	(segment
		(start 118.7216 114.0038)
		(end 118.7216 96.6162)
		(width 0.2032)
		(layer "B.Cu")
		(net "MAC_PPS_OUT+")
	)
	(segment
		(start 124.0216 114.26495)
		(end 124.0216 114.2162)
		(width 0.2032)
		(layer "F.Cu")
		(net "MAC_PPS_IN1+")
	)
	(segment
		(start 124.48157 114.72491)
		(end 125.25657 114.72491)
		(width 0.2032)
		(layer "F.Cu")
		(net "MAC_PPS_IN1+")
	)
	(segment
		(start 124.0216 114.26495)
		(end 124.48157 114.72491)
		(width 0.2032)
		(layer "F.Cu")
		(net "MAC_PPS_IN1+")
	)
	(segment
		(start 130.0866 82.4512)
		(end 130.1216 82.4162)
		(width 0.2032)
		(layer "F.Cu")
		(net "MAC_PPS_IN1+")
	)
	(segment
		(start 130.0866 83.9162)
		(end 130.0866 82.4512)
		(width 0.2032)
		(layer "F.Cu")
		(net "MAC_PPS_IN1+")
	)
	(via
		(at 124.0216 114.2162)
		(size 0.4064)
		(drill 0.2032)
		(layers "F.Cu" "B.Cu")
		(locked yes)
		(tenting
			(front yes)
			(back yes)
		)
		(net "MAC_PPS_IN1+")
	)
	(via
		(at 130.1216 82.4162)
		(size 0.4064)
		(drill 0.2032)
		(layers "F.Cu" "B.Cu")
		(net "MAC_PPS_IN1+")
	)
	(segment
		(start 124.0216 105.3162)
		(end 130.3216 99.0162)
		(width 0.2032)
		(layer "B.Cu")
		(net "MAC_PPS_IN1+")
	)
	(segment
		(start 124.0216 114.2162)
		(end 124.0216 105.3162)
		(width 0.2032)
		(layer "B.Cu")
		(net "MAC_PPS_IN1+")
	)
	(segment
		(start 125.6216 88.1468)
		(end 130.1216 83.6468)
		(width 0.2032)
		(layer "B.Cu")
		(net "MAC_PPS_IN1+")
	)
	(segment
		(start 125.6216 91.8162)
		(end 125.6216 88.1468)
		(width 0.2032)
		(layer "B.Cu")
		(net "MAC_PPS_IN1+")
	)
	(segment
		(start 130.1216 83.6468)
		(end 130.1216 82.4162)
		(width 0.2032)
		(layer "B.Cu")
		(net "MAC_PPS_IN1+")
	)
	(segment
		(start 125.6216 91.8162)
		(end 130.3216 96.5162)
		(width 0.2032)
		(layer "B.Cu")
		(net "MAC_PPS_IN1+")
	)
	(segment
		(start 130.3216 99.0162)
		(end 130.3216 96.5162)
		(width 0.2032)
		(layer "B.Cu")
		(net "MAC_PPS_IN1+")
	)
	(segment
		(start 123.90278 116.23424)
		(end 125.24189 116.23424)
		(width 0.2032)
		(layer "F.Cu")
		(net "MAC_PPS_IN0-")
	)
	(segment
		(start 132.6241 83.9137)
		(end 132.6266 83.9162)
		(width 0.2032)
		(layer "F.Cu")
		(net "MAC_PPS_IN0-")
	)
	(segment
		(start 123.8881 116.21957)
		(end 123.90278 116.23424)
		(width 0.2032)
		(layer "F.Cu")
		(net "MAC_PPS_IN0-")
	)
	(segment
		(start 132.6241 83.9137)
		(end 132.6241 82.3187)
		(width 0.2032)
		(layer "F.Cu")
		(net "MAC_PPS_IN0-")
	)
	(segment
		(start 125.24189 116.23424)
		(end 125.25657 116.24891)
		(width 0.2032)
		(layer "F.Cu")
		(net "MAC_PPS_IN0-")
	)
	(segment
		(start 132.6216 82.3162)
		(end 132.6241 82.3187)
		(width 0.2032)
		(layer "F.Cu")
		(net "MAC_PPS_IN0-")
	)
	(via
		(at 132.6216 82.3162)
		(size 0.4064)
		(drill 0.2032)
		(layers "F.Cu" "B.Cu")
		(net "MAC_PPS_IN0-")
	)
	(via
		(at 123.8881 116.21957)
		(size 0.4064)
		(drill 0.2032)
		(layers "F.Cu" "B.Cu")
		(locked yes)
		(tenting
			(front yes)
			(back yes)
		)
		(net "MAC_PPS_IN0-")
	)
	(segment
		(start 124.73998 115.27545)
		(end 132.2518 107.76363)
		(width 0.2032)
		(layer "B.Cu")
		(net "MAC_PPS_IN0-")
	)
	(segment
		(start 124.73998 115.40848)
		(end 124.73998 115.27545)
		(width 0.2032)
		(layer "B.Cu")
		(net "MAC_PPS_IN0-")
	)
	(segment
		(start 131.6518 85.57943)
		(end 133.9518 87.87943)
		(width 0.2032)
		(layer "B.Cu")
		(net "MAC_PPS_IN0-")
	)
	(segment
		(start 131.6518 83.286)
		(end 132.6216 82.3162)
		(width 0.2032)
		(layer "B.Cu")
		(net "MAC_PPS_IN0-")
	)
	(segment
		(start 123.8881 116.21957)
		(end 123.92888 116.21957)
		(width 0.2032)
		(layer "B.Cu")
		(net "MAC_PPS_IN0-")
	)
	(segment
		(start 133.9518 92.25297)
		(end 133.9518 87.87943)
		(width 0.2032)
		(layer "B.Cu")
		(net "MAC_PPS_IN0-")
	)
	(segment
		(start 132.2518 107.76363)
		(end 132.2518 93.95297)
		(width 0.2032)
		(layer "B.Cu")
		(net "MAC_PPS_IN0-")
	)
	(segment
		(start 132.2518 93.95297)
		(end 133.9518 92.25297)
		(width 0.2032)
		(layer "B.Cu")
		(net "MAC_PPS_IN0-")
	)
	(segment
		(start 123.92888 116.21957)
		(end 124.73998 115.40848)
		(width 0.2032)
		(layer "B.Cu")
		(net "MAC_PPS_IN0-")
	)
	(segment
		(start 131.6518 85.57943)
		(end 131.6518 83.286)
		(width 0.2032)
		(layer "B.Cu")
		(net "MAC_PPS_IN0-")
	)
	(segment
		(start 123.97659 115.6162)
		(end 124.1013 115.74091)
		(width 0.2032)
		(layer "F.Cu")
		(net "MAC_PPS_IN0+")
	)
	(segment
		(start 131.3216 82.3162)
		(end 131.3391 82.3337)
		(width 0.2032)
		(layer "F.Cu")
		(net "MAC_PPS_IN0+")
	)
	(segment
		(start 131.3391 83.8987)
		(end 131.3566 83.9162)
		(width 0.2032)
		(layer "F.Cu")
		(net "MAC_PPS_IN0+")
	)
	(segment
		(start 124.1013 115.74091)
		(end 125.25657 115.74091)
		(width 0.2032)
		(layer "F.Cu")
		(net "MAC_PPS_IN0+")
	)
	(segment
		(start 131.3391 83.8987)
		(end 131.3391 82.3337)
		(width 0.2032)
		(layer "F.Cu")
		(net "MAC_PPS_IN0+")
	)
	(segment
		(start 123.9216 115.6162)
		(end 123.97659 115.6162)
		(width 0.2032)
		(layer "F.Cu")
		(net "MAC_PPS_IN0+")
	)
	(via
		(at 131.3216 82.3162)
		(size 0.4064)
		(drill 0.2032)
		(layers "F.Cu" "B.Cu")
		(net "MAC_PPS_IN0+")
	)
	(via
		(at 123.9216 115.6162)
		(size 0.4064)
		(drill 0.2032)
		(layers "F.Cu" "B.Cu")
		(locked yes)
		(tenting
			(front yes)
			(back yes)
		)
		(net "MAC_PPS_IN0+")
	)
	(segment
		(start 131.9216 93.8162)
		(end 133.6216 92.1162)
		(width 0.2032)
		(layer "B.Cu")
		(net "MAC_PPS_IN0+")
	)
	(segment
		(start 133.6216 92.1162)
		(end 133.6216 88.0162)
		(width 0.2032)
		(layer "B.Cu")
		(net "MAC_PPS_IN0+")
	)
	(segment
		(start 131.3216 85.7162)
		(end 131.3216 82.3162)
		(width 0.2032)
		(layer "B.Cu")
		(net "MAC_PPS_IN0+")
	)
	(segment
		(start 123.93226 115.6162)
		(end 131.9216 107.62686)
		(width 0.2032)
		(layer "B.Cu")
		(net "MAC_PPS_IN0+")
	)
	(segment
		(start 131.9216 107.62686)
		(end 131.9216 93.8162)
		(width 0.2032)
		(layer "B.Cu")
		(net "MAC_PPS_IN0+")
	)
	(segment
		(start 123.9216 115.6162)
		(end 123.93226 115.6162)
		(width 0.2032)
		(layer "B.Cu")
		(net "MAC_PPS_IN0+")
	)
	(segment
		(start 131.3216 85.7162)
		(end 133.6216 88.0162)
		(width 0.2032)
		(layer "B.Cu")
		(net "MAC_PPS_IN0+")
	)
	(segment
		(start 162.39414 109.08874)
		(end 162.9216 109.6162)
		(width 0.2032)
		(layer "F.Cu")
		(net "MAC_BITE")
	)
	(segment
		(start 158.63115 108.52591)
		(end 159.19398 109.08874)
		(width 0.2032)
		(layer "F.Cu")
		(net "MAC_BITE")
	)
	(segment
		(start 158.63115 107.5847)
		(end 160.54891 105.66694)
		(width 0.2032)
		(layer "F.Cu")
		(net "MAC_BITE")
	)
	(segment
		(start 159.19398 109.08874)
		(end 162.39414 109.08874)
		(width 0.2032)
		(layer "F.Cu")
		(net "MAC_BITE")
	)
	(segment
		(start 160.54891 105.66694)
		(end 160.54891 103.31041)
		(width 0.2032)
		(layer "F.Cu")
		(net "MAC_BITE")
	)
	(segment
		(start 158.63115 108.52591)
		(end 158.63115 107.5847)
		(width 0.2032)
		(layer "F.Cu")
		(net "MAC_BITE")
	)
	(via
		(at 162.9216 109.6162)
		(size 0.4064)
		(drill 0.2032)
		(layers "F.Cu" "B.Cu")
		(tenting
			(front yes)
			(back yes)
		)
		(net "MAC_BITE")
	)
	(segment
		(start 162.9216 111.15967)
		(end 162.9216 109.6162)
		(width 0.2032)
		(layer "B.Cu")
		(net "MAC_BITE")
	)
	(segment
		(start 130.8216 138.5162)
		(end 130.8216 133.2162)
		(width 0.2032)
		(layer "B.Cu")
		(net "MAC_BITE")
	)
	(segment
		(start 137.39807 128.2162)
		(end 140.9216 128.2162)
		(width 0.2032)
		(layer "B.Cu")
		(net "MAC_BITE")
	)
	(segment
		(start 147.1716 126.3162)
		(end 149.5716 123.9162)
		(width 0.2032)
		(layer "B.Cu")
		(net "MAC_BITE")
	)
	(segment
		(start 140.9216 128.2162)
		(end 142.8216 126.3162)
		(width 0.2032)
		(layer "B.Cu")
		(net "MAC_BITE")
	)
	(segment
		(start 137.36627 128.248)
		(end 137.39807 128.2162)
		(width 0.2032)
		(layer "B.Cu")
		(net "MAC_BITE")
	)
	(segment
		(start 159.85785 114.22342)
		(end 162.9216 111.15967)
		(width 0.2032)
		(layer "B.Cu")
		(net "MAC_BITE")
	)
	(segment
		(start 129.3216 140.0162)
		(end 130.8216 138.5162)
		(width 0.2032)
		(layer "B.Cu")
		(net "MAC_BITE")
	)
	(segment
		(start 132.6534 131.3844)
		(end 132.6534 128.36703)
		(width 0.2032)
		(layer "B.Cu")
		(net "MAC_BITE")
	)
	(segment
		(start 154.78183 119.55597)
		(end 154.78183 118.65597)
		(width 0.2032)
		(layer "B.Cu")
		(net "MAC_BITE")
	)
	(segment
		(start 142.8216 126.3162)
		(end 147.1716 126.3162)
		(width 0.2032)
		(layer "B.Cu")
		(net "MAC_BITE")
	)
	(segment
		(start 132.77243 128.248)
		(end 137.36627 128.248)
		(width 0.2032)
		(layer "B.Cu")
		(net "MAC_BITE")
	)
	(segment
		(start 149.5716 123.9162)
		(end 150.4216 123.9162)
		(width 0.2032)
		(layer "B.Cu")
		(net "MAC_BITE")
	)
	(segment
		(start 158.1216 114.8162)
		(end 158.71438 114.22342)
		(width 0.2032)
		(layer "B.Cu")
		(net "MAC_BITE")
	)
	(segment
		(start 132.6534 128.36703)
		(end 132.77243 128.248)
		(width 0.2032)
		(layer "B.Cu")
		(net "MAC_BITE")
	)
	(segment
		(start 150.4216 123.9162)
		(end 154.78183 119.55597)
		(width 0.2032)
		(layer "B.Cu")
		(net "MAC_BITE")
	)
	(segment
		(start 158.1216 117.29573)
		(end 158.1216 114.8162)
		(width 0.2032)
		(layer "B.Cu")
		(net "MAC_BITE")
	)
	(segment
		(start 154.78183 118.65597)
		(end 156.14206 117.29573)
		(width 0.2032)
		(layer "B.Cu")
		(net "MAC_BITE")
	)
	(segment
		(start 125.4216 140.0162)
		(end 129.3216 140.0162)
		(width 0.2032)
		(layer "B.Cu")
		(net "MAC_BITE")
	)
	(segment
		(start 158.71438 114.22342)
		(end 159.85785 114.22342)
		(width 0.2032)
		(layer "B.Cu")
		(net "MAC_BITE")
	)
	(segment
		(start 156.14206 117.29573)
		(end 158.1216 117.29573)
		(width 0.2032)
		(layer "B.Cu")
		(net "MAC_BITE")
	)
	(segment
		(start 130.8216 133.2162)
		(end 132.6534 131.3844)
		(width 0.2032)
		(layer "B.Cu")
		(net "MAC_BITE")
	)
	(segment
		(start 159.4216 106.0162)
		(end 160.04904 105.38876)
		(width 0.2032)
		(layer "F.Cu")
		(net "MAC_ALARM")
	)
	(segment
		(start 130.63972 119.08899)
		(end 130.64469 119.08899)
		(width 0.2032)
		(layer "F.Cu")
		(net "MAC_ALARM")
	)
	(segment
		(start 130.43179 119.29691)
		(end 130.63972 119.08899)
		(width 0.2032)
		(layer "F.Cu")
		(net "MAC_ALARM")
	)
	(segment
		(start 129.25657 119.29691)
		(end 130.43179 119.29691)
		(width 0.2032)
		(layer "F.Cu")
		(net "MAC_ALARM")
	)
	(segment
		(start 160.04904 105.38876)
		(end 160.04904 103.31041)
		(width 0.2032)
		(layer "F.Cu")
		(net "MAC_ALARM")
	)
	(via
		(at 130.64469 119.08899)
		(size 0.4064)
		(drill 0.2032)
		(layers "F.Cu" "B.Cu")
		(locked yes)
		(net "MAC_ALARM")
	)
	(via
		(at 159.4216 106.0162)
		(size 0.4064)
		(drill 0.2032)
		(layers "F.Cu" "B.Cu")
		(tenting
			(front yes)
			(back yes)
		)
		(net "MAC_ALARM")
	)
	(segment
		(start 135.86584 107.37195)
		(end 143.0216 100.2162)
		(width 0.2032)
		(layer "In2.Cu")
		(net "MAC_ALARM")
	)
	(segment
		(start 158.69191 103.38211)
		(end 159.4216 104.1118)
		(width 0.2032)
		(layer "In2.Cu")
		(net "MAC_ALARM")
	)
	(segment
		(start 130.64469 118.69311)
		(end 135.86584 113.47196)
		(width 0.2032)
		(layer "In2.Cu")
		(net "MAC_ALARM")
	)
	(segment
		(start 130.64469 119.08899)
		(end 130.64469 118.69311)
		(width 0.2032)
		(layer "In2.Cu")
		(net "MAC_ALARM")
	)
	(segment
		(start 143.0216 100.2162)
		(end 151.1216 100.2162)
		(width 0.2032)
		(layer "In2.Cu")
		(net "MAC_ALARM")
	)
	(segment
		(start 159.4216 106.0162)
		(end 159.4216 104.1118)
		(width 0.2032)
		(layer "In2.Cu")
		(net "MAC_ALARM")
	)
	(segment
		(start 135.86584 113.47196)
		(end 135.86584 107.37195)
		(width 0.2032)
		(layer "In2.Cu")
		(net "MAC_ALARM")
	)
	(segment
		(start 154.28751 103.38211)
		(end 158.69191 103.38211)
		(width 0.2032)
		(layer "In2.Cu")
		(net "MAC_ALARM")
	)
	(segment
		(start 151.1216 100.2162)
		(end 154.28751 103.38211)
		(width 0.2032)
		(layer "In2.Cu")
		(net "MAC_ALARM")
	)
	(segment
		(start 115.0341 51.8037)
		(end 115.1216 51.7162)
		(width 0.2032)
		(layer "F.Cu")
		(net "GPS1_TP2")
	)
	(segment
		(start 112.7591 51.8037)
		(end 113.8841 51.8037)
		(width 0.2032)
		(layer "F.Cu")
		(net "GPS1_TP2")
	)
	(segment
		(start 113.8841 51.8037)
		(end 113.9216 51.8412)
		(width 0.2032)
		(layer "F.Cu")
		(net "GPS1_TP2")
	)
	(segment
		(start 188.08397 118.22305)
		(end 189.83867 118.22305)
		(width 0.2032)
		(layer "F.Cu")
		(net "GPS1_TP2")
	)
	(segment
		(start 113.9591 51.8037)
		(end 115.0341 51.8037)
		(width 0.2032)
		(layer "F.Cu")
		(net "GPS1_TP2")
	)
	(segment
		(start 115.1216 51.7662)
		(end 115.1216 51.7162)
		(width 0.2032)
		(layer "F.Cu")
		(net "GPS1_TP2")
	)
	(segment
		(start 189.83867 118.22305)
		(end 189.83867 118.07856)
		(width 0.2032)
		(layer "F.Cu")
		(net "GPS1_TP2")
	)
	(segment
		(start 113.9216 51.8412)
		(end 113.9591 51.8037)
		(width 0.2032)
		(layer "F.Cu")
		(net "GPS1_TP2")
	)
	(segment
		(start 112.7216 51.7662)
		(end 112.7591 51.8037)
		(width 0.2032)
		(layer "F.Cu")
		(net "GPS1_TP2")
	)
	(via
		(at 189.83867 118.07856)
		(size 0.4064)
		(drill 0.2032)
		(layers "F.Cu" "B.Cu")
		(tenting
			(front yes)
			(back yes)
		)
		(net "GPS1_TP2")
	)
	(via
		(at 115.1216 51.7162)
		(size 0.4064)
		(drill 0.2032)
		(layers "F.Cu" "B.Cu")
		(net "GPS1_TP2")
	)
	(segment
		(start 161.4216 87.0162)
		(end 161.4216 85.79525)
		(width 0.2032)
		(layer "In3.Cu")
		(net "GPS1_TP2")
	)
	(segment
		(start 175.6045 95.6991)
		(end 177.54478 95.6991)
		(width 0.2032)
		(layer "In3.Cu")
		(net "GPS1_TP2")
	)
	(segment
		(start 189.59773 115.9162)
		(end 190.8364 117.15487)
		(width 0.2032)
		(layer "In3.Cu")
		(net "GPS1_TP2")
	)
	(segment
		(start 177.54478 95.6991)
		(end 178.66188 96.8162)
		(width 0.2032)
		(layer "In3.Cu")
		(net "GPS1_TP2")
	)
	(segment
		(start 115.1216 51.7162)
		(end 122.2216 58.8162)
		(width 0.2032)
		(layer "In3.Cu")
		(net "GPS1_TP2")
	)
	(segment
		(start 158.3216 83.6162)
		(end 159.7216 85.0162)
		(width 0.2032)
		(layer "In3.Cu")
		(net "GPS1_TP2")
	)
	(segment
		(start 180.0216 98.4162)
		(end 180.0216 97.24174)
		(width 0.2032)
		(layer "In3.Cu")
		(net "GPS1_TP2")
	)
	(segment
		(start 173.4216 93.5162)
		(end 175.6045 95.6991)
		(width 0.2032)
		(layer "In3.Cu")
		(net "GPS1_TP2")
	)
	(segment
		(start 180.0216 98.4162)
		(end 181.42491 99.81951)
		(width 0.2032)
		(layer "In3.Cu")
		(net "GPS1_TP2")
	)
	(segment
		(start 173.40864 93.511)
		(end 173.41384 93.5162)
		(width 0.2032)
		(layer "In3.Cu")
		(net "GPS1_TP2")
	)
	(segment
		(start 161.4216 87.0162)
		(end 167.9164 93.511)
		(width 0.2032)
		(layer "In3.Cu")
		(net "GPS1_TP2")
	)
	(segment
		(start 158.3216 83.6162)
		(end 158.3216 82.6162)
		(width 0.2032)
		(layer "In3.Cu")
		(net "GPS1_TP2")
	)
	(segment
		(start 180.71194 113.30654)
		(end 182.91193 113.30654)
		(width 0.2032)
		(layer "In3.Cu")
		(net "GPS1_TP2")
	)
	(segment
		(start 167.9164 93.511)
		(end 173.40864 93.511)
		(width 0.2032)
		(layer "In3.Cu")
		(net "GPS1_TP2")
	)
	(segment
		(start 180.0518 112.6464)
		(end 180.0518 109.086)
		(width 0.2032)
		(layer "In3.Cu")
		(net "GPS1_TP2")
	)
	(segment
		(start 190.8364 117.7014)
		(end 190.8364 117.15487)
		(width 0.2032)
		(layer "In3.Cu")
		(net "GPS1_TP2")
	)
	(segment
		(start 189.83867 118.07856)
		(end 190.45924 118.07856)
		(width 0.2032)
		(layer "In3.Cu")
		(net "GPS1_TP2")
	)
	(segment
		(start 134.5216 58.8162)
		(end 158.3216 82.6162)
		(width 0.2032)
		(layer "In3.Cu")
		(net "GPS1_TP2")
	)
	(segment
		(start 178.66188 96.8162)
		(end 179.59606 96.8162)
		(width 0.2032)
		(layer "In3.Cu")
		(net "GPS1_TP2")
	)
	(segment
		(start 122.2216 58.8162)
		(end 134.5216 58.8162)
		(width 0.2032)
		(layer "In3.Cu")
		(net "GPS1_TP2")
	)
	(segment
		(start 182.91193 113.30654)
		(end 185.5216 115.9162)
		(width 0.2032)
		(layer "In3.Cu")
		(net "GPS1_TP2")
	)
	(segment
		(start 179.59606 96.8162)
		(end 180.0216 97.24174)
		(width 0.2032)
		(layer "In3.Cu")
		(net "GPS1_TP2")
	)
	(segment
		(start 173.41384 93.5162)
		(end 173.4216 93.5162)
		(width 0.2032)
		(layer "In3.Cu")
		(net "GPS1_TP2")
	)
	(segment
		(start 160.64255 85.0162)
		(end 161.4216 85.79525)
		(width 0.2032)
		(layer "In3.Cu")
		(net "GPS1_TP2")
	)
	(segment
		(start 180.0518 112.6464)
		(end 180.71194 113.30654)
		(width 0.2032)
		(layer "In3.Cu")
		(net "GPS1_TP2")
	)
	(segment
		(start 159.7216 85.0162)
		(end 160.64255 85.0162)
		(width 0.2032)
		(layer "In3.Cu")
		(net "GPS1_TP2")
	)
	(segment
		(start 190.45924 118.07856)
		(end 190.8364 117.7014)
		(width 0.2032)
		(layer "In3.Cu")
		(net "GPS1_TP2")
	)
	(segment
		(start 185.5216 115.9162)
		(end 189.59773 115.9162)
		(width 0.2032)
		(layer "In3.Cu")
		(net "GPS1_TP2")
	)
	(segment
		(start 181.42491 107.71289)
		(end 181.42491 99.81951)
		(width 0.2032)
		(layer "In3.Cu")
		(net "GPS1_TP2")
	)
	(segment
		(start 180.0518 109.086)
		(end 181.42491 107.71289)
		(width 0.2032)
		(layer "In3.Cu")
		(net "GPS1_TP2")
	)
	(segment
		(start 114.8216 57.7662)
		(end 116.3466 57.7662)
		(width 0.2032)
		(layer "F.Cu")
		(net "GPS1_RST")
	)
	(segment
		(start 190.09668 115.22306)
		(end 194.4216 110.89814)
		(width 0.2032)
		(layer "F.Cu")
		(net "GPS1_RST")
	)
	(segment
		(start 188.08397 115.22306)
		(end 190.09668 115.22306)
		(width 0.2032)
		(layer "F.Cu")
		(net "GPS1_RST")
	)
	(segment
		(start 123.8966 62.0162)
		(end 125.7216 62.0162)
		(width 0.2032)
		(layer "F.Cu")
		(net "GPS1_RST")
	)
	(segment
		(start 125.7216 62.0162)
		(end 125.7216 60.5162)
		(width 0.2032)
		(layer "F.Cu")
		(net "GPS1_RST")
	)
	(segment
		(start 109.4716 71.7286)
		(end 109.48401 71.7162)
		(width 0.2032)
		(layer "F.Cu")
		(net "GPS1_RST")
	)
	(segment
		(start 109.48401 71.7162)
		(end 110.9216 71.7162)
		(width 0.2032)
		(layer "F.Cu")
		(net "GPS1_RST")
	)
	(segment
		(start 194.4216 110.89814)
		(end 194.4216 105.2162)
		(width 0.2032)
		(layer "F.Cu")
		(net "GPS1_RST")
	)
	(segment
		(start 114.8216 57.8162)
		(end 114.8216 57.7662)
		(width 0.2032)
		(layer "F.Cu")
		(net "GPS1_RST")
	)
	(via
		(at 114.8216 57.8162)
		(size 0.4064)
		(drill 0.2032)
		(layers "F.Cu" "B.Cu")
		(net "GPS1_RST")
	)
	(via
		(at 194.4216 105.2162)
		(size 0.4064)
		(drill 0.2032)
		(layers "F.Cu" "B.Cu")
		(net "GPS1_RST")
	)
	(via
		(at 125.7216 60.5162)
		(size 0.4064)
		(drill 0.2032)
		(layers "F.Cu" "B.Cu")
		(net "GPS1_RST")
	)
	(via
		(at 110.9216 71.7162)
		(size 0.4064)
		(drill 0.2032)
		(layers "F.Cu" "B.Cu")
		(net "GPS1_RST")
	)
	(segment
		(start 185.45924 106.55384)
		(end 190.14082 106.55384)
		(width 0.2032)
		(layer "B.Cu")
		(net "GPS1_RST")
	)
	(segment
		(start 125.7216 61.8347)
		(end 125.7216 60.5162)
		(width 0.2032)
		(layer "B.Cu")
		(net "GPS1_RST")
	)
	(segment
		(start 117.5216 60.5162)
		(end 125.7216 60.5162)
		(width 0.2032)
		(layer "B.Cu")
		(net "GPS1_RST")
	)
	(segment
		(start 108.3092 69.1038)
		(end 108.3092 64.85798)
		(width 0.2032)
		(layer "B.Cu")
		(net "GPS1_RST")
	)
	(segment
		(start 111.66094 56.6162)
		(end 113.9846 56.6162)
		(width 0.2032)
		(layer "B.Cu")
		(net "GPS1_RST")
	)
	(segment
		(start 185.53146 98.1162)
		(end 201.0216 98.1162)
		(width 0.2032)
		(layer "B.Cu")
		(net "GPS1_RST")
	)
	(segment
		(start 207.9216 64.0162)
		(end 207.9216 52.9162)
		(width 0.2032)
		(layer "B.Cu")
		(net "GPS1_RST")
	)
	(segment
		(start 178.24063 98.9162)
		(end 184.73146 98.9162)
		(width 0.2032)
		(layer "B.Cu")
		(net "GPS1_RST")
	)
	(segment
		(start 114.8216 57.8162)
		(end 114.8216 57.4532)
		(width 0.2032)
		(layer "B.Cu")
		(net "GPS1_RST")
	)
	(segment
		(start 178.1216 99.03523)
		(end 178.24063 98.9162)
		(width 0.2032)
		(layer "B.Cu")
		(net "GPS1_RST")
	)
	(segment
		(start 201.0216 98.1162)
		(end 204.0216 95.1162)
		(width 0.2032)
		(layer "B.Cu")
		(net "GPS1_RST")
	)
	(segment
		(start 191.47847 105.2162)
		(end 194.4216 105.2162)
		(width 0.2032)
		(layer "B.Cu")
		(net "GPS1_RST")
	)
	(segment
		(start 204.0216 95.1162)
		(end 204.0216 78.2162)
		(width 0.2032)
		(layer "B.Cu")
		(net "GPS1_RST")
	)
	(segment
		(start 113.9846 56.6162)
		(end 114.8216 57.4532)
		(width 0.2032)
		(layer "B.Cu")
		(net "GPS1_RST")
	)
	(segment
		(start 190.14082 106.55384)
		(end 191.47847 105.2162)
		(width 0.2032)
		(layer "B.Cu")
		(net "GPS1_RST")
	)
	(segment
		(start 178.1216 100.84284)
		(end 178.1216 99.03523)
		(width 0.2032)
		(layer "B.Cu")
		(net "GPS1_RST")
	)
	(segment
		(start 206.9216 75.3162)
		(end 206.9216 65.0162)
		(width 0.2032)
		(layer "B.Cu")
		(net "GPS1_RST")
	)
	(segment
		(start 178.1216 100.84284)
		(end 179.74824 100.84284)
		(width 0.2032)
		(layer "B.Cu")
		(net "GPS1_RST")
	)
	(segment
		(start 206.9216 65.0162)
		(end 207.9216 64.0162)
		(width 0.2032)
		(layer "B.Cu")
		(net "GPS1_RST")
	)
	(segment
		(start 108.3092 69.1038)
		(end 110.9216 71.7162)
		(width 0.2032)
		(layer "B.Cu")
		(net "GPS1_RST")
	)
	(segment
		(start 143.46211 50.0162)
		(end 205.0216 50.0162)
		(width 0.2032)
		(layer "B.Cu")
		(net "GPS1_RST")
	)
	(segment
		(start 128.87423 60.8162)
		(end 132.66211 60.8162)
		(width 0.2032)
		(layer "B.Cu")
		(net "GPS1_RST")
	)
	(segment
		(start 127.17423 62.5162)
		(end 128.87423 60.8162)
		(width 0.2032)
		(layer "B.Cu")
		(net "GPS1_RST")
	)
	(segment
		(start 125.7216 61.8347)
		(end 126.4031 62.5162)
		(width 0.2032)
		(layer "B.Cu")
		(net "GPS1_RST")
	)
	(segment
		(start 184.73146 98.9162)
		(end 185.53146 98.1162)
		(width 0.2032)
		(layer "B.Cu")
		(net "GPS1_RST")
	)
	(segment
		(start 114.8216 57.8162)
		(end 117.5216 60.5162)
		(width 0.2032)
		(layer "B.Cu")
		(net "GPS1_RST")
	)
	(segment
		(start 110.6716 62.49558)
		(end 110.6716 57.60554)
		(width 0.2032)
		(layer "B.Cu")
		(net "GPS1_RST")
	)
	(segment
		(start 204.0216 78.2162)
		(end 206.9216 75.3162)
		(width 0.2032)
		(layer "B.Cu")
		(net "GPS1_RST")
	)
	(segment
		(start 179.74824 100.84284)
		(end 185.45924 106.55384)
		(width 0.2032)
		(layer "B.Cu")
		(net "GPS1_RST")
	)
	(segment
		(start 108.3092 64.85798)
		(end 110.6716 62.49558)
		(width 0.2032)
		(layer "B.Cu")
		(net "GPS1_RST")
	)
	(segment
		(start 205.0216 50.0162)
		(end 207.9216 52.9162)
		(width 0.2032)
		(layer "B.Cu")
		(net "GPS1_RST")
	)
	(segment
		(start 132.66211 60.8162)
		(end 143.46211 50.0162)
		(width 0.2032)
		(layer "B.Cu")
		(net "GPS1_RST")
	)
	(segment
		(start 126.4031 62.5162)
		(end 127.17423 62.5162)
		(width 0.2032)
		(layer "B.Cu")
		(net "GPS1_RST")
	)
	(segment
		(start 110.6716 57.60554)
		(end 111.66094 56.6162)
		(width 0.2032)
		(layer "B.Cu")
		(net "GPS1_RST")
	)
	(segment
		(start 69.9716 135.6162)
		(end 69.9716 135.5786)
		(width 0.2032)
		(layer "F.Cu")
		(net "NetAN4_1")
	)
	(segment
		(start 72.4216 140.3162)
		(end 75.67063 140.3162)
		(width 0.2032)
		(layer "F.Cu")
		(net "NetAN4_1")
	)
	(segment
		(start 75.24723 135.2178)
		(end 75.24723 135.1928)
		(width 0.2032)
		(layer "F.Cu")
		(net "NetAN4_1")
	)
	(segment
		(start 74.6216 134.56717)
		(end 74.6216 132.1162)
		(width 0.2032)
		(layer "F.Cu")
		(net "NetAN4_1")
	)
	(segment
		(start 75.64563 135.6162)
		(end 75.67063 135.6162)
		(width 0.2032)
		(layer "F.Cu")
		(net "NetAN4_1")
	)
	(segment
		(start 74.6216 134.56717)
		(end 75.24723 135.1928)
		(width 0.2032)
		(layer "F.Cu")
		(net "NetAN4_1")
	)
	(segment
		(start 75.24723 135.2178)
		(end 75.64563 135.6162)
		(width 0.2032)
		(layer "F.Cu")
		(net "NetAN4_1")
	)
	(segment
		(start 69.9716 135.6162)
		(end 75.64563 135.6162)
		(width 0.2032)
		(layer "F.Cu")
		(net "NetAN4_1")
	)
	(segment
		(start 75.67063 140.3162)
		(end 75.67063 135.6162)
		(width 0.2032)
		(layer "F.Cu")
		(net "NetAN4_1")
	)
	(segment
		(start 72.82161 130.31621)
		(end 74.6216 132.1162)
		(width 0.2032)
		(layer "F.Cu")
		(net "NetAN4_1")
	)
	(segment
		(start 72.82161 130.31621)
		(end 72.82161 129.2162)
		(width 0.2032)
		(layer "F.Cu")
		(net "NetAN4_1")
	)
	(segment
		(start 73.13722 103.93493)
		(end 73.13722 102.98182)
		(width 0.2032)
		(layer "F.Cu")
		(net "NetAN2_1")
	)
	(segment
		(start 75.0216 109.9162)
		(end 75.67063 109.9162)
		(width 0.2032)
		(layer "F.Cu")
		(net "NetAN2_1")
	)
	(segment
		(start 74.01922 105.61264)
		(end 74.01922 104.81693)
		(width 0.2032)
		(layer "F.Cu")
		(net "NetAN2_1")
	)
	(segment
		(start 69.9716 108.6162)
		(end 75.67063 108.6162)
		(width 0.2032)
		(layer "F.Cu")
		(net "NetAN2_1")
	)
	(segment
		(start 69.9716 108.6162)
		(end 69.9716 108.5782)
		(width 0.2032)
		(layer "F.Cu")
		(net "NetAN2_1")
	)
	(segment
		(start 72.8216 102.6662)
		(end 73.13722 102.98182)
		(width 0.2032)
		(layer "F.Cu")
		(net "NetAN2_1")
	)
	(segment
		(start 74.01922 105.61264)
		(end 75.67063 107.26406)
		(width 0.2032)
		(layer "F.Cu")
		(net "NetAN2_1")
	)
	(segment
		(start 73.13722 103.93493)
		(end 74.01922 104.81693)
		(width 0.2032)
		(layer "F.Cu")
		(net "NetAN2_1")
	)
	(segment
		(start 75.67063 108.6162)
		(end 75.67063 107.26406)
		(width 0.2032)
		(layer "F.Cu")
		(net "NetAN2_1")
	)
	(segment
		(start 75.0216 111.1162)
		(end 75.0216 109.9162)
		(width 0.2032)
		(layer "F.Cu")
		(net "NetAN2_1")
	)
	(segment
		(start 75.67063 109.9162)
		(end 75.67063 108.6162)
		(width 0.2032)
		(layer "F.Cu")
		(net "NetAN2_1")
	)
	(segment
		(start 69.9716 121.8662)
		(end 75.67063 121.8662)
		(width 0.2032)
		(layer "F.Cu")
		(net "NetAN3_1")
	)
	(segment
		(start 69.9716 122.0782)
		(end 69.9716 121.8662)
		(width 0.2032)
		(layer "F.Cu")
		(net "NetAN3_1")
	)
	(segment
		(start 74.4216 123.9162)
		(end 75.67063 123.9162)
		(width 0.2032)
		(layer "F.Cu")
		(net "NetAN3_1")
	)
	(segment
		(start 74.4216 126.4162)
		(end 74.4216 123.9162)
		(width 0.2032)
		(layer "F.Cu")
		(net "NetAN3_1")
	)
	(segment
		(start 72.82161 127.0162)
		(end 72.82161 126.4162)
		(width 0.2032)
		(layer "F.Cu")
		(net "NetAN3_1")
	)
	(segment
		(start 75.67063 123.9162)
		(end 75.67063 121.8662)
		(width 0.2032)
		(layer "F.Cu")
		(net "NetAN3_1")
	)
	(segment
		(start 72.82161 126.4162)
		(end 74.4216 126.4162)
		(width 0.2032)
		(layer "F.Cu")
		(net "NetAN3_1")
	)
	(segment
		(start 74.7216 96.5162)
		(end 75.67063 96.5162)
		(width 0.2032)
		(layer "F.Cu")
		(net "NetAN1_1")
	)
	(segment
		(start 72.8216 100.4662)
		(end 74.0216 100.4662)
		(width 0.2032)
		(layer "F.Cu")
		(net "NetAN1_1")
	)
	(segment
		(start 72.8216 100.4662)
		(end 72.8466 100.4412)
		(width 0.2032)
		(layer "F.Cu")
		(net "NetAN1_1")
	)
	(segment
		(start 69.9716 95.0786)
		(end 75.67063 95.0786)
		(width 0.2032)
		(layer "F.Cu")
		(net "NetAN1_1")
	)
	(segment
		(start 75.67063 96.5162)
		(end 75.67063 95.0786)
		(width 0.2032)
		(layer "F.Cu")
		(net "NetAN1_1")
	)
	(segment
		(start 74.0216 99.7162)
		(end 74.7216 99.7162)
		(width 0.2032)
		(layer "F.Cu")
		(net "NetAN1_1")
	)
	(segment
		(start 74.7216 99.7162)
		(end 74.7216 96.5162)
		(width 0.2032)
		(layer "F.Cu")
		(net "NetAN1_1")
	)
	(segment
		(start 74.0216 100.4662)
		(end 74.0216 99.7162)
		(width 0.2032)
		(layer "F.Cu")
		(net "NetAN1_1")
	)
	(segment
		(start 182.03556 127.2901)
		(end 182.03556 127.10075)
		(width 0.2032)
		(layer "F.Cu")
		(net "LED4")
	)
	(segment
		(start 182.03556 127.2901)
		(end 182.46862 127.72316)
		(width 0.2032)
		(layer "F.Cu")
		(net "LED4")
	)
	(segment
		(start 182.46862 127.72316)
		(end 184.0342 127.72316)
		(width 0.2032)
		(layer "F.Cu")
		(net "LED4")
	)
	(segment
		(start 181.99668 127.06187)
		(end 182.03556 127.10075)
		(width 0.2032)
		(layer "F.Cu")
		(net "LED4")
	)
	(via
		(at 181.99668 127.06187)
		(size 0.4064)
		(drill 0.2032)
		(layers "F.Cu" "B.Cu")
		(tenting
			(front yes)
			(back yes)
		)
		(net "LED4")
	)
	(via
		(at 83.2216 63.9162)
		(size 0.4064)
		(drill 0.2032)
		(layers "F.Cu" "B.Cu")
		(net "LED4")
	)
	(segment
		(start 80.0966 61.10186)
		(end 80.0966 56.2162)
		(width 0.2032)
		(layer "B.Cu")
		(net "LED4")
	)
	(segment
		(start 82.87206 63.87732)
		(end 83.18272 63.87732)
		(width 0.2032)
		(layer "B.Cu")
		(net "LED4")
	)
	(segment
		(start 83.18272 63.87732)
		(end 83.2216 63.9162)
		(width 0.2032)
		(layer "B.Cu")
		(net "LED4")
	)
	(segment
		(start 80.0966 61.10186)
		(end 82.87206 63.87732)
		(width 0.2032)
		(layer "B.Cu")
		(net "LED4")
	)
	(segment
		(start 82.3216 81.317)
		(end 84.71671 78.92189)
		(width 0.2032)
		(layer "In3.Cu")
		(net "LED4")
	)
	(segment
		(start 95.7216 94.4162)
		(end 115.9216 94.4162)
		(width 0.2032)
		(layer "In3.Cu")
		(net "LED4")
	)
	(segment
		(start 141.33239 96.12699)
		(end 143.97711 98.77171)
		(width 0.2032)
		(layer "In3.Cu")
		(net "LED4")
	)
	(segment
		(start 164.0138 110.65033)
		(end 164.0138 106.1084)
		(width 0.2032)
		(layer "In3.Cu")
		(net "LED4")
	)
	(segment
		(start 167.1216 124.5162)
		(end 178.2216 124.5162)
		(width 0.2032)
		(layer "In3.Cu")
		(net "LED4")
	)
	(segment
		(start 140.99936 96.12699)
		(end 141.33239 96.12699)
		(width 0.2032)
		(layer "In3.Cu")
		(net "LED4")
	)
	(segment
		(start 135.6163 95.986)
		(end 140.85837 95.986)
		(width 0.2032)
		(layer "In3.Cu")
		(net "LED4")
	)
	(segment
		(start 82.75699 70.5162)
		(end 84.71671 72.47592)
		(width 0.2032)
		(layer "In3.Cu")
		(net "LED4")
	)
	(segment
		(start 163.7898 105.8844)
		(end 163.7898 102.748)
		(width 0.2032)
		(layer "In3.Cu")
		(net "LED4")
	)
	(segment
		(start 94.5216 93.2162)
		(end 95.7216 94.4162)
		(width 0.2032)
		(layer "In3.Cu")
		(net "LED4")
	)
	(segment
		(start 140.85837 95.986)
		(end 140.99936 96.12699)
		(width 0.2032)
		(layer "In3.Cu")
		(net "LED4")
	)
	(segment
		(start 82.3216 90.6162)
		(end 84.9216 93.2162)
		(width 0.2032)
		(layer "In3.Cu")
		(net "LED4")
	)
	(segment
		(start 163.9216 110.74253)
		(end 164.0138 110.65033)
		(width 0.2032)
		(layer "In3.Cu")
		(net "LED4")
	)
	(segment
		(start 180.76727 127.06187)
		(end 181.99668 127.06187)
		(width 0.2032)
		(layer "In3.Cu")
		(net "LED4")
	)
	(segment
		(start 163.7898 102.748)
		(end 164.42531 102.11249)
		(width 0.2032)
		(layer "In3.Cu")
		(net "LED4")
	)
	(segment
		(start 84.9216 93.2162)
		(end 94.5216 93.2162)
		(width 0.2032)
		(layer "In3.Cu")
		(net "LED4")
	)
	(segment
		(start 82.05216 65.08564)
		(end 83.2216 63.9162)
		(width 0.2032)
		(layer "In3.Cu")
		(net "LED4")
	)
	(segment
		(start 115.9216 94.4162)
		(end 119.0518 91.286)
		(width 0.2032)
		(layer "In3.Cu")
		(net "LED4")
	)
	(segment
		(start 82.3216 90.6162)
		(end 82.3216 81.317)
		(width 0.2032)
		(layer "In3.Cu")
		(net "LED4")
	)
	(segment
		(start 163.9216 121.3162)
		(end 163.9216 110.74253)
		(width 0.2032)
		(layer "In3.Cu")
		(net "LED4")
	)
	(segment
		(start 81.75216 65.08564)
		(end 82.05216 65.08564)
		(width 0.2032)
		(layer "In3.Cu")
		(net "LED4")
	)
	(segment
		(start 80.6216 69.24912)
		(end 80.6216 66.2162)
		(width 0.2032)
		(layer "In3.Cu")
		(net "LED4")
	)
	(segment
		(start 163.9216 121.3162)
		(end 167.1216 124.5162)
		(width 0.2032)
		(layer "In3.Cu")
		(net "LED4")
	)
	(segment
		(start 164.42531 102.11249)
		(end 164.42531 100.85486)
		(width 0.2032)
		(layer "In3.Cu")
		(net "LED4")
	)
	(segment
		(start 80.6216 66.2162)
		(end 81.75216 65.08564)
		(width 0.2032)
		(layer "In3.Cu")
		(net "LED4")
	)
	(segment
		(start 84.71671 78.92189)
		(end 84.71671 72.47592)
		(width 0.2032)
		(layer "In3.Cu")
		(net "LED4")
	)
	(segment
		(start 159.81534 99.28335)
		(end 162.8538 99.28335)
		(width 0.2032)
		(layer "In3.Cu")
		(net "LED4")
	)
	(segment
		(start 159.3037 98.77171)
		(end 159.81534 99.28335)
		(width 0.2032)
		(layer "In3.Cu")
		(net "LED4")
	)
	(segment
		(start 130.91629 91.286)
		(end 135.6163 95.986)
		(width 0.2032)
		(layer "In3.Cu")
		(net "LED4")
	)
	(segment
		(start 119.0518 91.286)
		(end 130.91629 91.286)
		(width 0.2032)
		(layer "In3.Cu")
		(net "LED4")
	)
	(segment
		(start 143.97711 98.77171)
		(end 159.3037 98.77171)
		(width 0.2032)
		(layer "In3.Cu")
		(net "LED4")
	)
	(segment
		(start 80.6216 69.24912)
		(end 81.88868 70.5162)
		(width 0.2032)
		(layer "In3.Cu")
		(net "LED4")
	)
	(segment
		(start 162.8538 99.28335)
		(end 164.42531 100.85486)
		(width 0.2032)
		(layer "In3.Cu")
		(net "LED4")
	)
	(segment
		(start 81.88868 70.5162)
		(end 82.75699 70.5162)
		(width 0.2032)
		(layer "In3.Cu")
		(net "LED4")
	)
	(segment
		(start 178.2216 124.5162)
		(end 180.76727 127.06187)
		(width 0.2032)
		(layer "In3.Cu")
		(net "LED4")
	)
	(segment
		(start 163.7898 105.8844)
		(end 164.0138 106.1084)
		(width 0.2032)
		(layer "In3.Cu")
		(net "LED4")
	)
	(segment
		(start 181.99668 127.86188)
		(end 182.03556 127.90076)
		(width 0.2032)
		(layer "F.Cu")
		(net "LED3")
	)
	(segment
		(start 182.25326 128.22303)
		(end 184.0342 128.22303)
		(width 0.2032)
		(layer "F.Cu")
		(net "LED3")
	)
	(segment
		(start 182.03556 128.00533)
		(end 182.25326 128.22303)
		(width 0.2032)
		(layer "F.Cu")
		(net "LED3")
	)
	(segment
		(start 182.03556 128.00533)
		(end 182.03556 127.90076)
		(width 0.2032)
		(layer "F.Cu")
		(net "LED3")
	)
	(via
		(at 181.99668 127.86188)
		(size 0.4064)
		(drill 0.2032)
		(layers "F.Cu" "B.Cu")
		(tenting
			(front yes)
			(back yes)
		)
		(net "LED3")
	)
	(via
		(at 81.2216 54.7162)
		(size 0.4064)
		(drill 0.2032)
		(layers "F.Cu" "B.Cu")
		(net "LED3")
	)
	(segment
		(start 81.2216 54.7162)
		(end 81.2216 54.6162)
		(width 0.2032)
		(layer "B.Cu")
		(net "LED3")
	)
	(segment
		(start 80.0966 54.4662)
		(end 81.0716 54.4662)
		(width 0.2032)
		(layer "B.Cu")
		(net "LED3")
	)
	(segment
		(start 81.0716 54.4662)
		(end 81.2216 54.6162)
		(width 0.2032)
		(layer "B.Cu")
		(net "LED3")
	)
	(segment
		(start 93.8216 93.7162)
		(end 95.1216 95.0162)
		(width 0.2032)
		(layer "In3.Cu")
		(net "LED3")
	)
	(segment
		(start 83.8216 93.7162)
		(end 93.8216 93.7162)
		(width 0.2032)
		(layer "In3.Cu")
		(net "LED3")
	)
	(segment
		(start 161.6216 101.4162)
		(end 163.34383 103.13843)
		(width 0.2032)
		(layer "In3.Cu")
		(net "LED3")
	)
	(segment
		(start 163.34383 108.24843)
		(end 163.34383 103.13843)
		(width 0.2032)
		(layer "In3.Cu")
		(net "LED3")
	)
	(segment
		(start 163.2216 110.97556)
		(end 163.6836 110.51356)
		(width 0.2032)
		(layer "In3.Cu")
		(net "LED3")
	)
	(segment
		(start 161.6216 101.4162)
		(end 161.6216 100.54314)
		(width 0.2032)
		(layer "In3.Cu")
		(net "LED3")
	)
	(segment
		(start 163.2216 122.5162)
		(end 163.2216 110.97556)
		(width 0.2032)
		(layer "In3.Cu")
		(net "LED3")
	)
	(segment
		(start 140.7216 96.3162)
		(end 143.50731 99.10191)
		(width 0.2032)
		(layer "In3.Cu")
		(net "LED3")
	)
	(segment
		(start 163.34383 108.24843)
		(end 163.6836 108.5882)
		(width 0.2032)
		(layer "In3.Cu")
		(net "LED3")
	)
	(segment
		(start 84.10774 78.13005)
		(end 84.10774 72.50234)
		(width 0.2032)
		(layer "In3.Cu")
		(net "LED3")
	)
	(segment
		(start 81.2216 54.7162)
		(end 81.9966 54.7162)
		(width 0.2032)
		(layer "In3.Cu")
		(net "LED3")
	)
	(segment
		(start 159.16693 99.10191)
		(end 159.76456 99.69954)
		(width 0.2032)
		(layer "In3.Cu")
		(net "LED3")
	)
	(segment
		(start 120.0216 91.6162)
		(end 130.77952 91.6162)
		(width 0.2032)
		(layer "In3.Cu")
		(net "LED3")
	)
	(segment
		(start 83.1216 62.7162)
		(end 83.1216 55.8412)
		(width 0.2032)
		(layer "In3.Cu")
		(net "LED3")
	)
	(segment
		(start 130.77952 91.6162)
		(end 135.47952 96.3162)
		(width 0.2032)
		(layer "In3.Cu")
		(net "LED3")
	)
	(segment
		(start 116.6216 95.0162)
		(end 120.0216 91.6162)
		(width 0.2032)
		(layer "In3.Cu")
		(net "LED3")
	)
	(segment
		(start 79.6216 69.14639)
		(end 79.6216 66.2162)
		(width 0.2032)
		(layer "In3.Cu")
		(net "LED3")
	)
	(segment
		(start 135.47952 96.3162)
		(end 140.7216 96.3162)
		(width 0.2032)
		(layer "In3.Cu")
		(net "LED3")
	)
	(segment
		(start 82.4518 70.8464)
		(end 84.10774 72.50234)
		(width 0.2032)
		(layer "In3.Cu")
		(net "LED3")
	)
	(segment
		(start 160.778 99.69954)
		(end 161.6216 100.54314)
		(width 0.2032)
		(layer "In3.Cu")
		(net "LED3")
	)
	(segment
		(start 95.1216 95.0162)
		(end 116.6216 95.0162)
		(width 0.2032)
		(layer "In3.Cu")
		(net "LED3")
	)
	(segment
		(start 159.76456 99.69954)
		(end 160.778 99.69954)
		(width 0.2032)
		(layer "In3.Cu")
		(net "LED3")
	)
	(segment
		(start 171.3898 124.9844)
		(end 171.7216 125.3162)
		(width 0.2032)
		(layer "In3.Cu")
		(net "LED3")
	)
	(segment
		(start 79.6216 69.14639)
		(end 81.32161 70.8464)
		(width 0.2032)
		(layer "In3.Cu")
		(net "LED3")
	)
	(segment
		(start 178.01529 125.3162)
		(end 180.56097 127.86188)
		(width 0.2032)
		(layer "In3.Cu")
		(net "LED3")
	)
	(segment
		(start 79.6216 66.2162)
		(end 83.1216 62.7162)
		(width 0.2032)
		(layer "In3.Cu")
		(net "LED3")
	)
	(segment
		(start 163.6836 110.51356)
		(end 163.6836 108.5882)
		(width 0.2032)
		(layer "In3.Cu")
		(net "LED3")
	)
	(segment
		(start 180.56097 127.86188)
		(end 181.99668 127.86188)
		(width 0.2032)
		(layer "In3.Cu")
		(net "LED3")
	)
	(segment
		(start 171.7216 125.3162)
		(end 178.01529 125.3162)
		(width 0.2032)
		(layer "In3.Cu")
		(net "LED3")
	)
	(segment
		(start 81.32161 70.8464)
		(end 82.4518 70.8464)
		(width 0.2032)
		(layer "In3.Cu")
		(net "LED3")
	)
	(segment
		(start 165.6898 124.9844)
		(end 171.3898 124.9844)
		(width 0.2032)
		(layer "In3.Cu")
		(net "LED3")
	)
	(segment
		(start 163.2216 122.5162)
		(end 165.6898 124.9844)
		(width 0.2032)
		(layer "In3.Cu")
		(net "LED3")
	)
	(segment
		(start 81.9966 54.7162)
		(end 83.1216 55.8412)
		(width 0.2032)
		(layer "In3.Cu")
		(net "LED3")
	)
	(segment
		(start 81.93274 91.82734)
		(end 83.8216 93.7162)
		(width 0.2032)
		(layer "In3.Cu")
		(net "LED3")
	)
	(segment
		(start 143.50731 99.10191)
		(end 159.16693 99.10191)
		(width 0.2032)
		(layer "In3.Cu")
		(net "LED3")
	)
	(segment
		(start 81.93274 80.30506)
		(end 84.10774 78.13005)
		(width 0.2032)
		(layer "In3.Cu")
		(net "LED3")
	)
	(segment
		(start 81.93274 91.82734)
		(end 81.93274 80.30506)
		(width 0.2032)
		(layer "In3.Cu")
		(net "LED3")
	)
	(segment
		(start 110.54163 154.48357)
		(end 110.97438 154.05081)
		(width 0.508)
		(layer "F.Cu")
		(net "+12V_PCIE")
	)
	(segment
		(start 112.54162 157.7576)
		(end 112.54162 154.4601)
		(width 0.508)
		(layer "F.Cu")
		(net "+12V_PCIE")
	)
	(segment
		(start 111.54162 154.09205)
		(end 111.8576 153.77608)
		(width 0.508)
		(layer "F.Cu")
		(net "+12V_PCIE")
	)
	(segment
		(start 110.54163 157.7576)
		(end 110.54163 154.48357)
		(width 0.508)
		(layer "F.Cu")
		(net "+12V_PCIE")
	)
	(segment
		(start 111.50039 154.05081)
		(end 111.77512 153.77608)
		(width 0.508)
		(layer "F.Cu")
		(net "+12V_PCIE")
	)
	(segment
		(start 110.97438 154.05081)
		(end 111.50039 154.05081)
		(width 0.508)
		(layer "F.Cu")
		(net "+12V_PCIE")
	)
	(segment
		(start 111.54162 157.7576)
		(end 111.54162 154.09205)
		(width 0.508)
		(layer "F.Cu")
		(net "+12V_PCIE")
	)
	(segment
		(start 111.77512 153.77608)
		(end 111.8576 153.77608)
		(width 0.508)
		(layer "F.Cu")
		(net "+12V_PCIE")
	)
	(via
		(at 224.8216 61.9162)
		(size 0.4064)
		(drill 0.254)
		(layers "F.Cu" "B.Cu")
		(net "+12V_PCIE")
	)
	(via
		(at 112.1216 147.0162)
		(size 0.4064)
		(drill 0.2032)
		(layers "F.Cu" "B.Cu")
		(tenting
			(front yes)
			(back yes)
		)
		(net "+12V_PCIE")
	)
	(via
		(at 111.9216 154.0786)
		(size 0.4064)
		(drill 0.2032)
		(layers "F.Cu" "B.Cu")
		(tenting
			(front yes)
			(back yes)
		)
		(net "+12V_PCIE")
	)
	(via
		(at 111.4216 153.2786)
		(size 0.4064)
		(drill 0.2032)
		(layers "F.Cu" "B.Cu")
		(tenting
			(front yes)
			(back yes)
		)
		(net "+12V_PCIE")
	)
	(via
		(at 111.9216 153.2786)
		(size 0.4064)
		(drill 0.2032)
		(layers "F.Cu" "B.Cu")
		(tenting
			(front yes)
			(back yes)
		)
		(net "+12V_PCIE")
	)
	(via
		(at 111.6216 147.0162)
		(size 0.4064)
		(drill 0.2032)
		(layers "F.Cu" "B.Cu")
		(tenting
			(front yes)
			(back yes)
		)
		(net "+12V_PCIE")
	)
	(via
		(at 224.8216 61.1162)
		(size 0.4064)
		(drill 0.254)
		(layers "F.Cu" "B.Cu")
		(net "+12V_PCIE")
	)
	(via
		(at 111.1216 147.0162)
		(size 0.4064)
		(drill 0.2032)
		(layers "F.Cu" "B.Cu")
		(tenting
			(front yes)
			(back yes)
		)
		(net "+12V_PCIE")
	)
	(via
		(at 223.8216 62.7162)
		(size 0.4064)
		(drill 0.254)
		(layers "F.Cu" "B.Cu")
		(net "+12V_PCIE")
	)
	(via
		(at 209.2216 65.8162)
		(size 0.4064)
		(drill 0.254)
		(layers "F.Cu" "B.Cu")
		(net "+12V_PCIE")
	)
	(via
		(at 112.4216 154.0786)
		(size 0.4064)
		(drill 0.2032)
		(layers "F.Cu" "B.Cu")
		(tenting
			(front yes)
			(back yes)
		)
		(net "+12V_PCIE")
	)
	(via
		(at 111.1216 146.2162)
		(size 0.4064)
		(drill 0.2032)
		(layers "F.Cu" "B.Cu")
		(tenting
			(front yes)
			(back yes)
		)
		(net "+12V_PCIE")
	)
	(via
		(at 112.1216 146.2162)
		(size 0.4064)
		(drill 0.2032)
		(layers "F.Cu" "B.Cu")
		(tenting
			(front yes)
			(back yes)
		)
		(net "+12V_PCIE")
	)
	(via
		(at 223.8216 61.9162)
		(size 0.4064)
		(drill 0.254)
		(layers "F.Cu" "B.Cu")
		(net "+12V_PCIE")
	)
	(via
		(at 111.4216 154.0786)
		(size 0.4064)
		(drill 0.2032)
		(layers "F.Cu" "B.Cu")
		(tenting
			(front yes)
			(back yes)
		)
		(net "+12V_PCIE")
	)
	(via
		(at 207.8216 67.4162)
		(size 0.4064)
		(drill 0.254)
		(layers "F.Cu" "B.Cu")
		(net "+12V_PCIE")
	)
	(via
		(at 207.9216 68.3162)
		(size 0.4064)
		(drill 0.254)
		(layers "F.Cu" "B.Cu")
		(net "+12V_PCIE")
	)
	(via
		(at 224.8216 62.7162)
		(size 0.4064)
		(drill 0.254)
		(layers "F.Cu" "B.Cu")
		(net "+12V_PCIE")
	)
	(via
		(at 223.8216 61.1162)
		(size 0.4064)
		(drill 0.254)
		(layers "F.Cu" "B.Cu")
		(net "+12V_PCIE")
	)
	(via
		(at 210.3216 65.8162)
		(size 0.4064)
		(drill 0.254)
		(layers "F.Cu" "B.Cu")
		(net "+12V_PCIE")
	)
	(via
		(at 207.9216 65.8162)
		(size 0.4064)
		(drill 0.254)
		(layers "F.Cu" "B.Cu")
		(net "+12V_PCIE")
	)
	(via
		(at 112.4216 153.2786)
		(size 0.4064)
		(drill 0.2032)
		(layers "F.Cu" "B.Cu")
		(tenting
			(front yes)
			(back yes)
		)
		(net "+12V_PCIE")
	)
	(via
		(at 207.9216 66.6162)
		(size 0.4064)
		(drill 0.254)
		(layers "F.Cu" "B.Cu")
		(net "+12V_PCIE")
	)
	(via
		(at 111.6216 146.2162)
		(size 0.4064)
		(drill 0.2032)
		(layers "F.Cu" "B.Cu")
		(tenting
			(front yes)
			(back yes)
		)
		(net "+12V_PCIE")
	)
	(segment
		(start 111.54162 157.7576)
		(end 111.54162 154.03707)
		(width 0.508)
		(layer "B.Cu")
		(net "+12V_PCIE")
	)
	(segment
		(start 111.8576 153.72109)
		(end 112.54162 154.40511)
		(width 0.508)
		(layer "B.Cu")
		(net "+12V_PCIE")
	)
	(segment
		(start 111.54162 154.03707)
		(end 111.8576 153.72109)
		(width 0.508)
		(layer "B.Cu")
		(net "+12V_PCIE")
	)
	(segment
		(start 112.54162 157.7576)
		(end 112.54162 154.40511)
		(width 0.508)
		(layer "B.Cu")
		(net "+12V_PCIE")
	)
	(segment
		(start 130.67128 139.52876)
		(end 130.67128 132.98678)
		(width 1.27)
		(layer "In2.Cu")
		(net "+12V_PCIE")
	)
	(segment
		(start 130.67128 132.98678)
		(end 132.73219 130.92587)
		(width 1.27)
		(layer "In2.Cu")
		(net "+12V_PCIE")
	)
	(segment
		(start 126.28384 143.9162)
		(end 130.67128 139.52876)
		(width 1.27)
		(layer "In2.Cu")
		(net "+12V_PCIE")
	)
	(segment
		(start 112.4216 143.9162)
		(end 126.28384 143.9162)
		(width 1.27)
		(layer "In2.Cu")
		(net "+12V_PCIE")
	)
	(segment
		(start 117.52161 157.0786)
		(end 117.52161 154.31609)
		(width 0.254)
		(layer "F.Cu")
		(net "+3.3V_PCIE")
	)
	(segment
		(start 117.52161 154.31609)
		(end 118.23123 153.60647)
		(width 0.254)
		(layer "F.Cu")
		(net "+3.3V_PCIE")
	)
	(via
		(at 118.23123 153.60647)
		(size 0.4064)
		(drill 0.2032)
		(layers "F.Cu" "B.Cu")
		(net "+3.3V_PCIE")
	)
	(segment
		(start 118.52161 154.45561)
		(end 119.37282 154.45561)
		(width 0.254)
		(layer "B.Cu")
		(net "+3.3V_PCIE")
	)
	(segment
		(start 119.37282 154.45561)
		(end 119.52161 154.6044)
		(width 0.254)
		(layer "B.Cu")
		(net "+3.3V_PCIE")
	)
	(segment
		(start 118.23123 153.64771)
		(end 118.23123 153.60647)
		(width 0.254)
		(layer "B.Cu")
		(net "+3.3V_PCIE")
	)
	(segment
		(start 118.23123 153.64771)
		(end 118.52161 153.93808)
		(width 0.254)
		(layer "B.Cu")
		(net "+3.3V_PCIE")
	)
	(segment
		(start 118.52161 157.0786)
		(end 118.52161 154.45561)
		(width 0.254)
		(layer "B.Cu")
		(net "+3.3V_PCIE")
	)
	(segment
		(start 118.52161 154.45561)
		(end 118.52161 153.93808)
		(width 0.254)
		(layer "B.Cu")
		(net "+3.3V_PCIE")
	)
	(segment
		(start 119.52161 157.0786)
		(end 119.52161 154.6044)
		(width 0.254)
		(layer "B.Cu")
		(net "+3.3V_PCIE")
	)
	(segment
		(start 105.59629 144.87133)
		(end 105.693 144.99487)
		(width 0.2032)
		(layer "F.Cu")
		(net "PRSNT")
	)
	(segment
		(start 105.3966 144.6162)
		(end 105.3966 143.5162)
		(width 0.2032)
		(layer "F.Cu")
		(net "PRSNT")
	)
	(segment
		(start 113.8216 145.2162)
		(end 114.5216 145.9162)
		(width 0.2032)
		(layer "F.Cu")
		(net "PRSNT")
	)
	(segment
		(start 116.184 150.9786)
		(end 117.4716 150.9786)
		(width 0.2032)
		(layer "F.Cu")
		(net "PRSNT")
	)
	(segment
		(start 114.5216 149.3162)
		(end 116.184 150.9786)
		(width 0.2032)
		(layer "F.Cu")
		(net "PRSNT")
	)
	(segment
		(start 106.18867 145.2162)
		(end 113.8216 145.2162)
		(width 0.2032)
		(layer "F.Cu")
		(net "PRSNT")
	)
	(segment
		(start 105.693 144.99487)
		(end 105.73533 145.04895)
		(width 0.2032)
		(layer "F.Cu")
		(net "PRSNT")
	)
	(segment
		(start 114.5216 149.3162)
		(end 114.5216 145.9162)
		(width 0.2032)
		(layer "F.Cu")
		(net "PRSNT")
	)
	(segment
		(start 105.3966 144.6162)
		(end 105.5653 144.8146)
		(width 0.2032)
		(layer "F.Cu")
		(net "PRSNT")
	)
	(via
		(at 117.4716 150.9786)
		(size 0.4064)
		(drill 0.2032)
		(layers "F.Cu" "B.Cu")
		(tenting
			(front yes)
			(back yes)
		)
		(net "PRSNT")
	)
	(arc
		(start 105.880396 145.144801)
		(mid 105.881197 145.145179)
		(end 105.881996 145.145561)
		(width 0.2032)
		(layer "F.Cu")
		(net "PRSNT")
	)
	(arc
		(start 105.854666 145.134784)
		(mid 105.867701 145.139355)
		(end 105.880396 145.144802)
		(width 0.2032)
		(layer "F.Cu")
		(net "PRSNT")
	)
	(arc
		(start 105.854669 145.134782)
		(mid 105.804002 145.112232)
		(end 105.760257 145.078145)
		(width 0.2032)
		(layer "F.Cu")
		(net "PRSNT")
	)
	(arc
		(start 105.73534 145.048944)
		(mid 105.736769 145.050773)
		(end 105.738178 145.052619)
		(width 0.2032)
		(layer "F.Cu")
		(net "PRSNT")
	)
	(arc
		(start 105.760257 145.078145)
		(mid 105.759956 145.077844)
		(end 105.759655 145.077543)
		(width 0.2032)
		(layer "F.Cu")
		(net "PRSNT")
	)
	(arc
		(start 105.596289 144.871331)
		(mid 105.578523 144.844206)
		(end 105.565299 144.814601)
		(width 0.2032)
		(layer "F.Cu")
		(net "PRSNT")
	)
	(arc
		(start 105.759655 145.077543)
		(mid 105.748464 145.065471)
		(end 105.738171 145.052624)
		(width 0.2032)
		(layer "F.Cu")
		(net "PRSNT")
	)
	(arc
		(start 106.18867 145.2162)
		(mid 106.03132 145.198311)
		(end 105.882001 145.145559)
		(width 0.2032)
		(layer "F.Cu")
		(net "PRSNT")
	)
	(segment
		(start 110.6668 157.13713)
		(end 110.6668 152.75235)
		(width 0.2032)
		(layer "B.Cu")
		(net "PRSNT")
	)
	(segment
		(start 110.6668 152.75235)
		(end 112.44055 150.9786)
		(width 0.2032)
		(layer "B.Cu")
		(net "PRSNT")
	)
	(segment
		(start 110.54163 157.2623)
		(end 110.6668 157.13713)
		(width 0.2032)
		(layer "B.Cu")
		(net "PRSNT")
	)
	(segment
		(start 112.44055 150.9786)
		(end 117.4716 150.9786)
		(width 0.2032)
		(layer "B.Cu")
		(net "PRSNT")
	)
	(segment
		(start 166.5564 138.32715)
		(end 166.5564 136.86372)
		(width 0.127)
		(layer "F.Cu")
		(net "PCIE_TX3_N")
	)
	(segment
		(start 166.5564 136.86372)
		(end 166.56428 136.8716)
		(width 0.127)
		(layer "F.Cu")
		(net "PCIE_TX3_N")
	)
	(via
		(at 141.5716 150.2786)
		(size 0.4064)
		(drill 0.2032)
		(layers "F.Cu" "B.Cu")
		(tenting
			(front yes)
			(back yes)
		)
		(net "PCIE_TX3_N")
	)
	(via
		(at 166.44668 138.43687)
		(size 0.4064)
		(drill 0.2032)
		(layers "F.Cu" "B.Cu")
		(tenting
			(front yes)
			(back yes)
		)
		(net "PCIE_TX3_N")
	)
	(arc
		(start 166.55641 138.32715)
		(mid 166.524271 138.404741)
		(end 166.44668 138.43688)
		(width 0.127)
		(layer "F.Cu")
		(net "PCIE_TX3_N")
	)
	(segment
		(start 141.5716 151.3546)
		(end 141.5756 151.3586)
		(width 0.127)
		(layer "B.Cu")
		(net "PCIE_TX3_N")
	)
	(segment
		(start 141.5716 151.3546)
		(end 141.5716 150.2786)
		(width 0.127)
		(layer "B.Cu")
		(net "PCIE_TX3_N")
	)
	(segment
		(start 141.59553 147.74391)
		(end 141.63889 147.70055)
		(width 0.127)
		(layer "In2.Cu")
		(net "PCIE_TX3_N")
	)
	(segment
		(start 170.801 142.74181)
		(end 170.801 139.4683)
		(width 0.127)
		(layer "In2.Cu")
		(net "PCIE_TX3_N")
	)
	(segment
		(start 170.801 139.4683)
		(end 170.801 139.4683)
		(width 0.127)
		(layer "In2.Cu")
		(net "PCIE_TX3_N")
	)
	(segment
		(start 141.2131 148.16225)
		(end 141.21438 148.16098)
		(width 0.127)
		(layer "In2.Cu")
		(net "PCIE_TX3_N")
	)
	(segment
		(start 167.2216 136.5368)
		(end 168.63876 136.5368)
		(width 0.127)
		(layer "In2.Cu")
		(net "PCIE_TX3_N")
	)
	(segment
		(start 166.65698 137.92537)
		(end 166.65698 137.50478)
		(width 0.127)
		(layer "In2.Cu")
		(net "PCIE_TX3_N")
	)
	(segment
		(start 168.32023 146.39042)
		(end 169.97522 144.73543)
		(width 0.127)
		(layer "In2.Cu")
		(net "PCIE_TX3_N")
	)
	(segment
		(start 166.44668 138.43308)
		(end 166.44668 138.43307)
		(width 0.127)
		(layer "In2.Cu")
		(net "PCIE_TX3_N")
	)
	(segment
		(start 166.44668 138.43687)
		(end 166.44668 138.43308)
		(width 0.127)
		(layer "In2.Cu")
		(net "PCIE_TX3_N")
	)
	(segment
		(start 141.2131 149.41311)
		(end 141.2131 148.16225)
		(width 0.127)
		(layer "In2.Cu")
		(net "PCIE_TX3_N")
	)
	(segment
		(start 169.31917 136.81863)
		(end 169.97522 137.47468)
		(width 0.127)
		(layer "In2.Cu")
		(net "PCIE_TX3_N")
	)
	(segment
		(start 141.24991 148.08953)
		(end 141.59553 147.74391)
		(width 0.127)
		(layer "In2.Cu")
		(net "PCIE_TX3_N")
	)
	(segment
		(start 142.93084 147.2162)
		(end 166.32661 147.2162)
		(width 0.127)
		(layer "In2.Cu")
		(net "PCIE_TX3_N")
	)
	(arc
		(start 167.024034 136.618634)
		(mid 167.114678 136.558068)
		(end 167.2216 136.536799)
		(width 0.127)
		(layer "In2.Cu")
		(net "PCIE_TX3_N")
	)
	(arc
		(start 166.65697 137.50478)
		(mid 166.752365 137.025197)
		(end 167.024027 136.618627)
		(width 0.127)
		(layer "In2.Cu")
		(net "PCIE_TX3_N")
	)
	(arc
		(start 141.613486 147.761866)
		(mid 142.217893 147.358014)
		(end 142.93084 147.2162)
		(width 0.127)
		(layer "In2.Cu")
		(net "PCIE_TX3_N")
	)
	(arc
		(start 166.65698 137.925373)
		(mid 166.602324 138.200141)
		(end 166.446681 138.433079)
		(width 0.127)
		(layer "In2.Cu")
		(net "PCIE_TX3_N")
	)
	(arc
		(start 168.63876 136.5368)
		(mid 169.006993 136.610046)
		(end 169.319166 136.818634)
		(width 0.127)
		(layer "In2.Cu")
		(net "PCIE_TX3_N")
	)
	(arc
		(start 141.53889 150.199638)
		(mid 141.29777 149.838776)
		(end 141.2131 149.41311)
		(width 0.127)
		(layer "In2.Cu")
		(net "PCIE_TX3_N")
	)
	(arc
		(start 141.538893 150.199638)
		(mid 141.5631 150.235867)
		(end 141.5716 150.278601)
		(width 0.127)
		(layer "In2.Cu")
		(net "PCIE_TX3_N")
	)
	(arc
		(start 170.801 142.74181)
		(mid 170.586528 143.820405)
		(end 169.975741 144.734903)
		(width 0.127)
		(layer "In2.Cu")
		(net "PCIE_TX3_N")
	)
	(arc
		(start 141.214376 148.160971)
		(mid 141.226383 148.122383)
		(end 141.249905 148.089522)
		(width 0.127)
		(layer "In2.Cu")
		(net "PCIE_TX3_N")
	)
	(arc
		(start 169.975217 137.474683)
		(mid 170.586386 138.389362)
		(end 170.801 139.4683)
		(width 0.127)
		(layer "In2.Cu")
		(net "PCIE_TX3_N")
	)
	(arc
		(start 168.320227 146.390417)
		(mid 167.405548 147.001586)
		(end 166.32661 147.2162)
		(width 0.127)
		(layer "In2.Cu")
		(net "PCIE_TX3_N")
	)
	(segment
		(start 167.05653 138.34672)
		(end 167.05653 136.86372)
		(width 0.127)
		(layer "F.Cu")
		(net "PCIE_TX3_P")
	)
	(via
		(at 167.14668 138.43687)
		(size 0.4064)
		(drill 0.2032)
		(layers "F.Cu" "B.Cu")
		(tenting
			(front yes)
			(back yes)
		)
		(net "PCIE_TX3_P")
	)
	(via
		(at 140.57521 150.18609)
		(size 0.4064)
		(drill 0.2032)
		(layers "F.Cu" "B.Cu")
		(tenting
			(front yes)
			(back yes)
		)
		(net "PCIE_TX3_P")
	)
	(arc
		(start 167.14668 138.43687)
		(mid 167.082934 138.410466)
		(end 167.05653 138.34672)
		(width 0.127)
		(layer "F.Cu")
		(net "PCIE_TX3_P")
	)
	(segment
		(start 140.57359 150.19377)
		(end 140.57491 150.18639)
		(width 0.127)
		(layer "B.Cu")
		(net "PCIE_TX3_P")
	)
	(segment
		(start 140.57491 150.18639)
		(end 140.57521 150.18609)
		(width 0.127)
		(layer "B.Cu")
		(net "PCIE_TX3_P")
	)
	(segment
		(start 140.5716 151.32962)
		(end 140.5716 150.21614)
		(width 0.127)
		(layer "B.Cu")
		(net "PCIE_TX3_P")
	)
	(arc
		(start 140.5716 150.21614)
		(mid 140.572097 150.20491)
		(end 140.573586 150.193768)
		(width 0.127)
		(layer "B.Cu")
		(net "PCIE_TX3_P")
	)
	(arc
		(start 140.57161 151.32962)
		(mid 140.568491 151.345302)
		(end 140.559607 151.358597)
		(width 0.127)
		(layer "B.Cu")
		(net "PCIE_TX3_P")
	)
	(segment
		(start 167.2216 136.8162)
		(end 168.63876 136.8162)
		(width 0.127)
		(layer "In2.Cu")
		(net "PCIE_TX3_P")
	)
	(segment
		(start 169.1216 137.0162)
		(end 169.77765 137.67224)
		(width 0.127)
		(layer "In2.Cu")
		(net "PCIE_TX3_P")
	)
	(segment
		(start 143.37554 146.77171)
		(end 143.37554 146.77168)
		(width 0.127)
		(layer "In2.Cu")
		(net "PCIE_TX3_P")
	)
	(segment
		(start 140.9337 148.47757)
		(end 140.9337 148.47756)
		(width 0.127)
		(layer "In2.Cu")
		(net "PCIE_TX3_P")
	)
	(segment
		(start 143.18503 146.96221)
		(end 143.18504 146.96221)
		(width 0.127)
		(layer "In2.Cu")
		(net "PCIE_TX3_P")
	)
	(segment
		(start 140.9337 149.47852)
		(end 140.9337 148.47757)
		(width 0.127)
		(layer "In2.Cu")
		(net "PCIE_TX3_P")
	)
	(segment
		(start 140.9337 148.04652)
		(end 141.45929 147.52094)
		(width 0.127)
		(layer "In2.Cu")
		(net "PCIE_TX3_P")
	)
	(segment
		(start 170.547 142.74181)
		(end 170.547 139.4683)
		(width 0.127)
		(layer "In2.Cu")
		(net "PCIE_TX3_P")
	)
	(segment
		(start 148.44652 146.9622)
		(end 164.82071 146.9622)
		(width 0.127)
		(layer "In2.Cu")
		(net "PCIE_TX3_P")
	)
	(segment
		(start 144.51854 146.77171)
		(end 144.51854 146.77168)
		(width 0.127)
		(layer "In2.Cu")
		(net "PCIE_TX3_P")
	)
	(segment
		(start 168.12266 146.19285)
		(end 170.03228 144.28323)
		(width 0.127)
		(layer "In2.Cu")
		(net "PCIE_TX3_P")
	)
	(segment
		(start 167.14668 138.43687)
		(end 167.14668 138.43308)
		(width 0.127)
		(layer "In2.Cu")
		(net "PCIE_TX3_P")
	)
	(segment
		(start 140.9337 148.47756)
		(end 140.9337 148.04652)
		(width 0.127)
		(layer "In2.Cu")
		(net "PCIE_TX3_P")
	)
	(segment
		(start 164.82071 146.9622)
		(end 164.82071 146.9622)
		(width 0.127)
		(layer "In2.Cu")
		(net "PCIE_TX3_P")
	)
	(segment
		(start 166.93638 137.92537)
		(end 166.93638 137.50478)
		(width 0.127)
		(layer "In2.Cu")
		(net "PCIE_TX3_P")
	)
	(segment
		(start 142.82563 146.96221)
		(end 143.12152 146.96221)
		(width 0.127)
		(layer "In2.Cu")
		(net "PCIE_TX3_P")
	)
	(segment
		(start 167.14668 138.43308)
		(end 167.14668 138.43308)
		(width 0.127)
		(layer "In2.Cu")
		(net "PCIE_TX3_P")
	)
	(segment
		(start 140.9337 148.47757)
		(end 140.9337 148.47757)
		(width 0.127)
		(layer "In2.Cu")
		(net "PCIE_TX3_P")
	)
	(segment
		(start 143.75654 146.7717)
		(end 143.75654 146.77168)
		(width 0.127)
		(layer "In2.Cu")
		(net "PCIE_TX3_P")
	)
	(segment
		(start 144.13754 146.7717)
		(end 144.13754 146.77168)
		(width 0.127)
		(layer "In2.Cu")
		(net "PCIE_TX3_P")
	)
	(segment
		(start 148.38302 146.9622)
		(end 148.44652 146.9622)
		(width 0.127)
		(layer "In2.Cu")
		(net "PCIE_TX3_P")
	)
	(segment
		(start 143.12153 146.96221)
		(end 143.18503 146.96221)
		(width 0.127)
		(layer "In2.Cu")
		(net "PCIE_TX3_P")
	)
	(segment
		(start 144.70904 146.96221)
		(end 148.38302 146.9622)
		(width 0.127)
		(layer "In2.Cu")
		(net "PCIE_TX3_P")
	)
	(segment
		(start 164.88202 146.9368)
		(end 166.32661 146.9368)
		(width 0.127)
		(layer "In2.Cu")
		(net "PCIE_TX3_P")
	)
	(arc
		(start 141.59002 147.428561)
		(mid 141.599736 147.424064)
		(end 141.609551 147.419789)
		(width 0.127)
		(layer "In2.Cu")
		(net "PCIE_TX3_P")
	)
	(arc
		(start 170.213489 138.205789)
		(mid 170.216963 138.21105)
		(end 170.220428 138.216318)
		(width 0.127)
		(layer "In2.Cu")
		(net "PCIE_TX3_P")
	)
	(arc
		(start 144.13754 146.7717)
		(mid 143.94704 146.9622)
		(end 143.75654 146.7717)
		(width 0.127)
		(layer "In2.Cu")
		(net "PCIE_TX3_P")
	)
	(arc
		(start 144.70904 146.96221)
		(mid 144.574336 146.906414)
		(end 144.51854 146.77171)
		(width 0.127)
		(layer "In2.Cu")
		(net "PCIE_TX3_P")
	)
	(arc
		(start 170.224489 138.223018)
		(mid 170.465064 138.825116)
		(end 170.547 139.4683)
		(width 0.127)
		(layer "In2.Cu")
		(net "PCIE_TX3_P")
	)
	(arc
		(start 141.636181 147.404218)
		(mid 142.186126 147.09751)
		(end 142.801956 146.966127)
		(width 0.127)
		(layer "In2.Cu")
		(net "PCIE_TX3_P")
	)
	(arc
		(start 168.122661 146.192851)
		(mid 167.298626 146.743454)
		(end 166.32661 146.9368)
		(width 0.127)
		(layer "In2.Cu")
		(net "PCIE_TX3_P")
	)
	(arc
		(start 141.459285 147.520932)
		(mid 141.520711 147.469168)
		(end 141.59002 147.428561)
		(width 0.127)
		(layer "In2.Cu")
		(net "PCIE_TX3_P")
	)
	(arc
		(start 168.63876 136.8162)
		(mid 168.900068 136.868177)
		(end 169.121594 137.016196)
		(width 0.127)
		(layer "In2.Cu")
		(net "PCIE_TX3_P")
	)
	(arc
		(start 143.37554 146.77171)
		(mid 143.319744 146.906414)
		(end 143.18504 146.96221)
		(width 0.127)
		(layer "In2.Cu")
		(net "PCIE_TX3_P")
	)
	(arc
		(start 141.636183 147.404214)
		(mid 141.623341 147.412815)
		(end 141.609549 147.419792)
		(width 0.127)
		(layer "In2.Cu")
		(net "PCIE_TX3_P")
	)
	(arc
		(start 140.9337 149.47852)
		(mid 140.861051 149.843752)
		(end 140.654164 150.153381)
		(width 0.127)
		(layer "In2.Cu")
		(net "PCIE_TX3_P")
	)
	(arc
		(start 140.654173 150.153383)
		(mid 140.617944 150.17759)
		(end 140.57521 150.186091)
		(width 0.127)
		(layer "In2.Cu")
		(net "PCIE_TX3_P")
	)
	(arc
		(start 170.547 142.74181)
		(mid 170.414921 143.554354)
		(end 170.032282 144.283231)
		(width 0.127)
		(layer "In2.Cu")
		(net "PCIE_TX3_P")
	)
	(arc
		(start 143.37554 146.77168)
		(mid 143.56604 146.58118)
		(end 143.75654 146.77168)
		(width 0.127)
		(layer "In2.Cu")
		(net "PCIE_TX3_P")
	)
	(arc
		(start 142.825634 146.9622)
		(mid 142.813889 146.964722)
		(end 142.801959 146.966123)
		(width 0.127)
		(layer "In2.Cu")
		(net "PCIE_TX3_P")
	)
	(arc
		(start 169.777647 137.672248)
		(mid 170.008977 137.928065)
		(end 170.213489 138.205789)
		(width 0.127)
		(layer "In2.Cu")
		(net "PCIE_TX3_P")
	)
	(arc
		(start 170.220426 138.216319)
		(mid 170.222506 138.219636)
		(end 170.224483 138.223015)
		(width 0.127)
		(layer "In2.Cu")
		(net "PCIE_TX3_P")
	)
	(arc
		(start 164.820707 146.962197)
		(mid 164.848838 146.943401)
		(end 164.88202 146.9368)
		(width 0.127)
		(layer "In2.Cu")
		(net "PCIE_TX3_P")
	)
	(arc
		(start 166.93638 137.50478)
		(mid 167.010506 137.132123)
		(end 167.221599 136.8162)
		(width 0.127)
		(layer "In2.Cu")
		(net "PCIE_TX3_P")
	)
	(arc
		(start 144.13754 146.77168)
		(mid 144.32804 146.58118)
		(end 144.51854 146.77168)
		(width 0.127)
		(layer "In2.Cu")
		(net "PCIE_TX3_P")
	)
	(arc
		(start 167.14668 138.43308)
		(mid 166.991034 138.200139)
		(end 166.93638 137.925367)
		(width 0.127)
		(layer "In2.Cu")
		(net "PCIE_TX3_P")
	)
	(segment
		(start 168.05653 143.0131)
		(end 168.05653 140.9135)
		(width 0.127)
		(layer "F.Cu")
		(net "PCIE_TX2_N")
	)
	(via
		(at 137.3716 150.2786)
		(size 0.4064)
		(drill 0.2032)
		(layers "F.Cu" "B.Cu")
		(tenting
			(front yes)
			(back yes)
		)
		(net "PCIE_TX2_N")
	)
	(via
		(at 168.04668 143.03687)
		(size 0.4064)
		(drill 0.2032)
		(layers "F.Cu" "B.Cu")
		(tenting
			(front yes)
			(back yes)
		)
		(net "PCIE_TX2_N")
	)
	(arc
		(start 168.05653 143.0131)
		(mid 168.05397 143.02597)
		(end 168.04668 143.03688)
		(width 0.127)
		(layer "F.Cu")
		(net "PCIE_TX2_N")
	)
	(segment
		(start 137.3716 151.32721)
		(end 137.3716 150.2786)
		(width 0.127)
		(layer "B.Cu")
		(net "PCIE_TX2_N")
	)
	(arc
		(start 137.384599 151.358591)
		(mid 137.374979 151.344193)
		(end 137.371601 151.32721)
		(width 0.127)
		(layer "B.Cu")
		(net "PCIE_TX2_N")
	)
	(segment
		(start 137.0613 150.50319)
		(end 137.0613 150.48196)
		(width 0.127)
		(layer "In2.Cu")
		(net "PCIE_TX2_N")
	)
	(segment
		(start 140.01755 146.03681)
		(end 165.04889 146.03681)
		(width 0.127)
		(layer "In2.Cu")
		(net "PCIE_TX2_N")
	)
	(segment
		(start 136.07711 150.22666)
		(end 136.07716 150.22751)
		(width 0.127)
		(layer "In2.Cu")
		(net "PCIE_TX2_N")
	)
	(segment
		(start 137.89409 147.06489)
		(end 138.14762 146.81136)
		(width 0.127)
		(layer "In2.Cu")
		(net "PCIE_TX2_N")
	)
	(segment
		(start 168.04668 143.03687)
		(end 168.1183 143.1085)
		(width 0.127)
		(layer "In2.Cu")
		(net "PCIE_TX2_N")
	)
	(segment
		(start 166.84495 145.29286)
		(end 168.1183 144.0195)
		(width 0.127)
		(layer "In2.Cu")
		(net "PCIE_TX2_N")
	)
	(segment
		(start 136.29522 149.65497)
		(end 137.79456 148.15566)
		(width 0.127)
		(layer "In2.Cu")
		(net "PCIE_TX2_N")
	)
	(segment
		(start 137.81323 148.11058)
		(end 137.81323 147.26009)
		(width 0.127)
		(layer "In2.Cu")
		(net "PCIE_TX2_N")
	)
	(segment
		(start 136.23785 150.58482)
		(end 136.23853 150.58549)
		(width 0.127)
		(layer "In2.Cu")
		(net "PCIE_TX2_N")
	)
	(segment
		(start 137.79456 148.15566)
		(end 137.79456 148.15565)
		(width 0.127)
		(layer "In2.Cu")
		(net "PCIE_TX2_N")
	)
	(segment
		(start 137.2112 150.33206)
		(end 137.24254 150.33206)
		(width 0.127)
		(layer "In2.Cu")
		(net "PCIE_TX2_N")
	)
	(segment
		(start 136.29466 149.65553)
		(end 136.29522 149.65497)
		(width 0.127)
		(layer "In2.Cu")
		(net "PCIE_TX2_N")
	)
	(segment
		(start 137.89394 147.06503)
		(end 137.89409 147.06489)
		(width 0.127)
		(layer "In2.Cu")
		(net "PCIE_TX2_N")
	)
	(arc
		(start 136.237842 150.584826)
		(mid 136.124842 150.420854)
		(end 136.077159 150.227509)
		(width 0.127)
		(layer "In2.Cu")
		(net "PCIE_TX2_N")
	)
	(arc
		(start 137.81323 148.11058)
		(mid 137.808377 148.134976)
		(end 137.794558 148.155658)
		(width 0.127)
		(layer "In2.Cu")
		(net "PCIE_TX2_N")
	)
	(arc
		(start 168.118304 143.108496)
		(mid 168.257945 143.317483)
		(end 168.30698 143.564)
		(width 0.127)
		(layer "In2.Cu")
		(net "PCIE_TX2_N")
	)
	(arc
		(start 137.0613 150.48196)
		(mid 137.07271 150.424597)
		(end 137.105203 150.375966)
		(width 0.127)
		(layer "In2.Cu")
		(net "PCIE_TX2_N")
	)
	(arc
		(start 137.371601 150.278601)
		(mid 137.312387 150.318166)
		(end 137.24254 150.33206)
		(width 0.127)
		(layer "In2.Cu")
		(net "PCIE_TX2_N")
	)
	(arc
		(start 168.30698 143.564)
		(mid 168.257945 143.810517)
		(end 168.118304 144.019504)
		(width 0.127)
		(layer "In2.Cu")
		(net "PCIE_TX2_N")
	)
	(arc
		(start 138.147613 146.811353)
		(mid 139.005547 146.2381)
		(end 140.01755 146.0368)
		(width 0.127)
		(layer "In2.Cu")
		(net "PCIE_TX2_N")
	)
	(arc
		(start 166.844941 145.292861)
		(mid 166.020906 145.843464)
		(end 165.04889 146.03681)
		(width 0.127)
		(layer "In2.Cu")
		(net "PCIE_TX2_N")
	)
	(arc
		(start 137.0613 150.50319)
		(mid 137.050693 150.553999)
		(end 137.020645 150.596322)
		(width 0.127)
		(layer "In2.Cu")
		(net "PCIE_TX2_N")
	)
	(arc
		(start 136.077103 150.226667)
		(mid 136.125615 149.918146)
		(end 136.294651 149.655534)
		(width 0.127)
		(layer "In2.Cu")
		(net "PCIE_TX2_N")
	)
	(arc
		(start 137.020646 150.596325)
		(mid 136.627409 150.747996)
		(end 136.238525 150.585491)
		(width 0.127)
		(layer "In2.Cu")
		(net "PCIE_TX2_N")
	)
	(arc
		(start 137.81323 147.26009)
		(mid 137.834205 147.154539)
		(end 137.893942 147.065026)
		(width 0.127)
		(layer "In2.Cu")
		(net "PCIE_TX2_N")
	)
	(arc
		(start 137.105205 150.375965)
		(mid 137.153836 150.343471)
		(end 137.2112 150.33206)
		(width 0.127)
		(layer "In2.Cu")
		(net "PCIE_TX2_N")
	)
	(segment
		(start 168.5564 142.33608)
		(end 168.5564 140.9135)
		(width 0.127)
		(layer "F.Cu")
		(net "PCIE_TX2_P")
	)
	(via
		(at 136.54997 150.21916)
		(size 0.4064)
		(drill 0.2032)
		(layers "F.Cu" "B.Cu")
		(tenting
			(front yes)
			(back yes)
		)
		(net "PCIE_TX2_P")
	)
	(via
		(at 168.84668 143.03687)
		(size 0.4064)
		(drill 0.2032)
		(layers "F.Cu" "B.Cu")
		(tenting
			(front yes)
			(back yes)
		)
		(net "PCIE_TX2_P")
	)
	(arc
		(start 168.846671 143.036879)
		(mid 168.631832 142.71535)
		(end 168.556391 142.33608)
		(width 0.127)
		(layer "F.Cu")
		(net "PCIE_TX2_P")
	)
	(segment
		(start 136.4716 151.30066)
		(end 136.4716 150.33546)
		(width 0.127)
		(layer "B.Cu")
		(net "PCIE_TX2_P")
	)
	(arc
		(start 136.471604 150.335451)
		(mid 136.493283 150.265506)
		(end 136.549975 150.219157)
		(width 0.127)
		(layer "B.Cu")
		(net "PCIE_TX2_P")
	)
	(arc
		(start 136.4956 151.3586)
		(mid 136.477838 151.332017)
		(end 136.4716 151.30066)
		(width 0.127)
		(layer "B.Cu")
		(net "PCIE_TX2_P")
	)
	(segment
		(start 168.58637 143.71009)
		(end 168.58637 143.6653)
		(width 0.127)
		(layer "In2.Cu")
		(net "PCIE_TX2_P")
	)
	(segment
		(start 140.09 146.31621)
		(end 165.0489 146.31621)
		(width 0.127)
		(layer "In2.Cu")
		(net "PCIE_TX2_P")
	)
	(segment
		(start 136.46164 150.25308)
		(end 136.49314 150.22158)
		(width 0.127)
		(layer "In2.Cu")
		(net "PCIE_TX2_P")
	)
	(segment
		(start 138.00631 148.40311)
		(end 138.05121 148.35821)
		(width 0.127)
		(layer "In2.Cu")
		(net "PCIE_TX2_P")
	)
	(segment
		(start 136.43462 149.97478)
		(end 136.92867 149.48074)
		(width 0.127)
		(layer "In2.Cu")
		(net "PCIE_TX2_P")
	)
	(segment
		(start 137.68689 148.89193)
		(end 137.83904 149.04408)
		(width 0.127)
		(layer "In2.Cu")
		(net "PCIE_TX2_P")
	)
	(segment
		(start 138.05121 148.35821)
		(end 138.07355 148.33587)
		(width 0.127)
		(layer "In2.Cu")
		(net "PCIE_TX2_P")
	)
	(segment
		(start 136.40611 150.11074)
		(end 136.43462 149.97478)
		(width 0.127)
		(layer "In2.Cu")
		(net "PCIE_TX2_P")
	)
	(segment
		(start 137.41748 149.16134)
		(end 137.56963 149.31349)
		(width 0.127)
		(layer "In2.Cu")
		(net "PCIE_TX2_P")
	)
	(segment
		(start 167.04251 145.49042)
		(end 168.41917 144.11377)
		(width 0.127)
		(layer "In2.Cu")
		(net "PCIE_TX2_P")
	)
	(segment
		(start 138.09263 147.26147)
		(end 138.29395 147.06015)
		(width 0.127)
		(layer "In2.Cu")
		(net "PCIE_TX2_P")
	)
	(segment
		(start 138.09263 147.60044)
		(end 138.09263 147.26147)
		(width 0.127)
		(layer "In2.Cu")
		(net "PCIE_TX2_P")
	)
	(segment
		(start 137.19807 149.48075)
		(end 137.30022 149.5829)
		(width 0.127)
		(layer "In2.Cu")
		(net "PCIE_TX2_P")
	)
	(segment
		(start 138.0063 148.67252)
		(end 138.10845 148.77468)
		(width 0.127)
		(layer "In2.Cu")
		(net "PCIE_TX2_P")
	)
	(segment
		(start 138.05121 148.35821)
		(end 138.05121 148.35821)
		(width 0.127)
		(layer "In2.Cu")
		(net "PCIE_TX2_P")
	)
	(segment
		(start 136.40611 150.11074)
		(end 136.41415 150.13135)
		(width 0.127)
		(layer "In2.Cu")
		(net "PCIE_TX2_P")
	)
	(segment
		(start 138.1113 148.24551)
		(end 138.1113 147.64552)
		(width 0.127)
		(layer "In2.Cu")
		(net "PCIE_TX2_P")
	)
	(segment
		(start 138.0063 148.40311)
		(end 138.00631 148.40311)
		(width 0.127)
		(layer "In2.Cu")
		(net "PCIE_TX2_P")
	)
	(arc
		(start 138.293951 147.060156)
		(mid 139.117986 146.509555)
		(end 140.09 146.31621)
		(width 0.127)
		(layer "In2.Cu")
		(net "PCIE_TX2_P")
	)
	(arc
		(start 137.417486 149.161334)
		(mid 137.36169 149.026631)
		(end 137.417484 148.891928)
		(width 0.127)
		(layer "In2.Cu")
		(net "PCIE_TX2_P")
	)
	(arc
		(start 138.006299 148.672526)
		(mid 137.9505 148.537822)
		(end 138.006296 148.403117)
		(width 0.127)
		(layer "In2.Cu")
		(net "PCIE_TX2_P")
	)
	(arc
		(start 137.417486 148.891936)
		(mid 137.55219 148.83614)
		(end 137.686894 148.891936)
		(width 0.127)
		(layer "In2.Cu")
		(net "PCIE_TX2_P")
	)
	(arc
		(start 138.108451 149.044086)
		(mid 137.973748 149.09988)
		(end 137.839046 149.044083)
		(width 0.127)
		(layer "In2.Cu")
		(net "PCIE_TX2_P")
	)
	(arc
		(start 136.928669 149.480744)
		(mid 137.063372 149.42495)
		(end 137.198074 149.480747)
		(width 0.127)
		(layer "In2.Cu")
		(net "PCIE_TX2_P")
	)
	(arc
		(start 138.1113 148.24551)
		(mid 138.101632 148.294112)
		(end 138.0741 148.335315)
		(width 0.127)
		(layer "In2.Cu")
		(net "PCIE_TX2_P")
	)
	(arc
		(start 137.569631 149.582896)
		(mid 137.434928 149.63869)
		(end 137.300226 149.582893)
		(width 0.127)
		(layer "In2.Cu")
		(net "PCIE_TX2_P")
	)
	(arc
		(start 168.58637 143.6653)
		(mid 168.654021 143.325198)
		(end 168.846673 143.036873)
		(width 0.127)
		(layer "In2.Cu")
		(net "PCIE_TX2_P")
	)
	(arc
		(start 167.042507 145.490427)
		(mid 166.127831 146.101595)
		(end 165.048896 146.31621)
		(width 0.127)
		(layer "In2.Cu")
		(net "PCIE_TX2_P")
	)
	(arc
		(start 137.569634 149.313486)
		(mid 137.62543 149.44819)
		(end 137.569634 149.582894)
		(width 0.127)
		(layer "In2.Cu")
		(net "PCIE_TX2_P")
	)
	(arc
		(start 138.073549 148.335872)
		(mid 138.073828 148.335594)
		(end 138.074107 148.335317)
		(width 0.127)
		(layer "In2.Cu")
		(net "PCIE_TX2_P")
	)
	(arc
		(start 138.108454 148.774676)
		(mid 138.16425 148.90938)
		(end 138.108454 149.044084)
		(width 0.127)
		(layer "In2.Cu")
		(net "PCIE_TX2_P")
	)
	(arc
		(start 138.111302 147.645518)
		(mid 138.097483 147.624836)
		(end 138.09263 147.60044)
		(width 0.127)
		(layer "In2.Cu")
		(net "PCIE_TX2_P")
	)
	(arc
		(start 168.58638 143.71009)
		(mid 168.542924 143.92856)
		(end 168.41917 144.11377)
		(width 0.127)
		(layer "In2.Cu")
		(net "PCIE_TX2_P")
	)
	(segment
		(start 164.74667 142.92405)
		(end 164.74668 142.92486)
		(width 0.127)
		(layer "F.Cu")
		(net "PCIE_TX1_N")
	)
	(segment
		(start 165.05653 142.17599)
		(end 165.05653 140.9135)
		(width 0.127)
		(layer "F.Cu")
		(net "PCIE_TX1_N")
	)
	(segment
		(start 164.74668 143.03687)
		(end 164.74668 142.92486)
		(width 0.127)
		(layer "F.Cu")
		(net "PCIE_TX1_N")
	)
	(via
		(at 164.74668 143.03687)
		(size 0.4064)
		(drill 0.2032)
		(layers "F.Cu" "B.Cu")
		(tenting
			(front yes)
			(back yes)
		)
		(net "PCIE_TX1_N")
	)
	(via
		(at 133.5716 150.2786)
		(size 0.4064)
		(drill 0.2032)
		(layers "F.Cu" "B.Cu")
		(tenting
			(front yes)
			(back yes)
		)
		(net "PCIE_TX1_N")
	)
	(arc
		(start 164.74667 142.92405)
		(mid 164.799445 142.658735)
		(end 164.949734 142.433812)
		(width 0.127)
		(layer "F.Cu")
		(net "PCIE_TX1_N")
	)
	(arc
		(start 165.05653 142.17599)
		(mid 165.028776 142.31552)
		(end 164.949738 142.433808)
		(width 0.127)
		(layer "F.Cu")
		(net "PCIE_TX1_N")
	)
	(segment
		(start 133.5716 151.3556)
		(end 133.5716 150.2786)
		(width 0.127)
		(layer "B.Cu")
		(net "PCIE_TX1_N")
	)
	(segment
		(start 133.5716 151.3556)
		(end 133.5746 151.3586)
		(width 0.127)
		(layer "B.Cu")
		(net "PCIE_TX1_N")
	)
	(segment
		(start 134.24014 147.40996)
		(end 134.2914 147.40996)
		(width 0.127)
		(layer "In2.Cu")
		(net "PCIE_TX1_N")
	)
	(segment
		(start 134.24014 147.79096)
		(end 134.3168 147.79096)
		(width 0.127)
		(layer "In2.Cu")
		(net "PCIE_TX1_N")
	)
	(segment
		(start 134.63335 146.40931)
		(end 136.08008 144.96258)
		(width 0.127)
		(layer "In2.Cu")
		(net "PCIE_TX1_N")
	)
	(segment
		(start 134.29138 148.93396)
		(end 134.3168 148.93396)
		(width 0.127)
		(layer "In2.Cu")
		(net "PCIE_TX1_N")
	)
	(segment
		(start 134.36722 150.19983)
		(end 134.4819 149.82947)
		(width 0.127)
		(layer "In2.Cu")
		(net "PCIE_TX1_N")
	)
	(segment
		(start 157.75298 145.2368)
		(end 162.5489 145.2368)
		(width 0.127)
		(layer "In2.Cu")
		(net "PCIE_TX1_N")
	)
	(segment
		(start 138.0737 144.1368)
		(end 155.09734 144.1368)
		(width 0.127)
		(layer "In2.Cu")
		(net "PCIE_TX1_N")
	)
	(segment
		(start 164.34495 144.49285)
		(end 164.73429 144.10351)
		(width 0.127)
		(layer "In2.Cu")
		(net "PCIE_TX1_N")
	)
	(segment
		(start 134.26986 148.55296)
		(end 134.3168 148.55296)
		(width 0.127)
		(layer "In2.Cu")
		(net "PCIE_TX1_N")
	)
	(segment
		(start 134.4819 147.21946)
		(end 134.4819 146.77495)
		(width 0.127)
		(layer "In2.Cu")
		(net "PCIE_TX1_N")
	)
	(segment
		(start 134.3497 150.2242)
		(end 134.35011 150.22366)
		(width 0.127)
		(layer "In2.Cu")
		(net "PCIE_TX1_N")
	)
	(segment
		(start 164.74668 143.04067)
		(end 164.74668 143.03687)
		(width 0.127)
		(layer "In2.Cu")
		(net "PCIE_TX1_N")
	)
	(segment
		(start 133.5716 150.27861)
		(end 133.5716 150.2786)
		(width 0.127)
		(layer "In2.Cu")
		(net "PCIE_TX1_N")
	)
	(segment
		(start 164.74668 143.04067)
		(end 164.85183 143.14582)
		(width 0.127)
		(layer "In2.Cu")
		(net "PCIE_TX1_N")
	)
	(segment
		(start 164.95698 143.5659)
		(end 164.95698 143.39967)
		(width 0.127)
		(layer "In2.Cu")
		(net "PCIE_TX1_N")
	)
	(segment
		(start 134.4819 149.82947)
		(end 134.4819 149.50546)
		(width 0.127)
		(layer "In2.Cu")
		(net "PCIE_TX1_N")
	)
	(segment
		(start 134.26986 148.17196)
		(end 134.3168 148.17196)
		(width 0.127)
		(layer "In2.Cu")
		(net "PCIE_TX1_N")
	)
	(segment
		(start 134.29138 149.31496)
		(end 134.2914 149.31496)
		(width 0.127)
		(layer "In2.Cu")
		(net "PCIE_TX1_N")
	)
	(arc
		(start 134.3168 147.79096)
		(mid 134.5073 147.98146)
		(end 134.3168 148.17196)
		(width 0.127)
		(layer "In2.Cu")
		(net "PCIE_TX1_N")
	)
	(arc
		(start 136.080083 144.962583)
		(mid 136.994762 144.351414)
		(end 138.0737 144.1368)
		(width 0.127)
		(layer "In2.Cu")
		(net "PCIE_TX1_N")
	)
	(arc
		(start 134.349693 150.2242)
		(mid 134.333658 150.244175)
		(end 134.316657 150.263335)
		(width 0.127)
		(layer "In2.Cu")
		(net "PCIE_TX1_N")
	)
	(arc
		(start 155.09734 144.1368)
		(mid 155.596229 144.236035)
		(end 156.019167 144.518633)
		(width 0.127)
		(layer "In2.Cu")
		(net "PCIE_TX1_N")
	)
	(arc
		(start 134.3168 148.55296)
		(mid 134.5073 148.74346)
		(end 134.3168 148.93396)
		(width 0.127)
		(layer "In2.Cu")
		(net "PCIE_TX1_N")
	)
	(arc
		(start 134.316658 150.263333)
		(mid 133.947356 150.42845)
		(end 133.571597 150.278605)
		(width 0.127)
		(layer "In2.Cu")
		(net "PCIE_TX1_N")
	)
	(arc
		(start 164.851831 143.145819)
		(mid 164.929652 143.262287)
		(end 164.95698 143.39967)
		(width 0.127)
		(layer "In2.Cu")
		(net "PCIE_TX1_N")
	)
	(arc
		(start 134.367218 150.199832)
		(mid 134.358793 150.211841)
		(end 134.350102 150.223659)
		(width 0.127)
		(layer "In2.Cu")
		(net "PCIE_TX1_N")
	)
	(arc
		(start 134.29138 149.31496)
		(mid 134.10088 149.12446)
		(end 134.29138 148.93396)
		(width 0.127)
		(layer "In2.Cu")
		(net "PCIE_TX1_N")
	)
	(arc
		(start 134.2914 149.31496)
		(mid 134.426104 149.370756)
		(end 134.4819 149.50546)
		(width 0.127)
		(layer "In2.Cu")
		(net "PCIE_TX1_N")
	)
	(arc
		(start 134.4819 146.77495)
		(mid 134.521261 146.577068)
		(end 134.633352 146.409312)
		(width 0.127)
		(layer "In2.Cu")
		(net "PCIE_TX1_N")
	)
	(arc
		(start 134.24014 147.79096)
		(mid 134.04964 147.60046)
		(end 134.24014 147.40996)
		(width 0.127)
		(layer "In2.Cu")
		(net "PCIE_TX1_N")
	)
	(arc
		(start 164.95698 143.5659)
		(mid 164.899106 143.856854)
		(end 164.734293 144.103513)
		(width 0.127)
		(layer "In2.Cu")
		(net "PCIE_TX1_N")
	)
	(arc
		(start 134.4819 147.21946)
		(mid 134.426104 147.354164)
		(end 134.2914 147.40996)
		(width 0.127)
		(layer "In2.Cu")
		(net "PCIE_TX1_N")
	)
	(arc
		(start 164.344951 144.492851)
		(mid 163.520916 145.043454)
		(end 162.5489 145.2368)
		(width 0.127)
		(layer "In2.Cu")
		(net "PCIE_TX1_N")
	)
	(arc
		(start 157.75298 145.2368)
		(mid 156.814648 145.050154)
		(end 156.019168 144.518632)
		(width 0.127)
		(layer "In2.Cu")
		(net "PCIE_TX1_N")
	)
	(arc
		(start 134.26986 148.55296)
		(mid 134.07936 148.36246)
		(end 134.26986 148.17196)
		(width 0.127)
		(layer "In2.Cu")
		(net "PCIE_TX1_N")
	)
	(segment
		(start 165.5564 142.77197)
		(end 165.5564 140.9135)
		(width 0.127)
		(layer "F.Cu")
		(net "PCIE_TX1_P")
	)
	(via
		(at 132.5716 150.2786)
		(size 0.4064)
		(drill 0.2032)
		(layers "F.Cu" "B.Cu")
		(tenting
			(front yes)
			(back yes)
		)
		(net "PCIE_TX1_P")
	)
	(via
		(at 165.44668 143.03687)
		(size 0.4064)
		(drill 0.2032)
		(layers "F.Cu" "B.Cu")
		(tenting
			(front yes)
			(back yes)
		)
		(net "PCIE_TX1_P")
	)
	(arc
		(start 165.55641 142.77197)
		(mid 165.527892 142.915339)
		(end 165.44668 143.03688)
		(width 0.127)
		(layer "F.Cu")
		(net "PCIE_TX1_P")
	)
	(segment
		(start 132.5716 151.32721)
		(end 132.5716 150.2786)
		(width 0.127)
		(layer "B.Cu")
		(net "PCIE_TX1_P")
	)
	(arc
		(start 132.5716 151.32721)
		(mid 132.568222 151.344193)
		(end 132.558601 151.358591)
		(width 0.127)
		(layer "B.Cu")
		(net "PCIE_TX1_P")
	)
	(segment
		(start 134.8278 146.61)
		(end 136.5216 144.9162)
		(width 0.127)
		(layer "In2.Cu")
		(net "PCIE_TX1_P")
	)
	(segment
		(start 157.75298 145.5162)
		(end 162.5489 145.5162)
		(width 0.127)
		(layer "In2.Cu")
		(net "PCIE_TX1_P")
	)
	(segment
		(start 132.72779 150.4348)
		(end 132.72779 150.4348)
		(width 0.127)
		(layer "In2.Cu")
		(net "PCIE_TX1_P")
	)
	(segment
		(start 164.54251 144.69042)
		(end 165.01916 144.21377)
		(width 0.127)
		(layer "In2.Cu")
		(net "PCIE_TX1_P")
	)
	(segment
		(start 134.7613 149.8509)
		(end 134.7613 149.84976)
		(width 0.127)
		(layer "In2.Cu")
		(net "PCIE_TX1_P")
	)
	(segment
		(start 137.7287 144.4162)
		(end 155.09735 144.4162)
		(width 0.127)
		(layer "In2.Cu")
		(net "PCIE_TX1_P")
	)
	(segment
		(start 165.23638 143.68937)
		(end 165.23638 143.39967)
		(width 0.127)
		(layer "In2.Cu")
		(net "PCIE_TX1_P")
	)
	(segment
		(start 134.7613 149.84976)
		(end 134.7613 146.77053)
		(width 0.127)
		(layer "In2.Cu")
		(net "PCIE_TX1_P")
	)
	(segment
		(start 165.34152 143.14582)
		(end 165.44668 143.04067)
		(width 0.127)
		(layer "In2.Cu")
		(net "PCIE_TX1_P")
	)
	(segment
		(start 134.82764 146.61016)
		(end 134.8278 146.61)
		(width 0.127)
		(layer "In2.Cu")
		(net "PCIE_TX1_P")
	)
	(segment
		(start 132.5716 150.2786)
		(end 132.72779 150.4348)
		(width 0.127)
		(layer "In2.Cu")
		(net "PCIE_TX1_P")
	)
	(segment
		(start 165.44668 143.04067)
		(end 165.44668 143.03687)
		(width 0.127)
		(layer "In2.Cu")
		(net "PCIE_TX1_P")
	)
	(arc
		(start 137.704978 144.417436)
		(mid 137.713172 144.416559)
		(end 137.721406 144.416216)
		(width 0.127)
		(layer "In2.Cu")
		(net "PCIE_TX1_P")
	)
	(arc
		(start 165.23637 143.39967)
		(mid 165.263697 143.262287)
		(end 165.341519 143.145819)
		(width 0.127)
		(layer "In2.Cu")
		(net "PCIE_TX1_P")
	)
	(arc
		(start 155.09735 144.4162)
		(mid 155.489314 144.494166)
		(end 155.821604 144.716196)
		(width 0.127)
		(layer "In2.Cu")
		(net "PCIE_TX1_P")
	)
	(arc
		(start 157.75298 145.5162)
		(mid 156.707726 145.308286)
		(end 155.821603 144.716197)
		(width 0.127)
		(layer "In2.Cu")
		(net "PCIE_TX1_P")
	)
	(arc
		(start 134.7613 146.77053)
		(mid 134.778538 146.683752)
		(end 134.827636 146.610151)
		(width 0.127)
		(layer "In2.Cu")
		(net "PCIE_TX1_P")
	)
	(arc
		(start 136.539357 144.900217)
		(mid 137.092028 144.586054)
		(end 137.704981 144.417436)
		(width 0.127)
		(layer "In2.Cu")
		(net "PCIE_TX1_P")
	)
	(arc
		(start 134.342913 150.613118)
		(mid 133.503985 150.808083)
		(end 132.727797 150.434794)
		(width 0.127)
		(layer "In2.Cu")
		(net "PCIE_TX1_P")
	)
	(arc
		(start 137.721408 144.416216)
		(mid 137.725054 144.416204)
		(end 137.7287 144.4162)
		(width 0.127)
		(layer "In2.Cu")
		(net "PCIE_TX1_P")
	)
	(arc
		(start 164.542517 144.690417)
		(mid 163.627838 145.301586)
		(end 162.5489 145.5162)
		(width 0.127)
		(layer "In2.Cu")
		(net "PCIE_TX1_P")
	)
	(arc
		(start 134.76129 149.850895)
		(mid 134.649816 150.285644)
		(end 134.342906 150.613118)
		(width 0.127)
		(layer "In2.Cu")
		(net "PCIE_TX1_P")
	)
	(arc
		(start 136.526911 144.910915)
		(mid 136.532961 144.905367)
		(end 136.539356 144.900221)
		(width 0.127)
		(layer "In2.Cu")
		(net "PCIE_TX1_P")
	)
	(arc
		(start 165.23637 143.68937)
		(mid 165.179918 143.973172)
		(end 165.019157 144.213767)
		(width 0.127)
		(layer "In2.Cu")
		(net "PCIE_TX1_P")
	)
	(arc
		(start 136.521598 144.916198)
		(mid 136.524251 144.91355)
		(end 136.526911 144.910909)
		(width 0.127)
		(layer "In2.Cu")
		(net "PCIE_TX1_P")
	)
	(segment
		(start 163.47323 138.13387)
		(end 163.50983 138.09728)
		(width 0.127)
		(layer "F.Cu")
		(net "PCIE_TX0_N")
	)
	(segment
		(start 163.50983 138.09728)
		(end 163.50983 136.91031)
		(width 0.127)
		(layer "F.Cu")
		(net "PCIE_TX0_N")
	)
	(segment
		(start 163.50983 136.91031)
		(end 163.55641 136.86372)
		(width 0.127)
		(layer "F.Cu")
		(net "PCIE_TX0_N")
	)
	(via
		(at 128.6716 150.2786)
		(size 0.4064)
		(drill 0.2032)
		(layers "F.Cu" "B.Cu")
		(tenting
			(front yes)
			(back yes)
		)
		(net "PCIE_TX0_N")
	)
	(via
		(at 163.47323 138.13387)
		(size 0.4064)
		(drill 0.2032)
		(layers "F.Cu" "B.Cu")
		(tenting
			(front yes)
			(back yes)
		)
		(net "PCIE_TX0_N")
	)
	(segment
		(start 128.6716 151.3578)
		(end 128.6724 151.3586)
		(width 0.127)
		(layer "B.Cu")
		(net "PCIE_TX0_N")
	)
	(segment
		(start 128.6716 151.3578)
		(end 128.6716 150.2786)
		(width 0.127)
		(layer "B.Cu")
		(net "PCIE_TX0_N")
	)
	(segment
		(start 159.80963 140.157)
		(end 161.75466 140.157)
		(width 0.127)
		(layer "In2.Cu")
		(net "PCIE_TX0_N")
	)
	(segment
		(start 161.75583 140.15816)
		(end 163.42146 140.15816)
		(width 0.127)
		(layer "In2.Cu")
		(net "PCIE_TX0_N")
	)
	(segment
		(start 127.8188 150.66721)
		(end 127.81994 150.66721)
		(width 0.127)
		(layer "In2.Cu")
		(net "PCIE_TX0_N")
	)
	(segment
		(start 163.42146 140.15816)
		(end 163.48561 140.09401)
		(width 0.127)
		(layer "In2.Cu")
		(net "PCIE_TX0_N")
	)
	(segment
		(start 156.86311 138.26258)
		(end 158.01358 139.41305)
		(width 0.127)
		(layer "In2.Cu")
		(net "PCIE_TX0_N")
	)
	(segment
		(start 126.37064 149.90496)
		(end 126.59924 150.13357)
		(width 0.127)
		(layer "In2.Cu")
		(net "PCIE_TX0_N")
	)
	(segment
		(start 127.53849 150.66721)
		(end 127.8188 150.66721)
		(width 0.127)
		(layer "In2.Cu")
		(net "PCIE_TX0_N")
	)
	(segment
		(start 126.37064 149.90496)
		(end 126.37064 149.90496)
		(width 0.127)
		(layer "In2.Cu")
		(net "PCIE_TX0_N")
	)
	(segment
		(start 126.59924 150.13357)
		(end 126.91363 150.44796)
		(width 0.127)
		(layer "In2.Cu")
		(net "PCIE_TX0_N")
	)
	(segment
		(start 161.75466 140.157)
		(end 161.75583 140.15816)
		(width 0.127)
		(layer "In2.Cu")
		(net "PCIE_TX0_N")
	)
	(segment
		(start 126.2126 149.52344)
		(end 126.2126 148.95472)
		(width 0.127)
		(layer "In2.Cu")
		(net "PCIE_TX0_N")
	)
	(segment
		(start 127.53849 150.66721)
		(end 127.53849 150.66721)
		(width 0.127)
		(layer "In2.Cu")
		(net "PCIE_TX0_N")
	)
	(segment
		(start 163.68353 139.6162)
		(end 163.68353 138.64538)
		(width 0.127)
		(layer "In2.Cu")
		(net "PCIE_TX0_N")
	)
	(segment
		(start 136.0216 137.4368)
		(end 154.8695 137.4368)
		(width 0.127)
		(layer "In2.Cu")
		(net "PCIE_TX0_N")
	)
	(segment
		(start 134.26766 138.9404)
		(end 134.26786 138.9402)
		(width 0.127)
		(layer "In2.Cu")
		(net "PCIE_TX0_N")
	)
	(segment
		(start 127.03741 146.96346)
		(end 133.70726 140.29361)
		(width 0.127)
		(layer "In2.Cu")
		(net "PCIE_TX0_N")
	)
	(segment
		(start 127.31775 150.6162)
		(end 127.3716 150.6162)
		(width 0.127)
		(layer "In2.Cu")
		(net "PCIE_TX0_N")
	)
	(segment
		(start 134.26786 138.9402)
		(end 135.59425 137.61381)
		(width 0.127)
		(layer "In2.Cu")
		(net "PCIE_TX0_N")
	)
	(segment
		(start 127.81994 150.66721)
		(end 128.28299 150.66721)
		(width 0.127)
		(layer "In2.Cu")
		(net "PCIE_TX0_N")
	)
	(segment
		(start 163.47323 138.13767)
		(end 163.47323 138.13387)
		(width 0.127)
		(layer "In2.Cu")
		(net "PCIE_TX0_N")
	)
	(arc
		(start 154.8695 137.4368)
		(mid 155.948438 137.651414)
		(end 156.863117 138.262583)
		(width 0.127)
		(layer "In2.Cu")
		(net "PCIE_TX0_N")
	)
	(arc
		(start 135.594253 137.613813)
		(mid 135.790321 137.482804)
		(end 136.0216 137.4368)
		(width 0.127)
		(layer "In2.Cu")
		(net "PCIE_TX0_N")
	)
	(arc
		(start 128.6716 150.2786)
		(mid 128.557779 150.553389)
		(end 128.28299 150.66721)
		(width 0.127)
		(layer "In2.Cu")
		(net "PCIE_TX0_N")
	)
	(arc
		(start 163.47323 138.13767)
		(mid 163.628875 138.370609)
		(end 163.68353 138.64538)
		(width 0.127)
		(layer "In2.Cu")
		(net "PCIE_TX0_N")
	)
	(arc
		(start 126.370633 149.904967)
		(mid 126.253671 149.729921)
		(end 126.212599 149.52344)
		(width 0.127)
		(layer "In2.Cu")
		(net "PCIE_TX0_N")
	)
	(arc
		(start 163.68353 139.6162)
		(mid 163.632093 139.874791)
		(end 163.485613 140.094013)
		(width 0.127)
		(layer "In2.Cu")
		(net "PCIE_TX0_N")
	)
	(arc
		(start 127.317745 150.61621)
		(mid 127.098846 150.57253)
		(end 126.913622 150.447962)
		(width 0.127)
		(layer "In2.Cu")
		(net "PCIE_TX0_N")
	)
	(arc
		(start 159.80963 140.157)
		(mid 158.837613 139.963654)
		(end 158.013578 139.41305)
		(width 0.127)
		(layer "In2.Cu")
		(net "PCIE_TX0_N")
	)
	(arc
		(start 134.18603 139.13776)
		(mid 134.207244 139.030968)
		(end 134.267666 138.940393)
		(width 0.127)
		(layer "In2.Cu")
		(net "PCIE_TX0_N")
	)
	(arc
		(start 126.2126 148.95472)
		(mid 126.426961 147.877057)
		(end 127.037408 146.963458)
		(width 0.127)
		(layer "In2.Cu")
		(net "PCIE_TX0_N")
	)
	(arc
		(start 127.538485 150.667207)
		(mid 127.50231 150.661706)
		(end 127.469205 150.64612)
		(width 0.127)
		(layer "In2.Cu")
		(net "PCIE_TX0_N")
	)
	(arc
		(start 134.18603 139.13776)
		(mid 134.061603 139.763298)
		(end 133.707264 140.293604)
		(width 0.127)
		(layer "In2.Cu")
		(net "PCIE_TX0_N")
	)
	(arc
		(start 127.3716 150.6162)
		(mid 127.422646 150.623849)
		(end 127.469209 150.646123)
		(width 0.127)
		(layer "In2.Cu")
		(net "PCIE_TX0_N")
	)
	(segment
		(start 164.05653 137.94157)
		(end 164.17323 138.05827)
		(width 0.127)
		(layer "F.Cu")
		(net "PCIE_TX0_P")
	)
	(segment
		(start 164.17323 138.13387)
		(end 164.17323 138.05827)
		(width 0.127)
		(layer "F.Cu")
		(net "PCIE_TX0_P")
	)
	(segment
		(start 164.05653 137.94157)
		(end 164.05653 136.86372)
		(width 0.127)
		(layer "F.Cu")
		(net "PCIE_TX0_P")
	)
	(via
		(at 127.60662 150.1395)
		(size 0.4064)
		(drill 0.2032)
		(layers "F.Cu" "B.Cu")
		(tenting
			(front yes)
			(back yes)
		)
		(net "PCIE_TX0_P")
	)
	(via
		(at 164.17323 138.13387)
		(size 0.4064)
		(drill 0.2032)
		(layers "F.Cu" "B.Cu")
		(tenting
			(front yes)
			(back yes)
		)
		(net "PCIE_TX0_P")
	)
	(segment
		(start 127.5716 151.35)
		(end 127.5802 151.3586)
		(width 0.127)
		(layer "B.Cu")
		(net "PCIE_TX0_P")
	)
	(segment
		(start 127.60632 150.1398)
		(end 127.60662 150.1395)
		(width 0.127)
		(layer "B.Cu")
		(net "PCIE_TX0_P")
	)
	(segment
		(start 127.5716 150.29143)
		(end 127.57229 150.22501)
		(width 0.127)
		(layer "B.Cu")
		(net "PCIE_TX0_P")
	)
	(segment
		(start 127.605 150.14126)
		(end 127.60632 150.1398)
		(width 0.127)
		(layer "B.Cu")
		(net "PCIE_TX0_P")
	)
	(segment
		(start 127.5716 151.35)
		(end 127.5716 150.29143)
		(width 0.127)
		(layer "B.Cu")
		(net "PCIE_TX0_P")
	)
	(arc
		(start 127.572297 150.225012)
		(mid 127.580989 150.180146)
		(end 127.605 150.141261)
		(width 0.127)
		(layer "B.Cu")
		(net "PCIE_TX0_P")
	)
	(segment
		(start 135.79182 137.81138)
		(end 135.79202 137.81118)
		(width 0.127)
		(layer "In2.Cu")
		(net "PCIE_TX0_P")
	)
	(segment
		(start 129.5971 145.05252)
		(end 129.6303 145.08572)
		(width 0.127)
		(layer "In2.Cu")
		(net "PCIE_TX0_P")
	)
	(segment
		(start 156.66555 138.46015)
		(end 157.81602 139.61061)
		(width 0.127)
		(layer "In2.Cu")
		(net "PCIE_TX0_P")
	)
	(segment
		(start 163.96293 139.6162)
		(end 163.96293 138.64538)
		(width 0.127)
		(layer "In2.Cu")
		(net "PCIE_TX0_P")
	)
	(segment
		(start 127.60037 150.1417)
		(end 127.60632 150.13979)
		(width 0.127)
		(layer "In2.Cu")
		(net "PCIE_TX0_P")
	)
	(segment
		(start 127.94363 146.45237)
		(end 128.25795 146.13805)
		(width 0.127)
		(layer "In2.Cu")
		(net "PCIE_TX0_P")
	)
	(segment
		(start 161.63893 140.4364)
		(end 161.6401 140.43756)
		(width 0.127)
		(layer "In2.Cu")
		(net "PCIE_TX0_P")
	)
	(segment
		(start 129.8744 144.79101)
		(end 129.8744 144.79101)
		(width 0.127)
		(layer "In2.Cu")
		(net "PCIE_TX0_P")
	)
	(segment
		(start 128.78888 145.86075)
		(end 128.82208 145.89395)
		(width 0.127)
		(layer "In2.Cu")
		(net "PCIE_TX0_P")
	)
	(segment
		(start 126.492 149.52343)
		(end 126.492 148.9561)
		(width 0.127)
		(layer "In2.Cu")
		(net "PCIE_TX0_P")
	)
	(segment
		(start 127.60632 150.13979)
		(end 127.60662 150.1395)
		(width 0.127)
		(layer "In2.Cu")
		(net "PCIE_TX0_P")
	)
	(segment
		(start 131.18221 143.21379)
		(end 133.90483 140.49117)
		(width 0.127)
		(layer "In2.Cu")
		(net "PCIE_TX0_P")
	)
	(segment
		(start 127.23595 147.16005)
		(end 127.94363 146.45237)
		(width 0.127)
		(layer "In2.Cu")
		(net "PCIE_TX0_P")
	)
	(segment
		(start 129.8744 144.5216)
		(end 131.18221 143.21379)
		(width 0.127)
		(layer "In2.Cu")
		(net "PCIE_TX0_P")
	)
	(segment
		(start 136.0216 137.7162)
		(end 154.8695 137.7162)
		(width 0.127)
		(layer "In2.Cu")
		(net "PCIE_TX0_P")
	)
	(segment
		(start 161.6401 140.43756)
		(end 163.42145 140.43756)
		(width 0.127)
		(layer "In2.Cu")
		(net "PCIE_TX0_P")
	)
	(segment
		(start 159.80964 140.4364)
		(end 161.63893 140.4364)
		(width 0.127)
		(layer "In2.Cu")
		(net "PCIE_TX0_P")
	)
	(segment
		(start 129.8744 144.79101)
		(end 129.89971 144.81631)
		(width 0.127)
		(layer "In2.Cu")
		(net "PCIE_TX0_P")
	)
	(segment
		(start 163.61903 140.35573)
		(end 163.68318 140.29157)
		(width 0.127)
		(layer "In2.Cu")
		(net "PCIE_TX0_P")
	)
	(segment
		(start 164.17323 138.13767)
		(end 164.17323 138.13387)
		(width 0.127)
		(layer "In2.Cu")
		(net "PCIE_TX0_P")
	)
	(segment
		(start 129.32769 145.32193)
		(end 129.36089 145.35513)
		(width 0.127)
		(layer "In2.Cu")
		(net "PCIE_TX0_P")
	)
	(segment
		(start 129.05828 145.59134)
		(end 129.09148 145.62454)
		(width 0.127)
		(layer "In2.Cu")
		(net "PCIE_TX0_P")
	)
	(segment
		(start 128.52736 146.13805)
		(end 128.55267 146.16335)
		(width 0.127)
		(layer "In2.Cu")
		(net "PCIE_TX0_P")
	)
	(segment
		(start 126.56821 149.7074)
		(end 126.99988 150.13908)
		(width 0.127)
		(layer "In2.Cu")
		(net "PCIE_TX0_P")
	)
	(segment
		(start 134.46543 139.13776)
		(end 135.79182 137.81138)
		(width 0.127)
		(layer "In2.Cu")
		(net "PCIE_TX0_P")
	)
	(arc
		(start 128.257956 146.138046)
		(mid 128.39266 146.08225)
		(end 128.527364 146.138046)
		(width 0.127)
		(layer "In2.Cu")
		(net "PCIE_TX0_P")
	)
	(arc
		(start 127.600374 150.141704)
		(mid 127.464071 150.232779)
		(end 127.30329 150.26476)
		(width 0.127)
		(layer "In2.Cu")
		(net "PCIE_TX0_P")
	)
	(arc
		(start 126.609127 148.193678)
		(mid 126.860151 147.63903)
		(end 127.235949 147.160048)
		(width 0.127)
		(layer "In2.Cu")
		(net "PCIE_TX0_P")
	)
	(arc
		(start 129.360894 145.355126)
		(mid 129.41669 145.48983)
		(end 129.360894 145.624534)
		(width 0.127)
		(layer "In2.Cu")
		(net "PCIE_TX0_P")
	)
	(arc
		(start 128.822071 146.163356)
		(mid 128.687368 146.21915)
		(end 128.552666 146.163353)
		(width 0.127)
		(layer "In2.Cu")
		(net "PCIE_TX0_P")
	)
	(arc
		(start 129.327696 145.052526)
		(mid 129.4624 144.99673)
		(end 129.597104 145.052526)
		(width 0.127)
		(layer "In2.Cu")
		(net "PCIE_TX0_P")
	)
	(arc
		(start 127.30329 150.26476)
		(mid 127.139084 150.232097)
		(end 126.999878 150.139082)
		(width 0.127)
		(layer "In2.Cu")
		(net "PCIE_TX0_P")
	)
	(arc
		(start 159.80964 140.4364)
		(mid 158.730701 140.221785)
		(end 157.816021 139.610615)
		(width 0.127)
		(layer "In2.Cu")
		(net "PCIE_TX0_P")
	)
	(arc
		(start 163.96293 139.6162)
		(mid 163.890226 139.981709)
		(end 163.683182 140.291572)
		(width 0.127)
		(layer "In2.Cu")
		(net "PCIE_TX0_P")
	)
	(arc
		(start 129.899704 144.816316)
		(mid 129.9555 144.95102)
		(end 129.899704 145.085724)
		(width 0.127)
		(layer "In2.Cu")
		(net "PCIE_TX0_P")
	)
	(arc
		(start 154.8695 137.7162)
		(mid 155.841516 137.909546)
		(end 156.665551 138.460149)
		(width 0.127)
		(layer "In2.Cu")
		(net "PCIE_TX0_P")
	)
	(arc
		(start 128.788876 145.591336)
		(mid 128.92358 145.53554)
		(end 129.058284 145.591336)
		(width 0.127)
		(layer "In2.Cu")
		(net "PCIE_TX0_P")
	)
	(arc
		(start 135.792012 137.811171)
		(mid 135.89737 137.740873)
		(end 136.0216 137.71619)
		(width 0.127)
		(layer "In2.Cu")
		(net "PCIE_TX0_P")
	)
	(arc
		(start 128.822074 145.893946)
		(mid 128.87787 146.02865)
		(end 128.822074 146.163354)
		(width 0.127)
		(layer "In2.Cu")
		(net "PCIE_TX0_P")
	)
	(arc
		(start 163.96293 138.64538)
		(mid 164.017585 138.370609)
		(end 164.17323 138.13767)
		(width 0.127)
		(layer "In2.Cu")
		(net "PCIE_TX0_P")
	)
	(arc
		(start 128.788876 145.860744)
		(mid 128.73308 145.726041)
		(end 128.788874 145.591338)
		(width 0.127)
		(layer "In2.Cu")
		(net "PCIE_TX0_P")
	)
	(arc
		(start 163.619023 140.355733)
		(mid 163.528376 140.416302)
		(end 163.42145 140.43757)
		(width 0.127)
		(layer "In2.Cu")
		(net "PCIE_TX0_P")
	)
	(arc
		(start 134.46543 139.13776)
		(mid 134.319735 139.87022)
		(end 133.904829 140.491169)
		(width 0.127)
		(layer "In2.Cu")
		(net "PCIE_TX0_P")
	)
	(arc
		(start 129.327696 145.321934)
		(mid 129.2719 145.187231)
		(end 129.327694 145.052528)
		(width 0.127)
		(layer "In2.Cu")
		(net "PCIE_TX0_P")
	)
	(arc
		(start 129.360891 145.624536)
		(mid 129.226188 145.68033)
		(end 129.091486 145.624533)
		(width 0.127)
		(layer "In2.Cu")
		(net "PCIE_TX0_P")
	)
	(arc
		(start 126.568212 149.707398)
		(mid 126.511814 149.622993)
		(end 126.49201 149.52343)
		(width 0.127)
		(layer "In2.Cu")
		(net "PCIE_TX0_P")
	)
	(arc
		(start 126.492 148.9561)
		(mid 126.521453 148.570417)
		(end 126.609127 148.193678)
		(width 0.127)
		(layer "In2.Cu")
		(net "PCIE_TX0_P")
	)
	(arc
		(start 129.874396 144.791004)
		(mid 129.8186 144.6563)
		(end 129.874396 144.521596)
		(width 0.127)
		(layer "In2.Cu")
		(net "PCIE_TX0_P")
	)
	(arc
		(start 129.899701 145.085726)
		(mid 129.764998 145.14152)
		(end 129.630296 145.085723)
		(width 0.127)
		(layer "In2.Cu")
		(net "PCIE_TX0_P")
	)
	(segment
		(start 162.55641 141.44769)
		(end 162.55641 140.9135)
		(width 0.127)
		(layer "F.Cu")
		(net "PCIE_CLK_P")
	)
	(segment
		(start 162.04668 143.03687)
		(end 162.04668 142.6783)
		(width 0.127)
		(layer "F.Cu")
		(net "PCIE_CLK_P")
	)
	(via
		(at 162.04668 143.03687)
		(size 0.4064)
		(drill 0.2032)
		(layers "F.Cu" "B.Cu")
		(tenting
			(front yes)
			(back yes)
		)
		(net "PCIE_CLK_P")
	)
	(via
		(at 124.5716 150.2786)
		(size 0.4064)
		(drill 0.2032)
		(layers "F.Cu" "B.Cu")
		(tenting
			(front yes)
			(back yes)
		)
		(net "PCIE_CLK_P")
	)
	(arc
		(start 162.04668 142.6783)
		(mid 162.072669 142.547644)
		(end 162.14668 142.43688)
		(width 0.127)
		(layer "F.Cu")
		(net "PCIE_CLK_P")
	)
	(arc
		(start 162.55641 141.44769)
		(mid 162.449924 141.983034)
		(end 162.146676 142.436876)
		(width 0.127)
		(layer "F.Cu")
		(net "PCIE_CLK_P")
	)
	(segment
		(start 124.5716 151.3248)
		(end 124.5716 150.2786)
		(width 0.127)
		(layer "B.Cu")
		(net "PCIE_CLK_P")
	)
	(arc
		(start 124.5716 151.3248)
		(mid 124.567961 151.343092)
		(end 124.5576 151.3586)
		(width 0.127)
		(layer "B.Cu")
		(net "PCIE_CLK_P")
	)
	(segment
		(start 135.14586 142.6162)
		(end 138.48903 142.6162)
		(width 0.127)
		(layer "In2.Cu")
		(net "PCIE_CLK_P")
	)
	(segment
		(start 125.01001 150.66891)
		(end 125.5683 151.2272)
		(width 0.127)
		(layer "In2.Cu")
		(net "PCIE_CLK_P")
	)
	(segment
		(start 139.93755 142.0162)
		(end 156.1216 142.0162)
		(width 0.127)
		(layer "In2.Cu")
		(net "PCIE_CLK_P")
	)
	(segment
		(start 129.4683 151.77703)
		(end 130.5365 150.70883)
		(width 0.127)
		(layer "In2.Cu")
		(net "PCIE_CLK_P")
	)
	(segment
		(start 161.94153 143.14582)
		(end 162.04668 143.04067)
		(width 0.127)
		(layer "In2.Cu")
		(net "PCIE_CLK_P")
	)
	(segment
		(start 132.01045 145.32734)
		(end 132.8202 144.5176)
		(width 0.127)
		(layer "In2.Cu")
		(net "PCIE_CLK_P")
	)
	(segment
		(start 162.04668 143.04067)
		(end 162.04668 143.03687)
		(width 0.127)
		(layer "In2.Cu")
		(net "PCIE_CLK_P")
	)
	(segment
		(start 156.29231 142.08691)
		(end 158.08039 143.87499)
		(width 0.127)
		(layer "In2.Cu")
		(net "PCIE_CLK_P")
	)
	(segment
		(start 127.09117 151.858)
		(end 129.27282 151.858)
		(width 0.127)
		(layer "In2.Cu")
		(net "PCIE_CLK_P")
	)
	(segment
		(start 159.62842 144.5162)
		(end 160.01697 144.5162)
		(width 0.127)
		(layer "In2.Cu")
		(net "PCIE_CLK_P")
	)
	(segment
		(start 161.83638 143.45573)
		(end 161.83638 143.39968)
		(width 0.127)
		(layer "In2.Cu")
		(net "PCIE_CLK_P")
	)
	(segment
		(start 132.8202 144.5176)
		(end 134.4216 142.9162)
		(width 0.127)
		(layer "In2.Cu")
		(net "PCIE_CLK_P")
	)
	(segment
		(start 124.9319 150.48033)
		(end 124.9319 150.42247)
		(width 0.127)
		(layer "In2.Cu")
		(net "PCIE_CLK_P")
	)
	(segment
		(start 161.6621 143.83477)
		(end 161.69162 143.80524)
		(width 0.127)
		(layer "In2.Cu")
		(net "PCIE_CLK_P")
	)
	(segment
		(start 124.61232 150.29547)
		(end 124.8049 150.29547)
		(width 0.127)
		(layer "In2.Cu")
		(net "PCIE_CLK_P")
	)
	(segment
		(start 131.3613 148.71758)
		(end 131.3613 146.89453)
		(width 0.127)
		(layer "In2.Cu")
		(net "PCIE_CLK_P")
	)
	(arc
		(start 139.219165 142.313765)
		(mid 139.548763 142.093535)
		(end 139.93755 142.0162)
		(width 0.127)
		(layer "In2.Cu")
		(net "PCIE_CLK_P")
	)
	(arc
		(start 124.61232 150.29547)
		(mid 124.590281 150.291086)
		(end 124.571598 150.278602)
		(width 0.127)
		(layer "In2.Cu")
		(net "PCIE_CLK_P")
	)
	(arc
		(start 135.136688 142.616241)
		(mid 135.141274 142.61621)
		(end 135.14586 142.6162)
		(width 0.127)
		(layer "In2.Cu")
		(net "PCIE_CLK_P")
	)
	(arc
		(start 159.62842 144.5162)
		(mid 159.498172 144.512322)
		(end 159.368385 144.500702)
		(width 0.127)
		(layer "In2.Cu")
		(net "PCIE_CLK_P")
	)
	(arc
		(start 139.219167 142.313767)
		(mid 138.884177 142.5376)
		(end 138.48903 142.6162)
		(width 0.127)
		(layer "In2.Cu")
		(net "PCIE_CLK_P")
	)
	(arc
		(start 156.1216 142.0162)
		(mid 156.213984 142.034576)
		(end 156.292303 142.086907)
		(width 0.127)
		(layer "In2.Cu")
		(net "PCIE_CLK_P")
	)
	(arc
		(start 127.09117 151.858)
		(mid 126.266996 151.694062)
		(end 125.568295 151.227205)
		(width 0.127)
		(layer "In2.Cu")
		(net "PCIE_CLK_P")
	)
	(arc
		(start 131.36131 148.71758)
		(mid 131.14695 149.79524)
		(end 130.536505 150.708835)
		(width 0.127)
		(layer "In2.Cu")
		(net "PCIE_CLK_P")
	)
	(arc
		(start 161.662096 143.834766)
		(mid 160.908894 144.338442)
		(end 160.020408 144.516197)
		(width 0.127)
		(layer "In2.Cu")
		(net "PCIE_CLK_P")
	)
	(arc
		(start 159.368385 144.500702)
		(mid 158.672696 144.296571)
		(end 158.081826 143.876422)
		(width 0.127)
		(layer "In2.Cu")
		(net "PCIE_CLK_P")
	)
	(arc
		(start 124.894703 150.332667)
		(mid 124.922233 150.373869)
		(end 124.931901 150.42247)
		(width 0.127)
		(layer "In2.Cu")
		(net "PCIE_CLK_P")
	)
	(arc
		(start 124.8049 150.29547)
		(mid 124.853501 150.305137)
		(end 124.894703 150.332667)
		(width 0.127)
		(layer "In2.Cu")
		(net "PCIE_CLK_P")
	)
	(arc
		(start 161.83638 143.45573)
		(mid 161.798759 143.644884)
		(end 161.691622 143.805246)
		(width 0.127)
		(layer "In2.Cu")
		(net "PCIE_CLK_P")
	)
	(arc
		(start 161.83637 143.39968)
		(mid 161.863698 143.262293)
		(end 161.941522 143.145822)
		(width 0.127)
		(layer "In2.Cu")
		(net "PCIE_CLK_P")
	)
	(arc
		(start 125.010012 150.668908)
		(mid 124.952201 150.582388)
		(end 124.9319 150.48033)
		(width 0.127)
		(layer "In2.Cu")
		(net "PCIE_CLK_P")
	)
	(arc
		(start 134.421599 142.916199)
		(mid 134.42475 142.913062)
		(end 134.427914 142.909939)
		(width 0.127)
		(layer "In2.Cu")
		(net "PCIE_CLK_P")
	)
	(arc
		(start 134.427913 142.909936)
		(mid 134.435566 142.903051)
		(end 134.443751 142.896808)
		(width 0.127)
		(layer "In2.Cu")
		(net "PCIE_CLK_P")
	)
	(arc
		(start 131.3613 146.894524)
		(mid 131.530011 146.046367)
		(end 132.010454 145.327334)
		(width 0.127)
		(layer "In2.Cu")
		(net "PCIE_CLK_P")
	)
	(arc
		(start 129.4683 151.77703)
		(mid 129.378613 151.836957)
		(end 129.27282 151.858)
		(width 0.127)
		(layer "In2.Cu")
		(net "PCIE_CLK_P")
	)
	(arc
		(start 135.117149 142.618039)
		(mid 135.126882 142.616763)
		(end 135.136684 142.616243)
		(width 0.127)
		(layer "In2.Cu")
		(net "PCIE_CLK_P")
	)
	(arc
		(start 134.443748 142.896811)
		(mid 134.765472 142.721245)
		(end 135.11715 142.618034)
		(width 0.127)
		(layer "In2.Cu")
		(net "PCIE_CLK_P")
	)
	(segment
		(start 162.05654 141.73022)
		(end 162.05654 140.9135)
		(width 0.127)
		(layer "F.Cu")
		(net "PCIE_CLK_N")
	)
	(segment
		(start 161.55881 142.52474)
		(end 161.84668 142.23687)
		(width 0.127)
		(layer "F.Cu")
		(net "PCIE_CLK_N")
	)
	(via
		(at 125.5716 150.2786)
		(size 0.4064)
		(drill 0.2032)
		(layers "F.Cu" "B.Cu")
		(tenting
			(front yes)
			(back yes)
		)
		(net "PCIE_CLK_N")
	)
	(via
		(at 161.34668 143.03687)
		(size 0.4064)
		(drill 0.2032)
		(layers "F.Cu" "B.Cu")
		(tenting
			(front yes)
			(back yes)
		)
		(net "PCIE_CLK_N")
	)
	(arc
		(start 161.34667 143.03687)
		(mid 161.401802 142.759704)
		(end 161.558804 142.524734)
		(width 0.127)
		(layer "F.Cu")
		(net "PCIE_CLK_N")
	)
	(arc
		(start 162.05654 141.73022)
		(mid 162.001998 142.00442)
		(end 161.846676 142.236876)
		(width 0.127)
		(layer "F.Cu")
		(net "PCIE_CLK_N")
	)
	(segment
		(start 125.5716 151.3566)
		(end 125.5716 150.2786)
		(width 0.127)
		(layer "B.Cu")
		(net "PCIE_CLK_N")
	)
	(segment
		(start 125.5716 151.3566)
		(end 125.5736 151.3586)
		(width 0.127)
		(layer "B.Cu")
		(net "PCIE_CLK_N")
	)
	(segment
		(start 161.55698 143.41402)
		(end 161.55698 143.39967)
		(width 0.127)
		(layer "In2.Cu")
		(net "PCIE_CLK_N")
	)
	(segment
		(start 127.16503 151.3881)
		(end 127.16503 151.12243)
		(width 0.127)
		(layer "In2.Cu")
		(net "PCIE_CLK_N")
	)
	(segment
		(start 126.5432 151.42741)
		(end 126.5432 151.42741)
		(width 0.127)
		(layer "In2.Cu")
		(net "PCIE_CLK_N")
	)
	(segment
		(start 127.80004 151.5786)
		(end 129.2716 151.5786)
		(width 0.127)
		(layer "In2.Cu")
		(net "PCIE_CLK_N")
	)
	(segment
		(start 126.78403 151.24368)
		(end 126.78403 151.12243)
		(width 0.127)
		(layer "In2.Cu")
		(net "PCIE_CLK_N")
	)
	(segment
		(start 126.0716 151.27629)
		(end 126.07161 151.27629)
		(width 0.127)
		(layer "In2.Cu")
		(net "PCIE_CLK_N")
	)
	(segment
		(start 125.33831 150.29547)
		(end 125.53088 150.29547)
		(width 0.127)
		(layer "In2.Cu")
		(net "PCIE_CLK_N")
	)
	(segment
		(start 131.81289 145.12978)
		(end 132.69384 144.24883)
		(width 0.127)
		(layer "In2.Cu")
		(net "PCIE_CLK_N")
	)
	(segment
		(start 127.35553 151.5786)
		(end 127.80004 151.5786)
		(width 0.127)
		(layer "In2.Cu")
		(net "PCIE_CLK_N")
	)
	(segment
		(start 161.34668 143.04067)
		(end 161.45183 143.14582)
		(width 0.127)
		(layer "In2.Cu")
		(net "PCIE_CLK_N")
	)
	(segment
		(start 161.34668 143.04067)
		(end 161.34668 143.03687)
		(width 0.127)
		(layer "In2.Cu")
		(net "PCIE_CLK_N")
	)
	(segment
		(start 135.4216 142.3368)
		(end 138.48903 142.3368)
		(width 0.127)
		(layer "In2.Cu")
		(net "PCIE_CLK_N")
	)
	(segment
		(start 127.80004 151.5786)
		(end 127.80005 151.5786)
		(width 0.127)
		(layer "In2.Cu")
		(net "PCIE_CLK_N")
	)
	(segment
		(start 156.4898 141.88927)
		(end 156.48987 141.88934)
		(width 0.127)
		(layer "In2.Cu")
		(net "PCIE_CLK_N")
	)
	(segment
		(start 131.0819 148.71619)
		(end 131.0819 146.89453)
		(width 0.127)
		(layer "In2.Cu")
		(net "PCIE_CLK_N")
	)
	(segment
		(start 157.84386 143.24332)
		(end 158.19612 143.59558)
		(width 0.127)
		(layer "In2.Cu")
		(net "PCIE_CLK_N")
	)
	(segment
		(start 126.1351 151.31562)
		(end 126.5432 151.42741)
		(width 0.127)
		(layer "In2.Cu")
		(net "PCIE_CLK_N")
	)
	(segment
		(start 156.48987 141.88934)
		(end 157.84386 143.24332)
		(width 0.127)
		(layer "In2.Cu")
		(net "PCIE_CLK_N")
	)
	(segment
		(start 159.74415 144.2368)
		(end 160.01697 144.2368)
		(width 0.127)
		(layer "In2.Cu")
		(net "PCIE_CLK_N")
	)
	(segment
		(start 125.2113 150.42247)
		(end 125.2113 150.42247)
		(width 0.127)
		(layer "In2.Cu")
		(net "PCIE_CLK_N")
	)
	(segment
		(start 139.93755 141.7368)
		(end 156.1216 141.7368)
		(width 0.127)
		(layer "In2.Cu")
		(net "PCIE_CLK_N")
	)
	(segment
		(start 129.2716 151.5786)
		(end 130.33795 150.51224)
		(width 0.127)
		(layer "In2.Cu")
		(net "PCIE_CLK_N")
	)
	(segment
		(start 132.69384 144.24883)
		(end 134.02905 142.91361)
		(width 0.127)
		(layer "In2.Cu")
		(net "PCIE_CLK_N")
	)
	(segment
		(start 125.2485 150.51227)
		(end 125.76306 151.02684)
		(width 0.127)
		(layer "In2.Cu")
		(net "PCIE_CLK_N")
	)
	(arc
		(start 125.2113 150.42247)
		(mid 125.220967 150.373873)
		(end 125.248495 150.332675)
		(width 0.127)
		(layer "In2.Cu")
		(net "PCIE_CLK_N")
	)
	(arc
		(start 156.1216 141.7368)
		(mid 156.320857 141.776424)
		(end 156.489795 141.889268)
		(width 0.127)
		(layer "In2.Cu")
		(net "PCIE_CLK_N")
	)
	(arc
		(start 131.0819 148.71619)
		(mid 130.888554 149.688206)
		(end 130.337951 150.512241)
		(width 0.127)
		(layer "In2.Cu")
		(net "PCIE_CLK_N")
	)
	(arc
		(start 126.135107 151.315625)
		(mid 126.103161 151.296273)
		(end 126.071605 151.276292)
		(width 0.127)
		(layer "In2.Cu")
		(net "PCIE_CLK_N")
	)
	(arc
		(start 139.021602 142.116202)
		(mid 138.777256 142.279469)
		(end 138.48903 142.336801)
		(width 0.127)
		(layer "In2.Cu")
		(net "PCIE_CLK_N")
	)
	(arc
		(start 125.248487 150.512273)
		(mid 125.220957 150.471071)
		(end 125.211289 150.42247)
		(width 0.127)
		(layer "In2.Cu")
		(net "PCIE_CLK_N")
	)
	(arc
		(start 126.071598 151.276288)
		(mid 125.910744 151.159709)
		(end 125.763061 151.026839)
		(width 0.127)
		(layer "In2.Cu")
		(net "PCIE_CLK_N")
	)
	(arc
		(start 126.78403 151.24368)
		(mid 126.709077 151.395137)
		(end 126.543198 151.427411)
		(width 0.127)
		(layer "In2.Cu")
		(net "PCIE_CLK_N")
	)
	(arc
		(start 161.464531 143.637201)
		(mid 160.800384 144.08097)
		(end 160.01697 144.2368)
		(width 0.127)
		(layer "In2.Cu")
		(net "PCIE_CLK_N")
	)
	(arc
		(start 161.451831 143.145819)
		(mid 161.529652 143.262287)
		(end 161.55698 143.39967)
		(width 0.127)
		(layer "In2.Cu")
		(net "PCIE_CLK_N")
	)
	(arc
		(start 126.78403 151.12243)
		(mid 126.97453 150.93193)
		(end 127.16503 151.12243)
		(width 0.127)
		(layer "In2.Cu")
		(net "PCIE_CLK_N")
	)
	(arc
		(start 159.74415 144.2368)
		(mid 158.90636 144.070153)
		(end 158.196116 143.595584)
		(width 0.127)
		(layer "In2.Cu")
		(net "PCIE_CLK_N")
	)
	(arc
		(start 139.021599 142.116199)
		(mid 139.441841 141.835402)
		(end 139.93755 141.7368)
		(width 0.127)
		(layer "In2.Cu")
		(net "PCIE_CLK_N")
	)
	(arc
		(start 134.029052 142.913612)
		(mid 134.667958 142.486708)
		(end 135.4216 142.3368)
		(width 0.127)
		(layer "In2.Cu")
		(net "PCIE_CLK_N")
	)
	(arc
		(start 125.571602 150.278602)
		(mid 125.552919 150.291086)
		(end 125.53088 150.29547)
		(width 0.127)
		(layer "In2.Cu")
		(net "PCIE_CLK_N")
	)
	(arc
		(start 127.35553 151.5786)
		(mid 127.220826 151.522804)
		(end 127.16503 151.3881)
		(width 0.127)
		(layer "In2.Cu")
		(net "PCIE_CLK_N")
	)
	(arc
		(start 161.55697 143.41402)
		(mid 161.532945 143.534803)
		(end 161.464527 143.637197)
		(width 0.127)
		(layer "In2.Cu")
		(net "PCIE_CLK_N")
	)
	(arc
		(start 131.0819 146.89453)
		(mid 131.271877 145.939452)
		(end 131.812885 145.129775)
		(width 0.127)
		(layer "In2.Cu")
		(net "PCIE_CLK_N")
	)
	(arc
		(start 125.2485 150.33267)
		(mid 125.289705 150.305138)
		(end 125.33831 150.295469)
		(width 0.127)
		(layer "In2.Cu")
		(net "PCIE_CLK_N")
	)
	(segment
		(start 168.3716 118.5662)
		(end 169.3216 118.5662)
		(width 0.2032)
		(layer "F.Cu")
		(net "PCIE_PERST")
	)
	(segment
		(start 174.9216 125.7162)
		(end 175.2216 126.0162)
		(width 0.2032)
		(layer "F.Cu")
		(net "PCIE_PERST")
	)
	(segment
		(start 145.4216 133.9162)
		(end 169.6216 133.9162)
		(width 0.2032)
		(layer "F.Cu")
		(net "PCIE_PERST")
	)
	(segment
		(start 140.46126 124.72069)
		(end 143.33858 124.72069)
		(width 0.2032)
		(layer "F.Cu")
		(net "PCIE_PERST")
	)
	(segment
		(start 169.6216 133.9162)
		(end 175.2216 128.3162)
		(width 0.2032)
		(layer "F.Cu")
		(net "PCIE_PERST")
	)
	(segment
		(start 120.4716 148.5662)
		(end 123.90975 145.12804)
		(width 0.2032)
		(layer "F.Cu")
		(net "PCIE_PERST")
	)
	(segment
		(start 140.65809 143.3797)
		(end 145.4216 138.6162)
		(width 0.2032)
		(layer "F.Cu")
		(net "PCIE_PERST")
	)
	(segment
		(start 130.35589 145.12804)
		(end 132.10423 143.3797)
		(width 0.2032)
		(layer "F.Cu")
		(net "PCIE_PERST")
	)
	(segment
		(start 175.2216 128.3162)
		(end 175.2216 126.0162)
		(width 0.2032)
		(layer "F.Cu")
		(net "PCIE_PERST")
	)
	(segment
		(start 145.4216 133.9162)
		(end 145.4216 126.86549)
		(width 0.2032)
		(layer "F.Cu")
		(net "PCIE_PERST")
	)
	(segment
		(start 132.10423 143.3797)
		(end 140.65809 143.3797)
		(width 0.2032)
		(layer "F.Cu")
		(net "PCIE_PERST")
	)
	(segment
		(start 143.33858 124.78247)
		(end 143.33858 124.72069)
		(width 0.2032)
		(layer "F.Cu")
		(net "PCIE_PERST")
	)
	(segment
		(start 145.4216 138.6162)
		(end 145.4216 133.9162)
		(width 0.2032)
		(layer "F.Cu")
		(net "PCIE_PERST")
	)
	(segment
		(start 123.90975 145.12804)
		(end 130.35589 145.12804)
		(width 0.2032)
		(layer "F.Cu")
		(net "PCIE_PERST")
	)
	(segment
		(start 171.5216 125.7162)
		(end 174.9216 125.7162)
		(width 0.2032)
		(layer "F.Cu")
		(net "PCIE_PERST")
	)
	(segment
		(start 143.33858 124.78247)
		(end 145.4216 126.86549)
		(width 0.2032)
		(layer "F.Cu")
		(net "PCIE_PERST")
	)
	(segment
		(start 120.4716 150.9786)
		(end 120.4716 148.5662)
		(width 0.2032)
		(layer "F.Cu")
		(net "PCIE_PERST")
	)
	(via
		(at 171.5216 125.7162)
		(size 0.4064)
		(drill 0.2032)
		(layers "F.Cu" "B.Cu")
		(net "PCIE_PERST")
	)
	(via
		(at 133.1216 125.9162)
		(size 0.4064)
		(drill 0.2032)
		(layers "F.Cu" "B.Cu")
		(net "PCIE_PERST")
	)
	(via
		(at 168.3716 118.5662)
		(size 0.4064)
		(drill 0.2032)
		(layers "F.Cu" "B.Cu")
		(net "PCIE_PERST")
	)
	(via
		(at 120.4716 150.9786)
		(size 0.4064)
		(drill 0.2032)
		(layers "F.Cu" "B.Cu")
		(tenting
			(front yes)
			(back yes)
		)
		(net "PCIE_PERST")
	)
	(via
		(at 143.33858 124.78247)
		(size 0.4064)
		(drill 0.2032)
		(layers "F.Cu" "B.Cu")
		(tenting
			(front yes)
			(back yes)
		)
		(net "PCIE_PERST")
	)
	(via
		(at 117.38072 89.0662)
		(size 0.4064)
		(drill 0.2032)
		(layers "F.Cu" "B.Cu")
		(net "PCIE_PERST")
	)
	(via
		(at 85.14851 87.34311)
		(size 0.4064)
		(drill 0.2032)
		(layers "F.Cu" "B.Cu")
		(net "PCIE_PERST")
	)
	(via
		(at 75.5216 87.34311)
		(size 0.4064)
		(drill 0.2032)
		(layers "F.Cu" "B.Cu")
		(net "PCIE_PERST")
	)
	(segment
		(start 145.06532 124.78247)
		(end 145.2316 124.6162)
		(width 0.2032)
		(layer "B.Cu")
		(net "PCIE_PERST")
	)
	(segment
		(start 133.25939 126.14674)
		(end 133.37842 126.26578)
		(width 0.2032)
		(layer "B.Cu")
		(net "PCIE_PERST")
	)
	(segment
		(start 116.14477 88.8662)
		(end 117.18072 88.8662)
		(width 0.2032)
		(layer "B.Cu")
		(net "PCIE_PERST")
	)
	(segment
		(start 117.18072 88.8662)
		(end 117.38072 89.0662)
		(width 0.2032)
		(layer "B.Cu")
		(net "PCIE_PERST")
	)
	(segment
		(start 133.25939 126.14674)
		(end 133.25939 126.03523)
		(width 0.2032)
		(layer "B.Cu")
		(net "PCIE_PERST")
	)
	(segment
		(start 113.29149 87.45543)
		(end 113.29149 87.38214)
		(width 0.2032)
		(layer "B.Cu")
		(net "PCIE_PERST")
	)
	(segment
		(start 112.88072 87.8662)
		(end 113.29149 87.45543)
		(width 0.2032)
		(layer "B.Cu")
		(net "PCIE_PERST")
	)
	(segment
		(start 143.33858 124.78247)
		(end 145.06532 124.78247)
		(width 0.2032)
		(layer "B.Cu")
		(net "PCIE_PERST")
	)
	(segment
		(start 113.29149 87.38214)
		(end 113.70743 86.9662)
		(width 0.2032)
		(layer "B.Cu")
		(net "PCIE_PERST")
	)
	(segment
		(start 168.3716 122.5662)
		(end 168.3716 118.5662)
		(width 0.2032)
		(layer "B.Cu")
		(net "PCIE_PERST")
	)
	(segment
		(start 141.85528 126.26578)
		(end 143.33858 124.78247)
		(width 0.2032)
		(layer "B.Cu")
		(net "PCIE_PERST")
	)
	(segment
		(start 133.1216 125.9162)
		(end 133.14036 125.9162)
		(width 0.2032)
		(layer "B.Cu")
		(net "PCIE_PERST")
	)
	(segment
		(start 133.14036 125.9162)
		(end 133.25939 126.03523)
		(width 0.2032)
		(layer "B.Cu")
		(net "PCIE_PERST")
	)
	(segment
		(start 120.4716 157.02859)
		(end 120.4716 150.9786)
		(width 0.2032)
		(layer "B.Cu")
		(net "PCIE_PERST")
	)
	(segment
		(start 114.24477 86.9662)
		(end 116.14477 88.8662)
		(width 0.2032)
		(layer "B.Cu")
		(net "PCIE_PERST")
	)
	(segment
		(start 113.70743 86.9662)
		(end 114.24477 86.9662)
		(width 0.2032)
		(layer "B.Cu")
		(net "PCIE_PERST")
	)
	(segment
		(start 120.4716 157.02859)
		(end 120.52161 157.0786)
		(width 0.2032)
		(layer "B.Cu")
		(net "PCIE_PERST")
	)
	(segment
		(start 168.3716 122.5662)
		(end 171.5216 125.7162)
		(width 0.2032)
		(layer "B.Cu")
		(net "PCIE_PERST")
	)
	(segment
		(start 133.37842 126.26578)
		(end 141.85528 126.26578)
		(width 0.2032)
		(layer "B.Cu")
		(net "PCIE_PERST")
	)
	(segment
		(start 81.9216 85.8162)
		(end 83.44851 87.34311)
		(width 0.2032)
		(layer "In2.Cu")
		(net "PCIE_PERST")
	)
	(segment
		(start 75.9216 85.8162)
		(end 81.9216 85.8162)
		(width 0.2032)
		(layer "In2.Cu")
		(net "PCIE_PERST")
	)
	(segment
		(start 75.5216 86.2162)
		(end 75.9216 85.8162)
		(width 0.2032)
		(layer "In2.Cu")
		(net "PCIE_PERST")
	)
	(segment
		(start 75.5216 87.34311)
		(end 75.5216 86.2162)
		(width 0.2032)
		(layer "In2.Cu")
		(net "PCIE_PERST")
	)
	(segment
		(start 83.44851 87.34311)
		(end 85.14851 87.34311)
		(width 0.2032)
		(layer "In2.Cu")
		(net "PCIE_PERST")
	)
	(segment
		(start 74.04736 116.9162)
		(end 76.8216 116.9162)
		(width 0.2032)
		(layer "In3.Cu")
		(net "PCIE_PERST")
	)
	(segment
		(start 116.76571 90.78938)
		(end 116.76571 89.68121)
		(width 0.2032)
		(layer "In3.Cu")
		(net "PCIE_PERST")
	)
	(segment
		(start 75.5216 94.0243)
		(end 75.5216 87.34311)
		(width 0.2032)
		(layer "In3.Cu")
		(net "PCIE_PERST")
	)
	(segment
		(start 75.5216 94.0243)
		(end 75.9216 94.4243)
		(width 0.2032)
		(layer "In3.Cu")
		(net "PCIE_PERST")
	)
	(segment
		(start 74.0216 130.07343)
		(end 76.6216 132.67344)
		(width 0.2032)
		(layer "In3.Cu")
		(net "PCIE_PERST")
	)
	(segment
		(start 74.0216 130.07343)
		(end 74.0216 129.09864)
		(width 0.2032)
		(layer "In3.Cu")
		(net "PCIE_PERST")
	)
	(segment
		(start 75.9216 97.3162)
		(end 75.9216 94.4243)
		(width 0.2032)
		(layer "In3.Cu")
		(net "PCIE_PERST")
	)
	(segment
		(start 115.0088 92.54629)
		(end 116.76571 90.78938)
		(width 0.2032)
		(layer "In3.Cu")
		(net "PCIE_PERST")
	)
	(segment
		(start 72.80673 103.60444)
		(end 74.01922 104.81693)
		(width 0.2032)
		(layer "In3.Cu")
		(net "PCIE_PERST")
	)
	(segment
		(start 80.3216 128.2162)
		(end 81.74935 128.2162)
		(width 0.2032)
		(layer "In3.Cu")
		(net "PCIE_PERST")
	)
	(segment
		(start 74.38928 128.73096)
		(end 78.94181 128.73096)
		(width 0.2032)
		(layer "In3.Cu")
		(net "PCIE_PERST")
	)
	(segment
		(start 76.6216 141.3162)
		(end 76.6216 132.67344)
		(width 0.2032)
		(layer "In3.Cu")
		(net "PCIE_PERST")
	)
	(segment
		(start 72.80673 103.60444)
		(end 72.80673 100.43107)
		(width 0.2032)
		(layer "In3.Cu")
		(net "PCIE_PERST")
	)
	(segment
		(start 85.14851 90.65881)
		(end 87.03599 92.54629)
		(width 0.2032)
		(layer "In3.Cu")
		(net "PCIE_PERST")
	)
	(segment
		(start 81.74935 129.07469)
		(end 81.74935 128.2162)
		(width 0.2032)
		(layer "In3.Cu")
		(net "PCIE_PERST")
	)
	(segment
		(start 87.03599 92.54629)
		(end 115.0088 92.54629)
		(width 0.2032)
		(layer "In3.Cu")
		(net "PCIE_PERST")
	)
	(segment
		(start 74.0216 129.09864)
		(end 74.38928 128.73096)
		(width 0.2032)
		(layer "In3.Cu")
		(net "PCIE_PERST")
	)
	(segment
		(start 81.37345 129.4506)
		(end 81.74935 129.07469)
		(width 0.2032)
		(layer "In3.Cu")
		(net "PCIE_PERST")
	)
	(segment
		(start 76.9232 141.6178)
		(end 79.22 141.6178)
		(width 0.2032)
		(layer "In3.Cu")
		(net "PCIE_PERST")
	)
	(segment
		(start 76.6216 141.3162)
		(end 76.9232 141.6178)
		(width 0.2032)
		(layer "In3.Cu")
		(net "PCIE_PERST")
	)
	(segment
		(start 112.6216 125.9162)
		(end 133.1216 125.9162)
		(width 0.2032)
		(layer "In3.Cu")
		(net "PCIE_PERST")
	)
	(segment
		(start 74.01922 105.61264)
		(end 74.43349 106.02692)
		(width 0.2032)
		(layer "In3.Cu")
		(net "PCIE_PERST")
	)
	(segment
		(start 116.76571 89.68121)
		(end 117.38072 89.0662)
		(width 0.2032)
		(layer "In3.Cu")
		(net "PCIE_PERST")
	)
	(segment
		(start 72.8216 115.69044)
		(end 72.8216 114.83242)
		(width 0.2032)
		(layer "In3.Cu")
		(net "PCIE_PERST")
	)
	(segment
		(start 72.8216 115.69044)
		(end 74.04736 116.9162)
		(width 0.2032)
		(layer "In3.Cu")
		(net "PCIE_PERST")
	)
	(segment
		(start 76.8216 116.9162)
		(end 79.83186 119.92646)
		(width 0.2032)
		(layer "In3.Cu")
		(net "PCIE_PERST")
	)
	(segment
		(start 98.5216 140.0162)
		(end 112.6216 125.9162)
		(width 0.2032)
		(layer "In3.Cu")
		(net "PCIE_PERST")
	)
	(segment
		(start 85.14851 90.65881)
		(end 85.14851 87.34311)
		(width 0.2032)
		(layer "In3.Cu")
		(net "PCIE_PERST")
	)
	(segment
		(start 78.94181 128.73096)
		(end 79.66146 129.4506)
		(width 0.2032)
		(layer "In3.Cu")
		(net "PCIE_PERST")
	)
	(segment
		(start 79.83186 127.72646)
		(end 80.3216 128.2162)
		(width 0.2032)
		(layer "In3.Cu")
		(net "PCIE_PERST")
	)
	(segment
		(start 79.22 141.6178)
		(end 80.8216 140.0162)
		(width 0.2032)
		(layer "In3.Cu")
		(net "PCIE_PERST")
	)
	(segment
		(start 72.80673 100.43107)
		(end 75.9216 97.3162)
		(width 0.2032)
		(layer "In3.Cu")
		(net "PCIE_PERST")
	)
	(segment
		(start 79.83186 127.72646)
		(end 79.83186 119.92646)
		(width 0.2032)
		(layer "In3.Cu")
		(net "PCIE_PERST")
	)
	(segment
		(start 74.01922 105.61264)
		(end 74.01922 104.81693)
		(width 0.2032)
		(layer "In3.Cu")
		(net "PCIE_PERST")
	)
	(segment
		(start 74.43349 113.22053)
		(end 74.43349 106.02692)
		(width 0.2032)
		(layer "In3.Cu")
		(net "PCIE_PERST")
	)
	(segment
		(start 79.66146 129.4506)
		(end 81.37345 129.4506)
		(width 0.2032)
		(layer "In3.Cu")
		(net "PCIE_PERST")
	)
	(segment
		(start 80.8216 140.0162)
		(end 98.5216 140.0162)
		(width 0.2032)
		(layer "In3.Cu")
		(net "PCIE_PERST")
	)
	(segment
		(start 72.8216 114.83242)
		(end 74.43349 113.22053)
		(width 0.2032)
		(layer "In3.Cu")
		(net "PCIE_PERST")
	)
	(segment
		(start 165.1153 138.7469)
		(end 165.1153 137.85312)
		(width 0.127)
		(layer "F.Cu")
		(net "PCIE_RX3_N")
	)
	(segment
		(start 139.52157 157.0786)
		(end 139.52157 153.59923)
		(width 0.127)
		(layer "F.Cu")
		(net "PCIE_RX3_N")
	)
	(segment
		(start 139.3404 157.55643)
		(end 139.54157 157.7576)
		(width 0.127)
		(layer "F.Cu")
		(net "PCIE_RX3_N")
	)
	(segment
		(start 164.9216 138.94059)
		(end 165.1153 138.7469)
		(width 0.127)
		(layer "F.Cu")
		(net "PCIE_RX3_N")
	)
	(segment
		(start 165.05653 137.79436)
		(end 165.1153 137.85312)
		(width 0.127)
		(layer "F.Cu")
		(net "PCIE_RX3_N")
	)
	(segment
		(start 165.05653 137.79436)
		(end 165.05653 136.86372)
		(width 0.127)
		(layer "F.Cu")
		(net "PCIE_RX3_N")
	)
	(segment
		(start 164.9216 139.0162)
		(end 164.9216 138.94059)
		(width 0.127)
		(layer "F.Cu")
		(net "PCIE_RX3_N")
	)
	(via
		(at 139.4716 153.4786)
		(size 0.4064)
		(drill 0.2032)
		(layers "F.Cu" "B.Cu")
		(tenting
			(front yes)
			(back yes)
		)
		(net "PCIE_RX3_N")
	)
	(via
		(at 164.9216 139.0162)
		(size 0.4064)
		(drill 0.2032)
		(layers "F.Cu" "B.Cu")
		(tenting
			(front yes)
			(back yes)
		)
		(net "PCIE_RX3_N")
	)
	(arc
		(start 139.471602 153.478598)
		(mid 139.508583 153.533944)
		(end 139.521569 153.59923)
		(width 0.127)
		(layer "F.Cu")
		(net "PCIE_RX3_N")
	)
	(segment
		(start 139.25529 153.4786)
		(end 139.4716 153.4786)
		(width 0.127)
		(layer "In3.Cu")
		(net "PCIE_RX3_N")
	)
	(segment
		(start 165.1319 139.9162)
		(end 165.1319 139.5277)
		(width 0.127)
		(layer "In3.Cu")
		(net "PCIE_RX3_N")
	)
	(segment
		(start 169.8216 143.84166)
		(end 169.8216 142.07072)
		(width 0.127)
		(layer "In3.Cu")
		(net "PCIE_RX3_N")
	)
	(segment
		(start 138.69248 150.51531)
		(end 138.70484 150.51531)
		(width 0.127)
		(layer "In3.Cu")
		(net "PCIE_RX3_N")
	)
	(segment
		(start 154.29744 145.12675)
		(end 155.19595 146.02525)
		(width 0.127)
		(layer "In3.Cu")
		(net "PCIE_RX3_N")
	)
	(segment
		(start 164.9216 139.02)
		(end 164.9216 139.0162)
		(width 0.127)
		(layer "In3.Cu")
		(net "PCIE_RX3_N")
	)
	(segment
		(start 156.23102 146.45399)
		(end 166.66556 146.45399)
		(width 0.127)
		(layer "In3.Cu")
		(net "PCIE_RX3_N")
	)
	(segment
		(start 138.78848 150.4244)
		(end 139.2568 149.95608)
		(width 0.127)
		(layer "In3.Cu")
		(net "PCIE_RX3_N")
	)
	(segment
		(start 138.1716 153.56468)
		(end 138.1716 151.62432)
		(width 0.127)
		(layer "In3.Cu")
		(net "PCIE_RX3_N")
	)
	(segment
		(start 138.1716 151.03619)
		(end 138.58747 150.62032)
		(width 0.127)
		(layer "In3.Cu")
		(net "PCIE_RX3_N")
	)
	(segment
		(start 169.21562 141.25231)
		(end 169.67138 141.70807)
		(width 0.127)
		(layer "In3.Cu")
		(net "PCIE_RX3_N")
	)
	(segment
		(start 138.76812 150.45646)
		(end 138.78848 150.4244)
		(width 0.127)
		(layer "In3.Cu")
		(net "PCIE_RX3_N")
	)
	(segment
		(start 138.58747 150.62032)
		(end 138.69248 150.51531)
		(width 0.127)
		(layer "In3.Cu")
		(net "PCIE_RX3_N")
	)
	(segment
		(start 168.20218 140.9829)
		(end 168.56522 140.9829)
		(width 0.127)
		(layer "In3.Cu")
		(net "PCIE_RX3_N")
	)
	(segment
		(start 165.35777 140.46148)
		(end 165.42063 140.52434)
		(width 0.127)
		(layer "In3.Cu")
		(net "PCIE_RX3_N")
	)
	(segment
		(start 168.38145 145.40289)
		(end 169.73599 144.04835)
		(width 0.127)
		(layer "In3.Cu")
		(net "PCIE_RX3_N")
	)
	(segment
		(start 167.76976 145.99661)
		(end 168.35079 145.41559)
		(width 0.127)
		(layer "In3.Cu")
		(net "PCIE_RX3_N")
	)
	(segment
		(start 138.1716 151.62432)
		(end 138.1716 151.03619)
		(width 0.127)
		(layer "In3.Cu")
		(net "PCIE_RX3_N")
	)
	(segment
		(start 140.11939 146.6025)
		(end 141.22947 145.49241)
		(width 0.127)
		(layer "In3.Cu")
		(net "PCIE_RX3_N")
	)
	(segment
		(start 166.49701 140.9702)
		(end 168.17151 140.9702)
		(width 0.127)
		(layer "In3.Cu")
		(net "PCIE_RX3_N")
	)
	(segment
		(start 143.22308 144.66663)
		(end 153.18663 144.66663)
		(width 0.127)
		(layer "In3.Cu")
		(net "PCIE_RX3_N")
	)
	(segment
		(start 139.2936 149.86668)
		(end 139.2936 148.59611)
		(width 0.127)
		(layer "In3.Cu")
		(net "PCIE_RX3_N")
	)
	(arc
		(start 139.130367 153.578677)
		(mid 138.659868 153.965198)
		(end 138.175555 153.596132)
		(width 0.127)
		(layer "In3.Cu")
		(net "PCIE_RX3_N")
	)
	(arc
		(start 138.768122 150.45645)
		(mid 138.754375 150.474524)
		(end 138.737629 150.48986)
		(width 0.127)
		(layer "In3.Cu")
		(net "PCIE_RX3_N")
	)
	(arc
		(start 138.175555 153.596127)
		(mid 138.172593 153.580527)
		(end 138.1716 153.56468)
		(width 0.127)
		(layer "In3.Cu")
		(net "PCIE_RX3_N")
	)
	(arc
		(start 139.2936 148.59611)
		(mid 139.508214 147.517172)
		(end 140.119383 146.602493)
		(width 0.127)
		(layer "In3.Cu")
		(net "PCIE_RX3_N")
	)
	(arc
		(start 141.229463 145.492413)
		(mid 142.144142 144.881244)
		(end 143.22308 144.66663)
		(width 0.127)
		(layer "In3.Cu")
		(net "PCIE_RX3_N")
	)
	(arc
		(start 168.350846 145.415534)
		(mid 168.364893 145.406176)
		(end 168.38145 145.40289)
		(width 0.127)
		(layer "In3.Cu")
		(net "PCIE_RX3_N")
	)
	(arc
		(start 138.704837 150.51531)
		(mid 138.721141 150.50247)
		(end 138.737631 150.489869)
		(width 0.127)
		(layer "In3.Cu")
		(net "PCIE_RX3_N")
	)
	(arc
		(start 168.56522 140.9829)
		(mid 168.917216 141.052916)
		(end 169.215624 141.252306)
		(width 0.127)
		(layer "In3.Cu")
		(net "PCIE_RX3_N")
	)
	(arc
		(start 153.18663 144.66663)
		(mid 153.787378 144.786036)
		(end 154.296801 145.1261)
		(width 0.127)
		(layer "In3.Cu")
		(net "PCIE_RX3_N")
	)
	(arc
		(start 168.35079 145.41559)
		(mid 168.350818 145.415562)
		(end 168.350846 145.415534)
		(width 0.127)
		(layer "In3.Cu")
		(net "PCIE_RX3_N")
	)
	(arc
		(start 167.769764 145.996614)
		(mid 167.263151 146.335122)
		(end 166.66556 146.45399)
		(width 0.127)
		(layer "In3.Cu")
		(net "PCIE_RX3_N")
	)
	(arc
		(start 168.20218 140.9829)
		(mid 168.185583 140.979599)
		(end 168.171513 140.970197)
		(width 0.127)
		(layer "In3.Cu")
		(net "PCIE_RX3_N")
	)
	(arc
		(start 164.9216 139.01999)
		(mid 165.077245 139.252929)
		(end 165.1319 139.5277)
		(width 0.127)
		(layer "In3.Cu")
		(net "PCIE_RX3_N")
	)
	(arc
		(start 166.497012 140.9702)
		(mid 165.914473 140.854326)
		(end 165.420621 140.524344)
		(width 0.127)
		(layer "In3.Cu")
		(net "PCIE_RX3_N")
	)
	(arc
		(start 165.357765 140.461485)
		(mid 165.190601 140.211306)
		(end 165.131901 139.9162)
		(width 0.127)
		(layer "In3.Cu")
		(net "PCIE_RX3_N")
	)
	(arc
		(start 169.671384 141.708066)
		(mid 169.78256 141.874453)
		(end 169.8216 142.07072)
		(width 0.127)
		(layer "In3.Cu")
		(net "PCIE_RX3_N")
	)
	(arc
		(start 156.23102 146.454)
		(mid 155.670844 146.342574)
		(end 155.195949 146.025259)
		(width 0.127)
		(layer "In3.Cu")
		(net "PCIE_RX3_N")
	)
	(arc
		(start 139.2936 149.86668)
		(mid 139.284039 149.915024)
		(end 139.256795 149.956088)
		(width 0.127)
		(layer "In3.Cu")
		(net "PCIE_RX3_N")
	)
	(arc
		(start 139.130377 153.578674)
		(mid 139.175086 153.506483)
		(end 139.255293 153.478602)
		(width 0.127)
		(layer "In3.Cu")
		(net "PCIE_RX3_N")
	)
	(arc
		(start 169.736372 144.047962)
		(mid 169.73618 144.048155)
		(end 169.735987 144.048347)
		(width 0.127)
		(layer "In3.Cu")
		(net "PCIE_RX3_N")
	)
	(arc
		(start 169.8216 143.84166)
		(mid 169.799454 143.953267)
		(end 169.736372 144.047962)
		(width 0.127)
		(layer "In3.Cu")
		(net "PCIE_RX3_N")
	)
	(segment
		(start 165.58401 138.97861)
		(end 165.58401 136.89133)
		(width 0.127)
		(layer "F.Cu")
		(net "PCIE_RX3_P")
	)
	(segment
		(start 165.5564 136.86372)
		(end 165.58401 136.89133)
		(width 0.127)
		(layer "F.Cu")
		(net "PCIE_RX3_P")
	)
	(segment
		(start 165.58401 138.97861)
		(end 165.6216 139.0162)
		(width 0.127)
		(layer "F.Cu")
		(net "PCIE_RX3_P")
	)
	(segment
		(start 138.52157 157.0786)
		(end 138.52157 153.8408)
		(width 0.127)
		(layer "F.Cu")
		(net "PCIE_RX3_P")
	)
	(segment
		(start 138.54157 157.7576)
		(end 138.7308 157.56837)
		(width 0.127)
		(layer "F.Cu")
		(net "PCIE_RX3_P")
	)
	(via
		(at 138.67116 153.47904)
		(size 0.4064)
		(drill 0.2032)
		(layers "F.Cu" "B.Cu")
		(tenting
			(front yes)
			(back yes)
		)
		(net "PCIE_RX3_P")
	)
	(via
		(at 165.6216 139.0162)
		(size 0.4064)
		(drill 0.2032)
		(layers "F.Cu" "B.Cu")
		(tenting
			(front yes)
			(back yes)
		)
		(net "PCIE_RX3_P")
	)
	(arc
		(start 138.52157 153.8408)
		(mid 138.560443 153.645064)
		(end 138.671162 153.479036)
		(width 0.127)
		(layer "F.Cu")
		(net "PCIE_RX3_P")
	)
	(segment
		(start 139.07486 150.53315)
		(end 139.088 150.52)
		(width 0.127)
		(layer "In3.Cu")
		(net "PCIE_RX3_P")
	)
	(segment
		(start 154.18172 145.40615)
		(end 154.99839 146.22282)
		(width 0.127)
		(layer "In3.Cu")
		(net "PCIE_RX3_P")
	)
	(segment
		(start 165.4113 139.9162)
		(end 165.4113 139.5277)
		(width 0.127)
		(layer "In3.Cu")
		(net "PCIE_RX3_P")
	)
	(segment
		(start 165.6216 139.02)
		(end 165.6216 139.0162)
		(width 0.127)
		(layer "In3.Cu")
		(net "PCIE_RX3_P")
	)
	(segment
		(start 142.97731 144.94603)
		(end 153.0709 144.94603)
		(width 0.127)
		(layer "In3.Cu")
		(net "PCIE_RX3_P")
	)
	(segment
		(start 169.33135 140.97291)
		(end 169.86895 141.51051)
		(width 0.127)
		(layer "In3.Cu")
		(net "PCIE_RX3_P")
	)
	(segment
		(start 138.6161 151.82986)
		(end 138.95378 151.82986)
		(width 0.127)
		(layer "In3.Cu")
		(net "PCIE_RX3_P")
	)
	(segment
		(start 155.96149 146.70799)
		(end 166.66556 146.70799)
		(width 0.127)
		(layer "In3.Cu")
		(net "PCIE_RX3_P")
	)
	(segment
		(start 169.98998 144.15357)
		(end 169.98998 144.15356)
		(width 0.127)
		(layer "In3.Cu")
		(net "PCIE_RX3_P")
	)
	(segment
		(start 165.55533 140.26392)
		(end 165.76506 140.47365)
		(width 0.127)
		(layer "In3.Cu")
		(net "PCIE_RX3_P")
	)
	(segment
		(start 165.76506 140.47365)
		(end 165.76507 140.47366)
		(width 0.127)
		(layer "In3.Cu")
		(net "PCIE_RX3_P")
	)
	(segment
		(start 138.6621 152.59186)
		(end 138.931 152.59186)
		(width 0.127)
		(layer "In3.Cu")
		(net "PCIE_RX3_P")
	)
	(segment
		(start 140.31695 146.80006)
		(end 141.60082 145.5162)
		(width 0.127)
		(layer "In3.Cu")
		(net "PCIE_RX3_P")
	)
	(segment
		(start 168.28724 140.7162)
		(end 168.28725 140.7162)
		(width 0.127)
		(layer "In3.Cu")
		(net "PCIE_RX3_P")
	)
	(segment
		(start 170.0756 143.94687)
		(end 170.0756 143.94687)
		(width 0.127)
		(layer "In3.Cu")
		(net "PCIE_RX3_P")
	)
	(segment
		(start 138.95376 151.44886)
		(end 138.95378 151.44886)
		(width 0.127)
		(layer "In3.Cu")
		(net "PCIE_RX3_P")
	)
	(segment
		(start 138.80045 150.80755)
		(end 139.07485 150.53315)
		(width 0.127)
		(layer "In3.Cu")
		(net "PCIE_RX3_P")
	)
	(segment
		(start 170.0756 143.94687)
		(end 170.0756 142.63831)
		(width 0.127)
		(layer "In3.Cu")
		(net "PCIE_RX3_P")
	)
	(segment
		(start 139.07485 150.53315)
		(end 139.07486 150.53315)
		(width 0.127)
		(layer "In3.Cu")
		(net "PCIE_RX3_P")
	)
	(segment
		(start 167.92397 146.23754)
		(end 168.46658 145.69493)
		(width 0.127)
		(layer "In3.Cu")
		(net "PCIE_RX3_P")
	)
	(segment
		(start 139.573 149.86668)
		(end 139.573 148.59611)
		(width 0.127)
		(layer "In3.Cu")
		(net "PCIE_RX3_P")
	)
	(segment
		(start 138.6161 152.21086)
		(end 138.931 152.21086)
		(width 0.127)
		(layer "In3.Cu")
		(net "PCIE_RX3_P")
	)
	(segment
		(start 165.92669 140.58036)
		(end 165.92771 140.58096)
		(width 0.127)
		(layer "In3.Cu")
		(net "PCIE_RX3_P")
	)
	(segment
		(start 168.47922 145.66433)
		(end 169.9148 144.22875)
		(width 0.127)
		(layer "In3.Cu")
		(net "PCIE_RX3_P")
	)
	(segment
		(start 139.08801 150.52)
		(end 139.45489 150.15312)
		(width 0.127)
		(layer "In3.Cu")
		(net "PCIE_RX3_P")
	)
	(segment
		(start 138.5088 153.31667)
		(end 138.67116 153.47904)
		(width 0.127)
		(layer "In3.Cu")
		(net "PCIE_RX3_P")
	)
	(segment
		(start 169.91638 144.22716)
		(end 169.98998 144.15357)
		(width 0.127)
		(layer "In3.Cu")
		(net "PCIE_RX3_P")
	)
	(segment
		(start 170.101 142.18693)
		(end 170.101 142.07072)
		(width 0.127)
		(layer "In3.Cu")
		(net "PCIE_RX3_P")
	)
	(segment
		(start 139.07486 150.53315)
		(end 139.07486 150.53315)
		(width 0.127)
		(layer "In3.Cu")
		(net "PCIE_RX3_P")
	)
	(segment
		(start 139.088 150.52)
		(end 139.08801 150.52)
		(width 0.127)
		(layer "In3.Cu")
		(net "PCIE_RX3_P")
	)
	(segment
		(start 165.76506 140.47365)
		(end 165.76506 140.47365)
		(width 0.127)
		(layer "In3.Cu")
		(net "PCIE_RX3_P")
	)
	(segment
		(start 168.31791 140.7035)
		(end 168.68095 140.7035)
		(width 0.127)
		(layer "In3.Cu")
		(net "PCIE_RX3_P")
	)
	(segment
		(start 138.4716 153.16337)
		(end 138.4716 152.78236)
		(width 0.127)
		(layer "In3.Cu")
		(net "PCIE_RX3_P")
	)
	(segment
		(start 138.76326 151.25836)
		(end 138.76326 150.89735)
		(width 0.127)
		(layer "In3.Cu")
		(net "PCIE_RX3_P")
	)
	(segment
		(start 138.4716 153.16337)
		(end 138.4716 153.22687)
		(width 0.127)
		(layer "In3.Cu")
		(net "PCIE_RX3_P")
	)
	(segment
		(start 166.49437 140.7162)
		(end 168.28724 140.7162)
		(width 0.127)
		(layer "In3.Cu")
		(net "PCIE_RX3_P")
	)
	(arc
		(start 169.868949 141.510501)
		(mid 170.040691 141.767532)
		(end 170.100999 142.07072)
		(width 0.127)
		(layer "In3.Cu")
		(net "PCIE_RX3_P")
	)
	(arc
		(start 153.0709 144.94604)
		(mid 153.672069 145.06562)
		(end 154.181715 145.406155)
		(width 0.127)
		(layer "In3.Cu")
		(net "PCIE_RX3_P")
	)
	(arc
		(start 139.573 148.59611)
		(mid 139.766346 147.624094)
		(end 140.316949 146.800059)
		(width 0.127)
		(layer "In3.Cu")
		(net "PCIE_RX3_P")
	)
	(arc
		(start 166.494373 140.716197)
		(mid 166.206748 140.682537)
		(end 165.934257 140.584508)
		(width 0.127)
		(layer "In3.Cu")
		(net "PCIE_RX3_P")
	)
	(arc
		(start 155.961494 146.707987)
		(mid 155.644925 146.64715)
		(end 155.358865 146.498532)
		(width 0.127)
		(layer "In3.Cu")
		(net "PCIE_RX3_P")
	)
	(arc
		(start 165.55533 140.26392)
		(mid 165.448732 140.104385)
		(end 165.4113 139.9162)
		(width 0.127)
		(layer "In3.Cu")
		(net "PCIE_RX3_P")
	)
	(arc
		(start 169.916383 144.22716)
		(mid 169.915591 144.227953)
		(end 169.914798 144.228745)
		(width 0.127)
		(layer "In3.Cu")
		(net "PCIE_RX3_P")
	)
	(arc
		(start 167.923969 146.237539)
		(mid 167.848408 146.308606)
		(end 167.768636 146.374912)
		(width 0.127)
		(layer "In3.Cu")
		(net "PCIE_RX3_P")
	)
	(arc
		(start 138.76326 150.89735)
		(mid 138.772927 150.84875)
		(end 138.800456 150.807549)
		(width 0.127)
		(layer "In3.Cu")
		(net "PCIE_RX3_P")
	)
	(arc
		(start 142.825807 144.951935)
		(mid 142.901501 144.947507)
		(end 142.97731 144.946031)
		(width 0.127)
		(layer "In3.Cu")
		(net "PCIE_RX3_P")
	)
	(arc
		(start 168.83327 140.7162)
		(mid 169.102336 140.805701)
		(end 169.331354 140.972906)
		(width 0.127)
		(layer "In3.Cu")
		(net "PCIE_RX3_P")
	)
	(arc
		(start 138.4716 152.78236)
		(mid 138.527396 152.647656)
		(end 138.6621 152.59186)
		(width 0.127)
		(layer "In3.Cu")
		(net "PCIE_RX3_P")
	)
	(arc
		(start 155.35885 146.498531)
		(mid 155.169472 146.372631)
		(end 154.99838 146.222823)
		(width 0.127)
		(layer "In3.Cu")
		(net "PCIE_RX3_P")
	)
	(arc
		(start 166.72688 146.73339)
		(mid 166.693694 146.726789)
		(end 166.66556 146.70799)
		(width 0.127)
		(layer "In3.Cu")
		(net "PCIE_RX3_P")
	)
	(arc
		(start 141.719089 145.40774)
		(mid 142.241429 145.115874)
		(end 142.817172 144.952946)
		(width 0.127)
		(layer "In3.Cu")
		(net "PCIE_RX3_P")
	)
	(arc
		(start 165.4113 139.5277)
		(mid 165.465955 139.252929)
		(end 165.6216 139.01999)
		(width 0.127)
		(layer "In3.Cu")
		(net "PCIE_RX3_P")
	)
	(arc
		(start 138.931 152.21086)
		(mid 139.1215 152.40136)
		(end 138.931 152.59186)
		(width 0.127)
		(layer "In3.Cu")
		(net "PCIE_RX3_P")
	)
	(arc
		(start 170.101 142.18693)
		(mid 170.094645 142.412973)
		(end 170.0756 142.638301)
		(width 0.127)
		(layer "In3.Cu")
		(net "PCIE_RX3_P")
	)
	(arc
		(start 138.95378 151.44886)
		(mid 139.14428 151.63936)
		(end 138.95378 151.82986)
		(width 0.127)
		(layer "In3.Cu")
		(net "PCIE_RX3_P")
	)
	(arc
		(start 141.600814 145.516194)
		(mid 141.655559 145.463544)
		(end 141.712317 145.41307)
		(width 0.127)
		(layer "In3.Cu")
		(net "PCIE_RX3_P")
	)
	(arc
		(start 170.055892 143.987081)
		(mid 170.063959 143.9661)
		(end 170.075599 143.94687)
		(width 0.127)
		(layer "In3.Cu")
		(net "PCIE_RX3_P")
	)
	(arc
		(start 168.68095 140.7035)
		(mid 168.757374 140.70668)
		(end 168.83327 140.7162)
		(width 0.127)
		(layer "In3.Cu")
		(net "PCIE_RX3_P")
	)
	(arc
		(start 165.934258 140.584508)
		(mid 165.930959 140.58278)
		(end 165.927712 140.580957)
		(width 0.127)
		(layer "In3.Cu")
		(net "PCIE_RX3_P")
	)
	(arc
		(start 167.768636 146.374912)
		(mid 167.414315 146.587537)
		(end 167.019038 146.70799)
		(width 0.127)
		(layer "In3.Cu")
		(net "PCIE_RX3_P")
	)
	(arc
		(start 165.926691 140.580355)
		(mid 165.919521 140.575971)
		(end 165.912365 140.571564)
		(width 0.127)
		(layer "In3.Cu")
		(net "PCIE_RX3_P")
	)
	(arc
		(start 138.6161 152.21086)
		(mid 138.4256 152.02036)
		(end 138.6161 151.82986)
		(width 0.127)
		(layer "In3.Cu")
		(net "PCIE_RX3_P")
	)
	(arc
		(start 165.912365 140.571565)
		(mid 165.837906 140.523828)
		(end 165.76507 140.473651)
		(width 0.127)
		(layer "In3.Cu")
		(net "PCIE_RX3_P")
	)
	(arc
		(start 169.989984 144.153564)
		(mid 169.995372 144.131678)
		(end 170.004544 144.111088)
		(width 0.127)
		(layer "In3.Cu")
		(net "PCIE_RX3_P")
	)
	(arc
		(start 167.019038 146.70799)
		(mid 166.87351 146.727028)
		(end 166.72688 146.73339)
		(width 0.127)
		(layer "In3.Cu")
		(net "PCIE_RX3_P")
	)
	(arc
		(start 142.817174 144.952957)
		(mid 142.821482 144.952376)
		(end 142.825807 144.951943)
		(width 0.127)
		(layer "In3.Cu")
		(net "PCIE_RX3_P")
	)
	(arc
		(start 138.508797 153.316673)
		(mid 138.481268 153.275473)
		(end 138.471599 153.226875)
		(width 0.127)
		(layer "In3.Cu")
		(net "PCIE_RX3_P")
	)
	(arc
		(start 170.05589 143.98708)
		(mid 170.034039 144.050663)
		(end 170.004544 144.11108)
		(width 0.127)
		(layer "In3.Cu")
		(net "PCIE_RX3_P")
	)
	(arc
		(start 168.287251 140.716199)
		(mid 168.301318 140.706801)
		(end 168.31791 140.7035)
		(width 0.127)
		(layer "In3.Cu")
		(net "PCIE_RX3_P")
	)
	(arc
		(start 138.95376 151.44886)
		(mid 138.819056 151.393064)
		(end 138.76326 151.25836)
		(width 0.127)
		(layer "In3.Cu")
		(net "PCIE_RX3_P")
	)
	(arc
		(start 141.712325 145.413075)
		(mid 141.715666 145.410353)
		(end 141.719098 145.407745)
		(width 0.127)
		(layer "In3.Cu")
		(net "PCIE_RX3_P")
	)
	(arc
		(start 139.573 149.86668)
		(mid 139.542314 150.021599)
		(end 139.454891 150.153123)
		(width 0.127)
		(layer "In3.Cu")
		(net "PCIE_RX3_P")
	)
	(arc
		(start 168.47922 145.66433)
		(mid 168.475935 145.680887)
		(end 168.466576 145.694934)
		(width 0.127)
		(layer "In3.Cu")
		(net "PCIE_RX3_P")
	)
	(segment
		(start 135.52158 157.0786)
		(end 135.52158 153.59925)
		(width 0.127)
		(layer "F.Cu")
		(net "PCIE_RX2_N")
	)
	(segment
		(start 166.5564 142.77197)
		(end 166.5564 140.9135)
		(width 0.127)
		(layer "F.Cu")
		(net "PCIE_RX2_N")
	)
	(via
		(at 166.44668 143.03687)
		(size 0.4064)
		(drill 0.2032)
		(layers "F.Cu" "B.Cu")
		(tenting
			(front yes)
			(back yes)
		)
		(net "PCIE_RX2_N")
	)
	(via
		(at 135.4716 153.4786)
		(size 0.4064)
		(drill 0.2032)
		(layers "F.Cu" "B.Cu")
		(tenting
			(front yes)
			(back yes)
		)
		(net "PCIE_RX2_N")
	)
	(arc
		(start 135.541576 157.757603)
		(mid 135.533304 157.745223)
		(end 135.5304 157.73062)
		(width 0.127)
		(layer "F.Cu")
		(net "PCIE_RX2_N")
	)
	(arc
		(start 166.5564 142.77197)
		(mid 166.527883 142.915335)
		(end 166.446673 143.036873)
		(width 0.127)
		(layer "F.Cu")
		(net "PCIE_RX2_N")
	)
	(arc
		(start 135.471604 153.478596)
		(mid 135.508592 153.533953)
		(end 135.521581 153.59925)
		(width 0.127)
		(layer "F.Cu")
		(net "PCIE_RX2_N")
	)
	(arc
		(start 135.541577 157.757603)
		(mid 135.364116 157.492014)
		(end 135.3018 157.17873)
		(width 0.127)
		(layer "F.Cu")
		(net "PCIE_RX2_N")
	)
	(segment
		(start 136.1819 148.24663)
		(end 136.1819 147.5286)
		(width 0.127)
		(layer "In3.Cu")
		(net "PCIE_RX2_N")
	)
	(segment
		(start 165.63008 144.91078)
		(end 166.43321 144.10765)
		(width 0.127)
		(layer "In3.Cu")
		(net "PCIE_RX2_N")
	)
	(segment
		(start 166.44668 143.04067)
		(end 166.55183 143.14582)
		(width 0.127)
		(layer "In3.Cu")
		(net "PCIE_RX2_N")
	)
	(segment
		(start 155.40573 143.6368)
		(end 155.40573 143.6368)
		(width 0.127)
		(layer "In3.Cu")
		(net "PCIE_RX2_N")
	)
	(segment
		(start 135.25564 153.4786)
		(end 135.4716 153.4786)
		(width 0.127)
		(layer "In3.Cu")
		(net "PCIE_RX2_N")
	)
	(segment
		(start 158.16781 145.32901)
		(end 164.83205 145.32901)
		(width 0.127)
		(layer "In3.Cu")
		(net "PCIE_RX2_N")
	)
	(segment
		(start 156.69523 144.21927)
		(end 156.69523 144.21927)
		(width 0.127)
		(layer "In3.Cu")
		(net "PCIE_RX2_N")
	)
	(segment
		(start 166.65698 143.56743)
		(end 166.65698 143.39967)
		(width 0.127)
		(layer "In3.Cu")
		(net "PCIE_RX2_N")
	)
	(segment
		(start 134.40198 153.78627)
		(end 134.40267 153.78697)
		(width 0.127)
		(layer "In3.Cu")
		(net "PCIE_RX2_N")
	)
	(segment
		(start 156.61297 144.13701)
		(end 156.69523 144.21927)
		(width 0.127)
		(layer "In3.Cu")
		(net "PCIE_RX2_N")
	)
	(segment
		(start 137.00768 145.53498)
		(end 138.5764 143.96627)
		(width 0.127)
		(layer "In3.Cu")
		(net "PCIE_RX2_N")
	)
	(segment
		(start 156.61297 144.13701)
		(end 156.61297 144.137)
		(width 0.127)
		(layer "In3.Cu")
		(net "PCIE_RX2_N")
	)
	(segment
		(start 134.41435 150.73585)
		(end 135.6716 149.47859)
		(width 0.127)
		(layer "In3.Cu")
		(net "PCIE_RX2_N")
	)
	(segment
		(start 156.69523 144.21927)
		(end 157.54841 145.07245)
		(width 0.127)
		(layer "In3.Cu")
		(net "PCIE_RX2_N")
	)
	(segment
		(start 139.3718 143.6368)
		(end 155.40573 143.6368)
		(width 0.127)
		(layer "In3.Cu")
		(net "PCIE_RX2_N")
	)
	(segment
		(start 166.44668 143.04067)
		(end 166.44668 143.03687)
		(width 0.127)
		(layer "In3.Cu")
		(net "PCIE_RX2_N")
	)
	(arc
		(start 133.78276 152.258762)
		(mid 133.947103 151.434496)
		(end 134.414345 150.735849)
		(width 0.127)
		(layer "In3.Cu")
		(net "PCIE_RX2_N")
	)
	(arc
		(start 155.405733 143.6368)
		(mid 156.059116 143.766803)
		(end 156.612974 144.137007)
		(width 0.127)
		(layer "In3.Cu")
		(net "PCIE_RX2_N")
	)
	(arc
		(start 166.551831 143.145819)
		(mid 166.629652 143.262287)
		(end 166.65698 143.39967)
		(width 0.127)
		(layer "In3.Cu")
		(net "PCIE_RX2_N")
	)
	(arc
		(start 136.1819 147.5286)
		(mid 136.183736 147.426869)
		(end 136.189241 147.32527)
		(width 0.127)
		(layer "In3.Cu")
		(net "PCIE_RX2_N")
	)
	(arc
		(start 166.65697 143.56743)
		(mid 166.598815 143.859796)
		(end 166.433203 144.107653)
		(width 0.127)
		(layer "In3.Cu")
		(net "PCIE_RX2_N")
	)
	(arc
		(start 138.576397 143.966267)
		(mid 138.941331 143.722426)
		(end 139.3718 143.6368)
		(width 0.127)
		(layer "In3.Cu")
		(net "PCIE_RX2_N")
	)
	(arc
		(start 158.16781 145.32901)
		(mid 157.832591 145.262331)
		(end 157.548406 145.072444)
		(width 0.127)
		(layer "In3.Cu")
		(net "PCIE_RX2_N")
	)
	(arc
		(start 136.1819 148.24663)
		(mid 136.049278 148.913368)
		(end 135.671601 149.478601)
		(width 0.127)
		(layer "In3.Cu")
		(net "PCIE_RX2_N")
	)
	(arc
		(start 165.630076 144.910786)
		(mid 165.427828 145.087569)
		(end 165.203749 145.235707)
		(width 0.127)
		(layer "In3.Cu")
		(net "PCIE_RX2_N")
	)
	(arc
		(start 134.40199 153.786265)
		(mid 133.943722 153.082774)
		(end 133.782771 152.258758)
		(width 0.127)
		(layer "In3.Cu")
		(net "PCIE_RX2_N")
	)
	(arc
		(start 135.130738 153.57858)
		(mid 135.175464 153.506454)
		(end 135.255633 153.478603)
		(width 0.127)
		(layer "In3.Cu")
		(net "PCIE_RX2_N")
	)
	(arc
		(start 135.130742 153.57858)
		(mid 134.828999 153.900415)
		(end 134.402669 153.786972)
		(width 0.127)
		(layer "In3.Cu")
		(net "PCIE_RX2_N")
	)
	(arc
		(start 136.189241 147.32527)
		(mid 136.437141 146.356377)
		(end 137.007683 145.534983)
		(width 0.127)
		(layer "In3.Cu")
		(net "PCIE_RX2_N")
	)
	(arc
		(start 165.203749 145.2357)
		(mid 165.022476 145.300595)
		(end 164.832046 145.329013)
		(width 0.127)
		(layer "In3.Cu")
		(net "PCIE_RX2_N")
	)
	(segment
		(start 134.69133 153.40817)
		(end 134.69163 153.40787)
		(width 0.127)
		(layer "F.Cu")
		(net "PCIE_RX2_P")
	)
	(segment
		(start 134.64179 153.51109)
		(end 134.64227 153.51052)
		(width 0.127)
		(layer "F.Cu")
		(net "PCIE_RX2_P")
	)
	(segment
		(start 167.05653 142.81923)
		(end 167.05653 140.9135)
		(width 0.127)
		(layer "F.Cu")
		(net "PCIE_RX2_P")
	)
	(segment
		(start 134.54158 157.7576)
		(end 134.616 157.68318)
		(width 0.127)
		(layer "F.Cu")
		(net "PCIE_RX2_P")
	)
	(segment
		(start 134.489 157.70502)
		(end 134.54158 157.7576)
		(width 0.127)
		(layer "F.Cu")
		(net "PCIE_RX2_P")
	)
	(segment
		(start 134.52158 157.0786)
		(end 134.52158 153.84078)
		(width 0.127)
		(layer "F.Cu")
		(net "PCIE_RX2_P")
	)
	(segment
		(start 134.68889 153.41236)
		(end 134.69133 153.40817)
		(width 0.127)
		(layer "F.Cu")
		(net "PCIE_RX2_P")
	)
	(segment
		(start 134.6632 153.47477)
		(end 134.68 153.43091)
		(width 0.127)
		(layer "F.Cu")
		(net "PCIE_RX2_P")
	)
	(via
		(at 167.14668 143.03687)
		(size 0.4064)
		(drill 0.2032)
		(layers "F.Cu" "B.Cu")
		(tenting
			(front yes)
			(back yes)
		)
		(net "PCIE_RX2_P")
	)
	(via
		(at 134.69163 153.40787)
		(size 0.4064)
		(drill 0.2032)
		(layers "F.Cu" "B.Cu")
		(tenting
			(front yes)
			(back yes)
		)
		(net "PCIE_RX2_P")
	)
	(arc
		(start 134.663198 153.474767)
		(mid 134.654202 153.4935)
		(end 134.642272 153.510515)
		(width 0.127)
		(layer "F.Cu")
		(net "PCIE_RX2_P")
	)
	(arc
		(start 134.52158 153.84078)
		(mid 134.552571 153.665316)
		(end 134.641794 153.511085)
		(width 0.127)
		(layer "F.Cu")
		(net "PCIE_RX2_P")
	)
	(arc
		(start 134.680002 153.430905)
		(mid 134.684069 153.421452)
		(end 134.688888 153.41236)
		(width 0.127)
		(layer "F.Cu")
		(net "PCIE_RX2_P")
	)
	(arc
		(start 167.14668 143.03687)
		(mid 167.07996 142.937016)
		(end 167.056531 142.81923)
		(width 0.127)
		(layer "F.Cu")
		(net "PCIE_RX2_P")
	)
	(segment
		(start 167.04153 143.14582)
		(end 167.14668 143.04067)
		(width 0.127)
		(layer "In3.Cu")
		(net "PCIE_RX2_P")
	)
	(segment
		(start 134.69162 153.40787)
		(end 134.69163 153.40787)
		(width 0.127)
		(layer "In3.Cu")
		(net "PCIE_RX2_P")
	)
	(segment
		(start 156.41583 144.335)
		(end 156.41583 144.335)
		(width 0.127)
		(layer "In3.Cu")
		(net "PCIE_RX2_P")
	)
	(segment
		(start 165.82764 145.10834)
		(end 166.82939 144.1066)
		(width 0.127)
		(layer "In3.Cu")
		(net "PCIE_RX2_P")
	)
	(segment
		(start 134.67172 153.16517)
		(end 134.67176 153.06998)
		(width 0.127)
		(layer "In3.Cu")
		(net "PCIE_RX2_P")
	)
	(segment
		(start 167.14668 143.04067)
		(end 167.14668 143.03687)
		(width 0.127)
		(layer "In3.Cu")
		(net "PCIE_RX2_P")
	)
	(segment
		(start 134.67261 150.92528)
		(end 134.67261 150.92527)
		(width 0.127)
		(layer "In3.Cu")
		(net "PCIE_RX2_P")
	)
	(segment
		(start 134.33159 152.49841)
		(end 134.8658 152.49841)
		(width 0.127)
		(layer "In3.Cu")
		(net "PCIE_RX2_P")
	)
	(segment
		(start 134.70981 150.83552)
		(end 135.87003 149.6753)
		(width 0.127)
		(layer "In3.Cu")
		(net "PCIE_RX2_P")
	)
	(segment
		(start 165.28886 145.50292)
		(end 165.34331 145.44847)
		(width 0.127)
		(layer "In3.Cu")
		(net "PCIE_RX2_P")
	)
	(segment
		(start 134.67165 153.33945)
		(end 134.67165 153.33945)
		(width 0.127)
		(layer "In3.Cu")
		(net "PCIE_RX2_P")
	)
	(segment
		(start 139.16301 143.9162)
		(end 155.4037 143.9162)
		(width 0.127)
		(layer "In3.Cu")
		(net "PCIE_RX2_P")
	)
	(segment
		(start 134.6717 153.22867)
		(end 134.67172 153.16517)
		(width 0.127)
		(layer "In3.Cu")
		(net "PCIE_RX2_P")
	)
	(segment
		(start 134.48184 152.11741)
		(end 134.8658 152.11741)
		(width 0.127)
		(layer "In3.Cu")
		(net "PCIE_RX2_P")
	)
	(segment
		(start 134.33159 152.87941)
		(end 134.48126 152.87941)
		(width 0.127)
		(layer "In3.Cu")
		(net "PCIE_RX2_P")
	)
	(segment
		(start 137.20525 145.73255)
		(end 138.92161 144.01619)
		(width 0.127)
		(layer "In3.Cu")
		(net "PCIE_RX2_P")
	)
	(segment
		(start 134.67165 153.33945)
		(end 134.6717 153.22867)
		(width 0.127)
		(layer "In3.Cu")
		(net "PCIE_RX2_P")
	)
	(segment
		(start 136.4613 148.24785)
		(end 136.4613 147.5286)
		(width 0.127)
		(layer "In3.Cu")
		(net "PCIE_RX2_P")
	)
	(segment
		(start 134.48184 151.73641)
		(end 134.48186 151.73641)
		(width 0.127)
		(layer "In3.Cu")
		(net "PCIE_RX2_P")
	)
	(segment
		(start 157.01953 144.90278)
		(end 157.4432 145.32645)
		(width 0.127)
		(layer "In3.Cu")
		(net "PCIE_RX2_P")
	)
	(segment
		(start 134.67236 151.54598)
		(end 134.67261 150.92861)
		(width 0.127)
		(layer "In3.Cu")
		(net "PCIE_RX2_P")
	)
	(segment
		(start 156.41583 144.335)
		(end 156.7711 144.69027)
		(width 0.127)
		(layer "In3.Cu")
		(net "PCIE_RX2_P")
	)
	(segment
		(start 158.05102 145.58301)
		(end 164.93125 145.58301)
		(width 0.127)
		(layer "In3.Cu")
		(net "PCIE_RX2_P")
	)
	(segment
		(start 166.93638 143.84831)
		(end 166.93638 143.39968)
		(width 0.127)
		(layer "In3.Cu")
		(net "PCIE_RX2_P")
	)
	(segment
		(start 134.67261 150.92861)
		(end 134.67261 150.92528)
		(width 0.127)
		(layer "In3.Cu")
		(net "PCIE_RX2_P")
	)
	(segment
		(start 165.23 145.50292)
		(end 165.28886 145.50292)
		(width 0.127)
		(layer "In3.Cu")
		(net "PCIE_RX2_P")
	)
	(arc
		(start 136.4613 147.5286)
		(mid 136.654646 146.556584)
		(end 137.205249 145.732549)
		(width 0.127)
		(layer "In3.Cu")
		(net "PCIE_RX2_P")
	)
	(arc
		(start 134.33159 152.87941)
		(mid 134.14109 152.68891)
		(end 134.33159 152.49841)
		(width 0.127)
		(layer "In3.Cu")
		(net "PCIE_RX2_P")
	)
	(arc
		(start 165.230005 145.50292)
		(mid 165.08289 145.551409)
		(end 164.931247 145.583009)
		(width 0.127)
		(layer "In3.Cu")
		(net "PCIE_RX2_P")
	)
	(arc
		(start 134.48184 152.11741)
		(mid 134.29134 151.92691)
		(end 134.48184 151.73641)
		(width 0.127)
		(layer "In3.Cu")
		(net "PCIE_RX2_P")
	)
	(arc
		(start 157.4432 145.326455)
		(mid 157.45791 145.333816)
		(end 157.471545 145.343017)
		(width 0.127)
		(layer "In3.Cu")
		(net "PCIE_RX2_P")
	)
	(arc
		(start 158.051012 145.58302)
		(mid 157.744901 145.502554)
		(end 157.471539 145.343018)
		(width 0.127)
		(layer "In3.Cu")
		(net "PCIE_RX2_P")
	)
	(arc
		(start 165.542008 145.319221)
		(mid 165.560161 145.308301)
		(end 165.579877 145.300551)
		(width 0.127)
		(layer "In3.Cu")
		(net "PCIE_RX2_P")
	)
	(arc
		(start 138.921604 144.016191)
		(mid 139.038533 143.95709)
		(end 139.163004 143.9162)
		(width 0.127)
		(layer "In3.Cu")
		(net "PCIE_RX2_P")
	)
	(arc
		(start 166.93637 143.39968)
		(mid 166.963698 143.262293)
		(end 167.041522 143.145822)
		(width 0.127)
		(layer "In3.Cu")
		(net "PCIE_RX2_P")
	)
	(arc
		(start 165.827649 145.108344)
		(mid 165.739683 145.188323)
		(end 165.644524 145.259593)
		(width 0.127)
		(layer "In3.Cu")
		(net "PCIE_RX2_P")
	)
	(arc
		(start 155.403696 143.9162)
		(mid 155.951457 144.024839)
		(end 156.415833 144.335)
		(width 0.127)
		(layer "In3.Cu")
		(net "PCIE_RX2_P")
	)
	(arc
		(start 134.48126 152.87941)
		(mid 134.61599 152.935232)
		(end 134.67176 153.069983)
		(width 0.127)
		(layer "In3.Cu")
		(net "PCIE_RX2_P")
	)
	(arc
		(start 134.687787 150.865115)
		(mid 134.697717 150.849513)
		(end 134.709807 150.835518)
		(width 0.127)
		(layer "In3.Cu")
		(net "PCIE_RX2_P")
	)
	(arc
		(start 134.691621 153.407864)
		(mid 134.676739 153.375088)
		(end 134.671651 153.339452)
		(width 0.127)
		(layer "In3.Cu")
		(net "PCIE_RX2_P")
	)
	(arc
		(start 157.019527 144.902779)
		(mid 156.891127 144.801416)
		(end 156.771095 144.690272)
		(width 0.127)
		(layer "In3.Cu")
		(net "PCIE_RX2_P")
	)
	(arc
		(start 134.67236 151.545986)
		(mid 134.616537 151.680641)
		(end 134.48186 151.73641)
		(width 0.127)
		(layer "In3.Cu")
		(net "PCIE_RX2_P")
	)
	(arc
		(start 134.8658 152.11741)
		(mid 135.0563 152.30791)
		(end 134.8658 152.49841)
		(width 0.127)
		(layer "In3.Cu")
		(net "PCIE_RX2_P")
	)
	(arc
		(start 166.93638 143.84831)
		(mid 166.908575 143.988093)
		(end 166.829395 144.106595)
		(width 0.127)
		(layer "In3.Cu")
		(net "PCIE_RX2_P")
	)
	(arc
		(start 134.67261 150.925271)
		(mid 134.676469 150.894252)
		(end 134.687787 150.865114)
		(width 0.127)
		(layer "In3.Cu")
		(net "PCIE_RX2_P")
	)
	(arc
		(start 165.542005 145.319224)
		(mid 165.444354 145.38646)
		(end 165.343307 145.448476)
		(width 0.127)
		(layer "In3.Cu")
		(net "PCIE_RX2_P")
	)
	(arc
		(start 165.644524 145.259593)
		(mid 165.612516 145.280564)
		(end 165.579882 145.300547)
		(width 0.127)
		(layer "In3.Cu")
		(net "PCIE_RX2_P")
	)
	(arc
		(start 136.4613 148.24785)
		(mid 136.307635 149.020377)
		(end 135.870034 149.675294)
		(width 0.127)
		(layer "In3.Cu")
		(net "PCIE_RX2_P")
	)
	(segment
		(start 163.40023 142.18332)
		(end 163.44668 142.13687)
		(width 0.127)
		(layer "F.Cu")
		(net "PCIE_RX1_N")
	)
	(segment
		(start 131.52158 157.0786)
		(end 131.52158 154.84069)
		(width 0.127)
		(layer "F.Cu")
		(net "PCIE_RX1_N")
	)
	(segment
		(start 163.55641 141.87196)
		(end 163.55641 140.9135)
		(width 0.127)
		(layer "F.Cu")
		(net "PCIE_RX1_N")
	)
	(segment
		(start 131.1716 153.99576)
		(end 131.1716 153.4786)
		(width 0.127)
		(layer "F.Cu")
		(net "PCIE_RX1_N")
	)
	(segment
		(start 163.39999 142.18356)
		(end 163.40023 142.18332)
		(width 0.127)
		(layer "F.Cu")
		(net "PCIE_RX1_N")
	)
	(via
		(at 131.1716 153.4786)
		(size 0.4064)
		(drill 0.2032)
		(layers "F.Cu" "B.Cu")
		(tenting
			(front yes)
			(back yes)
		)
		(net "PCIE_RX1_N")
	)
	(via
		(at 163.04668 143.03687)
		(size 0.4064)
		(drill 0.2032)
		(layers "F.Cu" "B.Cu")
		(tenting
			(front yes)
			(back yes)
		)
		(net "PCIE_RX1_N")
	)
	(arc
		(start 131.371599 154.478601)
		(mid 131.223578 154.257072)
		(end 131.1716 153.99576)
		(width 0.127)
		(layer "F.Cu")
		(net "PCIE_RX1_N")
	)
	(arc
		(start 163.55641 141.87196)
		(mid 163.527892 142.015329)
		(end 163.44668 142.13687)
		(width 0.127)
		(layer "F.Cu")
		(net "PCIE_RX1_N")
	)
	(arc
		(start 163.04667 143.03687)
		(mid 163.138493 142.575082)
		(end 163.399991 142.183548)
		(width 0.127)
		(layer "F.Cu")
		(net "PCIE_RX1_N")
	)
	(arc
		(start 131.371605 154.478595)
		(mid 131.48261 154.644726)
		(end 131.52159 154.84069)
		(width 0.127)
		(layer "F.Cu")
		(net "PCIE_RX1_N")
	)
	(arc
		(start 131.541583 157.757597)
		(mid 131.316751 157.421112)
		(end 131.2378 157.0242)
		(width 0.127)
		(layer "F.Cu")
		(net "PCIE_RX1_N")
	)
	(segment
		(start 130.65956 150.29604)
		(end 130.65956 150.29604)
		(width 0.127)
		(layer "In3.Cu")
		(net "PCIE_RX1_N")
	)
	(segment
		(start 130.65916 152.20166)
		(end 130.65916 151.97896)
		(width 0.127)
		(layer "In3.Cu")
		(net "PCIE_RX1_N")
	)
	(segment
		(start 130.60497 152.43151)
		(end 130.60586 152.42798)
		(width 0.127)
		(layer "In3.Cu")
		(net "PCIE_RX1_N")
	)
	(segment
		(start 132.86119 145.92257)
		(end 135.52118 143.26258)
		(width 0.127)
		(layer "In3.Cu")
		(net "PCIE_RX1_N")
	)
	(segment
		(start 161.96477 144.3368)
		(end 162.33289 144.3368)
		(width 0.127)
		(layer "In3.Cu")
		(net "PCIE_RX1_N")
	)
	(segment
		(start 130.8284 153.58878)
		(end 130.8289 153.58675)
		(width 0.127)
		(layer "In3.Cu")
		(net "PCIE_RX1_N")
	)
	(segment
		(start 132.7819 146.1162)
		(end 132.7819 146.11398)
		(width 0.127)
		(layer "In3.Cu")
		(net "PCIE_RX1_N")
	)
	(segment
		(start 131.56936 148.38084)
		(end 132.03795 147.91225)
		(width 0.127)
		(layer "In3.Cu")
		(net "PCIE_RX1_N")
	)
	(segment
		(start 130.60492 152.43171)
		(end 130.60497 152.43151)
		(width 0.127)
		(layer "In3.Cu")
		(net "PCIE_RX1_N")
	)
	(segment
		(start 163.2216 143.8162)
		(end 163.22181 143.81599)
		(width 0.127)
		(layer "In3.Cu")
		(net "PCIE_RX1_N")
	)
	(segment
		(start 163.2216 143.8162)
		(end 163.22181 143.81599)
		(width 0.127)
		(layer "In3.Cu")
		(net "PCIE_RX1_N")
	)
	(segment
		(start 163.25697 143.73081)
		(end 163.25697 143.39967)
		(width 0.127)
		(layer "In3.Cu")
		(net "PCIE_RX1_N")
	)
	(segment
		(start 130.60586 152.42798)
		(end 130.65537 152.23245)
		(width 0.127)
		(layer "In3.Cu")
		(net "PCIE_RX1_N")
	)
	(segment
		(start 163.04668 143.04067)
		(end 163.15183 143.14582)
		(width 0.127)
		(layer "In3.Cu")
		(net "PCIE_RX1_N")
	)
	(segment
		(start 130.65916 151.97896)
		(end 130.65916 150.30604)
		(width 0.127)
		(layer "In3.Cu")
		(net "PCIE_RX1_N")
	)
	(segment
		(start 159.31917 142.71863)
		(end 160.21083 143.6103)
		(width 0.127)
		(layer "In3.Cu")
		(net "PCIE_RX1_N")
	)
	(segment
		(start 137.51479 142.4368)
		(end 158.63876 142.4368)
		(width 0.127)
		(layer "In3.Cu")
		(net "PCIE_RX1_N")
	)
	(segment
		(start 131.12766 148.96642)
		(end 131.12766 148.96642)
		(width 0.127)
		(layer "In3.Cu")
		(net "PCIE_RX1_N")
	)
	(segment
		(start 130.33325 153.01027)
		(end 130.33325 153.01027)
		(width 0.127)
		(layer "In3.Cu")
		(net "PCIE_RX1_N")
	)
	(segment
		(start 130.50713 152.81799)
		(end 130.60492 152.43171)
		(width 0.127)
		(layer "In3.Cu")
		(net "PCIE_RX1_N")
	)
	(segment
		(start 130.91324 153.49702)
		(end 130.91324 153.49702)
		(width 0.127)
		(layer "In3.Cu")
		(net "PCIE_RX1_N")
	)
	(segment
		(start 163.2216 143.8162)
		(end 163.2216 143.8162)
		(width 0.127)
		(layer "In3.Cu")
		(net "PCIE_RX1_N")
	)
	(segment
		(start 162.9613 144.0765)
		(end 163.2216 143.8162)
		(width 0.127)
		(layer "In3.Cu")
		(net "PCIE_RX1_N")
	)
	(segment
		(start 131.02946 153.4786)
		(end 131.1716 153.4786)
		(width 0.127)
		(layer "In3.Cu")
		(net "PCIE_RX1_N")
	)
	(segment
		(start 163.04668 143.04067)
		(end 163.04668 143.03687)
		(width 0.127)
		(layer "In3.Cu")
		(net "PCIE_RX1_N")
	)
	(arc
		(start 130.828399 153.588785)
		(mid 130.014607 153.784152)
		(end 130.333243 153.010268)
		(width 0.127)
		(layer "In3.Cu")
		(net "PCIE_RX1_N")
	)
	(arc
		(start 131.127667 148.96641)
		(mid 131.328108 148.658233)
		(end 131.569358 148.380838)
		(width 0.127)
		(layer "In3.Cu")
		(net "PCIE_RX1_N")
	)
	(arc
		(start 130.433076 152.946823)
		(mid 130.390997 152.990877)
		(end 130.333243 153.010266)
		(width 0.127)
		(layer "In3.Cu")
		(net "PCIE_RX1_N")
	)
	(arc
		(start 163.25698 143.73081)
		(mid 163.247843 143.776891)
		(end 163.221815 143.815999)
		(width 0.127)
		(layer "In3.Cu")
		(net "PCIE_RX1_N")
	)
	(arc
		(start 158.63876 142.4368)
		(mid 159.006993 142.510046)
		(end 159.319166 142.718634)
		(width 0.127)
		(layer "In3.Cu")
		(net "PCIE_RX1_N")
	)
	(arc
		(start 162.960879 144.076926)
		(mid 162.672708 144.269265)
		(end 162.33289 144.3368)
		(width 0.127)
		(layer "In3.Cu")
		(net "PCIE_RX1_N")
	)
	(arc
		(start 130.43308 152.946824)
		(mid 130.459594 152.902833)
		(end 130.488031 152.86006)
		(width 0.127)
		(layer "In3.Cu")
		(net "PCIE_RX1_N")
	)
	(arc
		(start 132.7819 146.11398)
		(mid 132.802506 146.010388)
		(end 132.861186 145.922566)
		(width 0.127)
		(layer "In3.Cu")
		(net "PCIE_RX1_N")
	)
	(arc
		(start 130.65916 150.306039)
		(mid 130.659259 150.301034)
		(end 130.659555 150.296037)
		(width 0.127)
		(layer "In3.Cu")
		(net "PCIE_RX1_N")
	)
	(arc
		(start 130.828894 153.586754)
		(mid 130.85946 153.530982)
		(end 130.913233 153.497022)
		(width 0.127)
		(layer "In3.Cu")
		(net "PCIE_RX1_N")
	)
	(arc
		(start 163.221814 143.816)
		(mid 163.22171 143.816104)
		(end 163.221607 143.816208)
		(width 0.127)
		(layer "In3.Cu")
		(net "PCIE_RX1_N")
	)
	(arc
		(start 161.96122 144.336797)
		(mid 161.013907 144.147307)
		(end 160.210834 143.610295)
		(width 0.127)
		(layer "In3.Cu")
		(net "PCIE_RX1_N")
	)
	(arc
		(start 130.65956 150.29604)
		(mid 130.806811 149.600674)
		(end 131.127657 148.966423)
		(width 0.127)
		(layer "In3.Cu")
		(net "PCIE_RX1_N")
	)
	(arc
		(start 130.913239 153.497017)
		(mid 130.970624 153.483233)
		(end 131.02946 153.4786)
		(width 0.127)
		(layer "In3.Cu")
		(net "PCIE_RX1_N")
	)
	(arc
		(start 130.659158 152.202406)
		(mid 130.658164 152.217539)
		(end 130.655373 152.232445)
		(width 0.127)
		(layer "In3.Cu")
		(net "PCIE_RX1_N")
	)
	(arc
		(start 163.151831 143.145819)
		(mid 163.229652 143.262287)
		(end 163.25698 143.39967)
		(width 0.127)
		(layer "In3.Cu")
		(net "PCIE_RX1_N")
	)
	(arc
		(start 132.7819 146.1162)
		(mid 132.588554 147.088216)
		(end 132.037951 147.912251)
		(width 0.127)
		(layer "In3.Cu")
		(net "PCIE_RX1_N")
	)
	(arc
		(start 130.65916 152.20166)
		(mid 130.659159 152.202033)
		(end 130.659158 152.202406)
		(width 0.127)
		(layer "In3.Cu")
		(net "PCIE_RX1_N")
	)
	(arc
		(start 130.507127 152.817986)
		(mid 130.49951 152.839899)
		(end 130.488035 152.860061)
		(width 0.127)
		(layer "In3.Cu")
		(net "PCIE_RX1_N")
	)
	(arc
		(start 135.521173 143.262583)
		(mid 136.435852 142.651414)
		(end 137.51479 142.4368)
		(width 0.127)
		(layer "In3.Cu")
		(net "PCIE_RX1_N")
	)
	(segment
		(start 163.74668 143.03687)
		(end 163.74668 142.61972)
		(width 0.127)
		(layer "F.Cu")
		(net "PCIE_RX1_P")
	)
	(segment
		(start 164.05653 141.87165)
		(end 164.05653 140.9135)
		(width 0.127)
		(layer "F.Cu")
		(net "PCIE_RX1_P")
	)
	(segment
		(start 130.52159 157.0786)
		(end 130.52159 153.84069)
		(width 0.127)
		(layer "F.Cu")
		(net "PCIE_RX1_P")
	)
	(via
		(at 163.74668 143.03687)
		(size 0.4064)
		(drill 0.2032)
		(layers "F.Cu" "B.Cu")
		(tenting
			(front yes)
			(back yes)
		)
		(net "PCIE_RX1_P")
	)
	(via
		(at 130.3716 153.4786)
		(size 0.4064)
		(drill 0.2032)
		(layers "F.Cu" "B.Cu")
		(tenting
			(front yes)
			(back yes)
		)
		(net "PCIE_RX1_P")
	)
	(arc
		(start 164.05654 141.87165)
		(mid 164.027989 142.015187)
		(end 163.946682 142.136872)
		(width 0.127)
		(layer "F.Cu")
		(net "PCIE_RX1_P")
	)
	(arc
		(start 130.541585 157.757595)
		(mid 130.361306 157.487788)
		(end 130.298001 157.16953)
		(width 0.127)
		(layer "F.Cu")
		(net "PCIE_RX1_P")
	)
	(arc
		(start 163.74668 142.61972)
		(mid 163.798658 142.358408)
		(end 163.946679 142.136879)
		(width 0.127)
		(layer "F.Cu")
		(net "PCIE_RX1_P")
	)
	(arc
		(start 130.371605 153.478595)
		(mid 130.48261 153.644726)
		(end 130.52159 153.84069)
		(width 0.127)
		(layer "F.Cu")
		(net "PCIE_RX1_P")
	)
	(segment
		(start 131.10366 150.82433)
		(end 131.37741 150.82433)
		(width 0.127)
		(layer "In3.Cu")
		(net "PCIE_RX1_P")
	)
	(segment
		(start 130.97158 152.01837)
		(end 130.97158 151.77683)
		(width 0.127)
		(layer "In3.Cu")
		(net "PCIE_RX1_P")
	)
	(segment
		(start 137.51479 142.7162)
		(end 158.63876 142.7162)
		(width 0.127)
		(layer "In3.Cu")
		(net "PCIE_RX1_P")
	)
	(segment
		(start 131.10366 151.20533)
		(end 131.49141 151.20533)
		(width 0.127)
		(layer "In3.Cu")
		(net "PCIE_RX1_P")
	)
	(segment
		(start 131.76917 148.57616)
		(end 132.2365 148.10884)
		(width 0.127)
		(layer "In3.Cu")
		(net "PCIE_RX1_P")
	)
	(segment
		(start 131.16208 151.58633)
		(end 131.49141 151.58633)
		(width 0.127)
		(layer "In3.Cu")
		(net "PCIE_RX1_P")
	)
	(segment
		(start 159.1216 142.91619)
		(end 160.0951 143.8897)
		(width 0.127)
		(layer "In3.Cu")
		(net "PCIE_RX1_P")
	)
	(segment
		(start 163.74668 143.04067)
		(end 163.74668 143.03687)
		(width 0.127)
		(layer "In3.Cu")
		(net "PCIE_RX1_P")
	)
	(segment
		(start 131.01125 150.22554)
		(end 131.08279 149.73146)
		(width 0.127)
		(layer "In3.Cu")
		(net "PCIE_RX1_P")
	)
	(segment
		(start 163.53637 143.7308)
		(end 163.53637 143.39968)
		(width 0.127)
		(layer "In3.Cu")
		(net "PCIE_RX1_P")
	)
	(segment
		(start 163.11795 144.31498)
		(end 163.41917 144.01377)
		(width 0.127)
		(layer "In3.Cu")
		(net "PCIE_RX1_P")
	)
	(segment
		(start 130.68292 153.0786)
		(end 130.68293 153.07859)
		(width 0.127)
		(layer "In3.Cu")
		(net "PCIE_RX1_P")
	)
	(segment
		(start 131.19978 150.44333)
		(end 131.37741 150.44333)
		(width 0.127)
		(layer "In3.Cu")
		(net "PCIE_RX1_P")
	)
	(segment
		(start 130.71924 153.0151)
		(end 130.97158 152.01838)
		(width 0.127)
		(layer "In3.Cu")
		(net "PCIE_RX1_P")
	)
	(segment
		(start 133.0613 146.11758)
		(end 135.71874 143.46015)
		(width 0.127)
		(layer "In3.Cu")
		(net "PCIE_RX1_P")
	)
	(segment
		(start 131.76917 148.57616)
		(end 131.76917 148.57616)
		(width 0.127)
		(layer "In3.Cu")
		(net "PCIE_RX1_P")
	)
	(segment
		(start 163.64153 143.14582)
		(end 163.74668 143.04067)
		(width 0.127)
		(layer "In3.Cu")
		(net "PCIE_RX1_P")
	)
	(segment
		(start 161.84904 144.6162)
		(end 162.39075 144.6162)
		(width 0.127)
		(layer "In3.Cu")
		(net "PCIE_RX1_P")
	)
	(segment
		(start 130.97158 152.01838)
		(end 130.97158 152.01837)
		(width 0.127)
		(layer "In3.Cu")
		(net "PCIE_RX1_P")
	)
	(arc
		(start 158.63876 142.7162)
		(mid 158.900068 142.768177)
		(end 159.121594 142.916196)
		(width 0.127)
		(layer "In3.Cu")
		(net "PCIE_RX1_P")
	)
	(arc
		(start 131.19978 150.44333)
		(mid 131.055749 150.37751)
		(end 131.011246 150.225534)
		(width 0.127)
		(layer "In3.Cu")
		(net "PCIE_RX1_P")
	)
	(arc
		(start 131.102361 149.667959)
		(mid 131.370737 149.082344)
		(end 131.769167 148.576159)
		(width 0.127)
		(layer "In3.Cu")
		(net "PCIE_RX1_P")
	)
	(arc
		(start 130.719236 153.015098)
		(mid 130.701363 153.047009)
		(end 130.682923 153.078596)
		(width 0.127)
		(layer "In3.Cu")
		(net "PCIE_RX1_P")
	)
	(arc
		(start 163.117957 144.314993)
		(mid 162.784311 144.537926)
		(end 162.39075 144.61621)
		(width 0.127)
		(layer "In3.Cu")
		(net "PCIE_RX1_P")
	)
	(arc
		(start 131.49141 151.20533)
		(mid 131.68191 151.39583)
		(end 131.49141 151.58633)
		(width 0.127)
		(layer "In3.Cu")
		(net "PCIE_RX1_P")
	)
	(arc
		(start 131.37741 150.44333)
		(mid 131.56791 150.63383)
		(end 131.37741 150.82433)
		(width 0.127)
		(layer "In3.Cu")
		(net "PCIE_RX1_P")
	)
	(arc
		(start 163.53637 143.7308)
		(mid 163.505909 143.883938)
		(end 163.419163 144.013763)
		(width 0.127)
		(layer "In3.Cu")
		(net "PCIE_RX1_P")
	)
	(arc
		(start 131.082793 149.731452)
		(mid 131.092383 149.699646)
		(end 131.102361 149.667959)
		(width 0.127)
		(layer "In3.Cu")
		(net "PCIE_RX1_P")
	)
	(arc
		(start 131.10366 151.20533)
		(mid 130.91316 151.01483)
		(end 131.10366 150.82433)
		(width 0.127)
		(layer "In3.Cu")
		(net "PCIE_RX1_P")
	)
	(arc
		(start 130.97158 151.776827)
		(mid 131.027377 151.642125)
		(end 131.16208 151.58633)
		(width 0.127)
		(layer "In3.Cu")
		(net "PCIE_RX1_P")
	)
	(arc
		(start 130.682922 153.078598)
		(mid 130.53968 153.288265)
		(end 130.3716 153.478599)
		(width 0.127)
		(layer "In3.Cu")
		(net "PCIE_RX1_P")
	)
	(arc
		(start 163.53637 143.39968)
		(mid 163.563698 143.262293)
		(end 163.641522 143.145822)
		(width 0.127)
		(layer "In3.Cu")
		(net "PCIE_RX1_P")
	)
	(arc
		(start 161.84549 144.616197)
		(mid 160.898181 144.426708)
		(end 160.095111 143.889698)
		(width 0.127)
		(layer "In3.Cu")
		(net "PCIE_RX1_P")
	)
	(arc
		(start 135.718739 143.460148)
		(mid 136.542774 142.909545)
		(end 137.51479 142.7162)
		(width 0.127)
		(layer "In3.Cu")
		(net "PCIE_RX1_P")
	)
	(arc
		(start 133.0613 146.117583)
		(mid 132.84694 147.195241)
		(end 132.236495 148.108835)
		(width 0.127)
		(layer "In3.Cu")
		(net "PCIE_RX1_P")
	)
	(segment
		(start 161.9216 139.0162)
		(end 161.9216 138.94059)
		(width 0.127)
		(layer "F.Cu")
		(net "PCIE_RX0_N")
	)
	(segment
		(start 162.05654 138.80565)
		(end 162.05654 136.86372)
		(width 0.127)
		(layer "F.Cu")
		(net "PCIE_RX0_N")
	)
	(segment
		(start 161.9216 138.94059)
		(end 162.05654 138.80565)
		(width 0.127)
		(layer "F.Cu")
		(net "PCIE_RX0_N")
	)
	(segment
		(start 126.52159 157.0786)
		(end 126.52159 154.56501)
		(width 0.127)
		(layer "F.Cu")
		(net "PCIE_RX0_N")
	)
	(via
		(at 161.9216 139.0162)
		(size 0.4064)
		(drill 0.2032)
		(layers "F.Cu" "B.Cu")
		(tenting
			(front yes)
			(back yes)
		)
		(net "PCIE_RX0_N")
	)
	(via
		(at 126.9716 153.4786)
		(size 0.4064)
		(drill 0.2032)
		(layers "F.Cu" "B.Cu")
		(tenting
			(front yes)
			(back yes)
		)
		(net "PCIE_RX0_N")
	)
	(arc
		(start 126.541594 157.757596)
		(mid 126.370337 157.501292)
		(end 126.310199 157.19896)
		(width 0.127)
		(layer "F.Cu")
		(net "PCIE_RX0_N")
	)
	(arc
		(start 126.52159 154.56501)
		(mid 126.638543 153.977048)
		(end 126.971597 153.478597)
		(width 0.127)
		(layer "F.Cu")
		(net "PCIE_RX0_N")
	)
	(segment
		(start 148.67948 138.26258)
		(end 150.57654 140.15964)
		(width 0.127)
		(layer "In3.Cu")
		(net "PCIE_RX0_N")
	)
	(segment
		(start 128.76355 151.41725)
		(end 128.76355 151.41724)
		(width 0.127)
		(layer "In3.Cu")
		(net "PCIE_RX0_N")
	)
	(segment
		(start 129.4216 150.75336)
		(end 129.4216 143.9921)
		(width 0.127)
		(layer "In3.Cu")
		(net "PCIE_RX0_N")
	)
	(segment
		(start 128.16204 151.89337)
		(end 128.22473 151.95605)
		(width 0.127)
		(layer "In3.Cu")
		(net "PCIE_RX0_N")
	)
	(segment
		(start 128.76352 151.41722)
		(end 128.76355 151.41724)
		(width 0.127)
		(layer "In3.Cu")
		(net "PCIE_RX0_N")
	)
	(segment
		(start 127.95532 152.22546)
		(end 127.9554 152.22554)
		(width 0.127)
		(layer "In3.Cu")
		(net "PCIE_RX0_N")
	)
	(segment
		(start 126.9716 153.4786)
		(end 127.41651 153.03369)
		(width 0.127)
		(layer "In3.Cu")
		(net "PCIE_RX0_N")
	)
	(segment
		(start 135.46076 137.4368)
		(end 146.68586 137.4368)
		(width 0.127)
		(layer "In3.Cu")
		(net "PCIE_RX0_N")
	)
	(segment
		(start 162.11181 139.69111)
		(end 162.11181 139.33592)
		(width 0.127)
		(layer "In3.Cu")
		(net "PCIE_RX0_N")
	)
	(segment
		(start 127.60214 152.4111)
		(end 127.60222 152.41117)
		(width 0.127)
		(layer "In3.Cu")
		(net "PCIE_RX0_N")
	)
	(segment
		(start 161.97506 139.14527)
		(end 162.07368 139.24389)
		(width 0.127)
		(layer "In3.Cu")
		(net "PCIE_RX0_N")
	)
	(segment
		(start 127.41651 152.76428)
		(end 127.41659 152.76436)
		(width 0.127)
		(layer "In3.Cu")
		(net "PCIE_RX0_N")
	)
	(segment
		(start 162.07368 139.24389)
		(end 162.07386 139.24407)
		(width 0.127)
		(layer "In3.Cu")
		(net "PCIE_RX0_N")
	)
	(segment
		(start 152.37259 140.90359)
		(end 160.92159 140.90359)
		(width 0.127)
		(layer "In3.Cu")
		(net "PCIE_RX0_N")
	)
	(segment
		(start 130.24738 141.99848)
		(end 134.34824 137.89762)
		(width 0.127)
		(layer "In3.Cu")
		(net "PCIE_RX0_N")
	)
	(segment
		(start 127.33281 152.68058)
		(end 127.41651 152.76428)
		(width 0.127)
		(layer "In3.Cu")
		(net "PCIE_RX0_N")
	)
	(segment
		(start 127.60222 152.41117)
		(end 127.68591 152.49487)
		(width 0.127)
		(layer "In3.Cu")
		(net "PCIE_RX0_N")
	)
	(segment
		(start 128.16196 151.89329)
		(end 128.16204 151.89337)
		(width 0.127)
		(layer "In3.Cu")
		(net "PCIE_RX0_N")
	)
	(segment
		(start 127.41651 153.03369)
		(end 127.41659 153.03361)
		(width 0.127)
		(layer "In3.Cu")
		(net "PCIE_RX0_N")
	)
	(segment
		(start 128.49412 151.68663)
		(end 128.49414 151.68665)
		(width 0.127)
		(layer "In3.Cu")
		(net "PCIE_RX0_N")
	)
	(segment
		(start 129.03288 151.41732)
		(end 129.03296 151.41724)
		(width 0.127)
		(layer "In3.Cu")
		(net "PCIE_RX0_N")
	)
	(segment
		(start 127.89263 152.16277)
		(end 127.95532 152.22546)
		(width 0.127)
		(layer "In3.Cu")
		(net "PCIE_RX0_N")
	)
	(segment
		(start 129.03296 151.41724)
		(end 129.22697 151.22323)
		(width 0.127)
		(layer "In3.Cu")
		(net "PCIE_RX0_N")
	)
	(arc
		(start 127.9554 152.225543)
		(mid 128.01112 152.360224)
		(end 127.955324 152.494873)
		(width 0.127)
		(layer "In3.Cu")
		(net "PCIE_RX0_N")
	)
	(arc
		(start 162.1118 139.69111)
		(mid 162.018307 140.161129)
		(end 161.752063 140.559593)
		(width 0.127)
		(layer "In3.Cu")
		(net "PCIE_RX0_N")
	)
	(arc
		(start 134.348234 137.897614)
		(mid 134.858665 137.556555)
		(end 135.46076 137.436791)
		(width 0.127)
		(layer "In3.Cu")
		(net "PCIE_RX0_N")
	)
	(arc
		(start 146.68586 137.4368)
		(mid 147.764798 137.651414)
		(end 148.679477 138.262583)
		(width 0.127)
		(layer "In3.Cu")
		(net "PCIE_RX0_N")
	)
	(arc
		(start 127.892636 152.162774)
		(mid 127.83684 152.028072)
		(end 127.892633 151.893369)
		(width 0.127)
		(layer "In3.Cu")
		(net "PCIE_RX0_N")
	)
	(arc
		(start 162.073687 139.243883)
		(mid 162.073774 139.243971)
		(end 162.073862 139.244058)
		(width 0.127)
		(layer "In3.Cu")
		(net "PCIE_RX0_N")
	)
	(arc
		(start 161.975052 139.145268)
		(mid 161.935485 139.086051)
		(end 161.92159 139.0162)
		(width 0.127)
		(layer "In3.Cu")
		(net "PCIE_RX0_N")
	)
	(arc
		(start 127.955321 152.494866)
		(mid 127.820619 152.55066)
		(end 127.685917 152.494864)
		(width 0.127)
		(layer "In3.Cu")
		(net "PCIE_RX0_N")
	)
	(arc
		(start 129.4216 143.9921)
		(mid 129.636214 142.913162)
		(end 130.247383 141.998483)
		(width 0.127)
		(layer "In3.Cu")
		(net "PCIE_RX0_N")
	)
	(arc
		(start 129.4216 150.75336)
		(mid 129.371019 151.007649)
		(end 129.226975 151.223225)
		(width 0.127)
		(layer "In3.Cu")
		(net "PCIE_RX0_N")
	)
	(arc
		(start 152.37259 140.90359)
		(mid 151.400573 140.710244)
		(end 150.576538 140.15964)
		(width 0.127)
		(layer "In3.Cu")
		(net "PCIE_RX0_N")
	)
	(arc
		(start 161.752066 140.559596)
		(mid 161.37104 140.814189)
		(end 160.92159 140.90359)
		(width 0.127)
		(layer "In3.Cu")
		(net "PCIE_RX0_N")
	)
	(arc
		(start 127.332816 152.680584)
		(mid 127.27702 152.545882)
		(end 127.332813 152.411179)
		(width 0.127)
		(layer "In3.Cu")
		(net "PCIE_RX0_N")
	)
	(arc
		(start 162.073862 139.244058)
		(mid 162.10195 139.286224)
		(end 162.11181 139.33592)
		(width 0.127)
		(layer "In3.Cu")
		(net "PCIE_RX0_N")
	)
	(arc
		(start 127.41659 152.764363)
		(mid 127.47231 152.89899)
		(end 127.41659 153.033617)
		(width 0.127)
		(layer "In3.Cu")
		(net "PCIE_RX0_N")
	)
	(arc
		(start 127.892636 151.893366)
		(mid 128.027286 151.83757)
		(end 128.161967 151.893289)
		(width 0.127)
		(layer "In3.Cu")
		(net "PCIE_RX0_N")
	)
	(arc
		(start 129.032877 151.41732)
		(mid 128.898196 151.47304)
		(end 128.763547 151.417244)
		(width 0.127)
		(layer "In3.Cu")
		(net "PCIE_RX0_N")
	)
	(arc
		(start 128.494116 151.417216)
		(mid 128.62882 151.36142)
		(end 128.763524 151.417216)
		(width 0.127)
		(layer "In3.Cu")
		(net "PCIE_RX0_N")
	)
	(arc
		(start 128.494134 151.686646)
		(mid 128.54993 151.82135)
		(end 128.494134 151.956054)
		(width 0.127)
		(layer "In3.Cu")
		(net "PCIE_RX0_N")
	)
	(arc
		(start 128.494116 151.686624)
		(mid 128.43832 151.551922)
		(end 128.494113 151.417219)
		(width 0.127)
		(layer "In3.Cu")
		(net "PCIE_RX0_N")
	)
	(arc
		(start 128.494131 151.956056)
		(mid 128.359429 152.01185)
		(end 128.224727 151.956054)
		(width 0.127)
		(layer "In3.Cu")
		(net "PCIE_RX0_N")
	)
	(arc
		(start 127.332806 152.411176)
		(mid 127.467456 152.35538)
		(end 127.602137 152.411099)
		(width 0.127)
		(layer "In3.Cu")
		(net "PCIE_RX0_N")
	)
	(segment
		(start 162.6216 139.0162)
		(end 162.6216 138.94703)
		(width 0.127)
		(layer "F.Cu")
		(net "PCIE_RX0_P")
	)
	(segment
		(start 162.48496 137.6609)
		(end 162.48496 136.94481)
		(width 0.127)
		(layer "F.Cu")
		(net "PCIE_RX0_P")
	)
	(segment
		(start 162.48496 136.94481)
		(end 162.54643 136.88334)
		(width 0.127)
		(layer "F.Cu")
		(net "PCIE_RX0_P")
	)
	(segment
		(start 162.47667 138.8021)
		(end 162.6216 138.94703)
		(width 0.127)
		(layer "F.Cu")
		(net "PCIE_RX0_P")
	)
	(segment
		(start 162.47667 138.8021)
		(end 162.47667 137.66919)
		(width 0.127)
		(layer "F.Cu")
		(net "PCIE_RX0_P")
	)
	(segment
		(start 125.5216 157.0786)
		(end 125.5216 155.04785)
		(width 0.127)
		(layer "F.Cu")
		(net "PCIE_RX0_P")
	)
	(segment
		(start 162.47667 137.66919)
		(end 162.48496 137.6609)
		(width 0.127)
		(layer "F.Cu")
		(net "PCIE_RX0_P")
	)
	(via
		(at 126.1716 153.4786)
		(size 0.4064)
		(drill 0.2032)
		(layers "F.Cu" "B.Cu")
		(tenting
			(front yes)
			(back yes)
		)
		(net "PCIE_RX0_P")
	)
	(via
		(at 162.6216 139.0162)
		(size 0.4064)
		(drill 0.2032)
		(layers "F.Cu" "B.Cu")
		(tenting
			(front yes)
			(back yes)
		)
		(net "PCIE_RX0_P")
	)
	(arc
		(start 125.5216 155.04785)
		(mid 125.69053 154.19858)
		(end 126.171603 153.478603)
		(width 0.127)
		(layer "F.Cu")
		(net "PCIE_RX0_P")
	)
	(segment
		(start 151.59334 141.18299)
		(end 160.92159 141.18299)
		(width 0.127)
		(layer "In3.Cu")
		(net "PCIE_RX0_P")
	)
	(segment
		(start 126.1716 153.4786)
		(end 126.38756 153.4786)
		(width 0.127)
		(layer "In3.Cu")
		(net "PCIE_RX0_P")
	)
	(segment
		(start 135.20312 137.7162)
		(end 135.20314 137.7162)
		(width 0.127)
		(layer "In3.Cu")
		(net "PCIE_RX0_P")
	)
	(segment
		(start 148.48192 138.46015)
		(end 150.92999 140.90822)
		(width 0.127)
		(layer "In3.Cu")
		(net "PCIE_RX0_P")
	)
	(segment
		(start 135.20314 137.7162)
		(end 146.68586 137.7162)
		(width 0.127)
		(layer "In3.Cu")
		(net "PCIE_RX0_P")
	)
	(segment
		(start 130.44495 142.19605)
		(end 134.72799 137.913)
		(width 0.127)
		(layer "In3.Cu")
		(net "PCIE_RX0_P")
	)
	(segment
		(start 126.38756 153.4786)
		(end 126.38756 153.4786)
		(width 0.127)
		(layer "In3.Cu")
		(net "PCIE_RX0_P")
	)
	(segment
		(start 129.701 150.79284)
		(end 129.701 143.9921)
		(width 0.127)
		(layer "In3.Cu")
		(net "PCIE_RX0_P")
	)
	(segment
		(start 135.20312 137.7162)
		(end 135.20314 137.7162)
		(width 0.127)
		(layer "In3.Cu")
		(net "PCIE_RX0_P")
	)
	(segment
		(start 162.39121 139.3222)
		(end 162.56839 139.14501)
		(width 0.127)
		(layer "In3.Cu")
		(net "PCIE_RX0_P")
	)
	(segment
		(start 127.4689 153.3533)
		(end 129.41298 151.40923)
		(width 0.127)
		(layer "In3.Cu")
		(net "PCIE_RX0_P")
	)
	(segment
		(start 162.3658 139.79632)
		(end 162.36581 139.65074)
		(width 0.127)
		(layer "In3.Cu")
		(net "PCIE_RX0_P")
	)
	(arc
		(start 161.47903 141.044747)
		(mid 161.475168 141.046779)
		(end 161.471299 141.048797)
		(width 0.127)
		(layer "In3.Cu")
		(net "PCIE_RX0_P")
	)
	(arc
		(start 146.68586 137.7162)
		(mid 147.657876 137.909546)
		(end 148.481911 138.460149)
		(width 0.127)
		(layer "In3.Cu")
		(net "PCIE_RX0_P")
	)
	(arc
		(start 129.701 143.9921)
		(mid 129.894346 143.020084)
		(end 130.444949 142.196049)
		(width 0.127)
		(layer "In3.Cu")
		(net "PCIE_RX0_P")
	)
	(arc
		(start 161.930007 140.740862)
		(mid 161.722737 140.911782)
		(end 161.487131 141.040871)
		(width 0.127)
		(layer "In3.Cu")
		(net "PCIE_RX0_P")
	)
	(arc
		(start 129.452465 151.392875)
		(mid 129.434349 151.40498)
		(end 129.41298 151.40923)
		(width 0.127)
		(layer "In3.Cu")
		(net "PCIE_RX0_P")
	)
	(arc
		(start 162.39121 139.3222)
		(mid 162.38485 139.486959)
		(end 162.36581 139.650737)
		(width 0.127)
		(layer "In3.Cu")
		(net "PCIE_RX0_P")
	)
	(arc
		(start 127.468904 153.353305)
		(mid 127.437459 153.600505)
		(end 127.303876 153.810868)
		(width 0.127)
		(layer "In3.Cu")
		(net "PCIE_RX0_P")
	)
	(arc
		(start 162.6216 139.0162)
		(mid 162.607774 139.085886)
		(end 162.568391 139.145015)
		(width 0.127)
		(layer "In3.Cu")
		(net "PCIE_RX0_P")
	)
	(arc
		(start 134.727985 137.912996)
		(mid 134.95587 137.791218)
		(end 135.203119 137.716191)
		(width 0.127)
		(layer "In3.Cu")
		(net "PCIE_RX0_P")
	)
	(arc
		(start 162.359801 139.824333)
		(mid 162.225571 140.320425)
		(end 161.930003 140.74086)
		(width 0.127)
		(layer "In3.Cu")
		(net "PCIE_RX0_P")
	)
	(arc
		(start 161.479029 141.044749)
		(mid 161.483046 141.042738)
		(end 161.487132 141.04087)
		(width 0.127)
		(layer "In3.Cu")
		(net "PCIE_RX0_P")
	)
	(arc
		(start 129.558131 151.264069)
		(mid 129.508464 151.331069)
		(end 129.452459 151.39287)
		(width 0.127)
		(layer "In3.Cu")
		(net "PCIE_RX0_P")
	)
	(arc
		(start 127.303868 153.810871)
		(mid 126.83926 153.929479)
		(end 126.51246 153.578581)
		(width 0.127)
		(layer "In3.Cu")
		(net "PCIE_RX0_P")
	)
	(arc
		(start 162.359807 139.824335)
		(mid 162.362013 139.810159)
		(end 162.365803 139.796322)
		(width 0.127)
		(layer "In3.Cu")
		(net "PCIE_RX0_P")
	)
	(arc
		(start 161.471299 141.048797)
		(mid 161.204517 141.148956)
		(end 160.921592 141.18299)
		(width 0.127)
		(layer "In3.Cu")
		(net "PCIE_RX0_P")
	)
	(arc
		(start 151.59334 141.18299)
		(mid 151.234339 141.11158)
		(end 150.929993 140.908221)
		(width 0.127)
		(layer "In3.Cu")
		(net "PCIE_RX0_P")
	)
	(arc
		(start 126.387567 153.478603)
		(mid 126.467735 153.506453)
		(end 126.512461 153.578578)
		(width 0.127)
		(layer "In3.Cu")
		(net "PCIE_RX0_P")
	)
	(arc
		(start 129.701 150.79284)
		(mid 129.664498 151.039045)
		(end 129.558131 151.264069)
		(width 0.127)
		(layer "In3.Cu")
		(net "PCIE_RX0_P")
	)
	(segment
		(start 182.06162 129.22303)
		(end 182.06162 129.22193)
		(width 0.2032)
		(layer "F.Cu")
		(net "LED1")
	)
	(segment
		(start 182.06162 129.22303)
		(end 184.0342 129.22303)
		(width 0.2032)
		(layer "F.Cu")
		(net "LED1")
	)
	(via
		(at 81.1216 51.2162)
		(size 0.4064)
		(drill 0.2032)
		(layers "F.Cu" "B.Cu")
		(net "LED1")
	)
	(via
		(at 182.06162 129.22193)
		(size 0.4064)
		(drill 0.2032)
		(layers "F.Cu" "B.Cu")
		(tenting
			(front yes)
			(back yes)
		)
		(net "LED1")
	)
	(segment
		(start 80.8716 50.9662)
		(end 81.1216 51.2162)
		(width 0.2032)
		(layer "B.Cu")
		(net "LED1")
	)
	(segment
		(start 80.0966 50.9662)
		(end 80.8716 50.9662)
		(width 0.2032)
		(layer "B.Cu")
		(net "LED1")
	)
	(segment
		(start 80.0966 50.9662)
		(end 80.1168 50.946)
		(width 0.2032)
		(layer "B.Cu")
		(net "LED1")
	)
	(segment
		(start 135.27414 97.2162)
		(end 140.4216 97.2162)
		(width 0.2032)
		(layer "In3.Cu")
		(net "LED1")
	)
	(segment
		(start 81.4216 71.9162)
		(end 81.8216 72.3162)
		(width 0.2032)
		(layer "In3.Cu")
		(net "LED1")
	)
	(segment
		(start 159.06108 101.75568)
		(end 160.42551 103.12011)
		(width 0.2032)
		(layer "In3.Cu")
		(net "LED1")
	)
	(segment
		(start 166.4216 127.1162)
		(end 178.30423 127.1162)
		(width 0.2032)
		(layer "In3.Cu")
		(net "LED1")
	)
	(segment
		(start 178.30423 127.1162)
		(end 180.40996 129.22193)
		(width 0.2032)
		(layer "In3.Cu")
		(net "LED1")
	)
	(segment
		(start 77.7216 52.44607)
		(end 78.95147 51.2162)
		(width 0.2032)
		(layer "In3.Cu")
		(net "LED1")
	)
	(segment
		(start 156.63115 99.8026)
		(end 156.86413 100.03559)
		(width 0.2032)
		(layer "In3.Cu")
		(net "LED1")
	)
	(segment
		(start 140.4216 97.2162)
		(end 143.008 99.8026)
		(width 0.2032)
		(layer "In3.Cu")
		(net "LED1")
	)
	(segment
		(start 77.7216 68.48317)
		(end 77.7216 52.44607)
		(width 0.2032)
		(layer "In3.Cu")
		(net "LED1")
	)
	(segment
		(start 162.4898 123.1844)
		(end 166.4216 127.1162)
		(width 0.2032)
		(layer "In3.Cu")
		(net "LED1")
	)
	(segment
		(start 78.2216 91.95475)
		(end 78.2216 80.71341)
		(width 0.2032)
		(layer "In3.Cu")
		(net "LED1")
	)
	(segment
		(start 119.93794 93.19986)
		(end 131.25781 93.19986)
		(width 0.2032)
		(layer "In3.Cu")
		(net "LED1")
	)
	(segment
		(start 162.4898 123.1844)
		(end 162.4898 103.23914)
		(width 0.2032)
		(layer "In3.Cu")
		(net "LED1")
	)
	(segment
		(start 114.2216 98.9162)
		(end 119.93794 93.19986)
		(width 0.2032)
		(layer "In3.Cu")
		(net "LED1")
	)
	(segment
		(start 80.4216 71.9162)
		(end 81.4216 71.9162)
		(width 0.2032)
		(layer "In3.Cu")
		(net "LED1")
	)
	(segment
		(start 78.2216 91.95475)
		(end 85.18305 98.9162)
		(width 0.2032)
		(layer "In3.Cu")
		(net "LED1")
	)
	(segment
		(start 159.06108 101.75568)
		(end 159.06108 101.2662)
		(width 0.2032)
		(layer "In3.Cu")
		(net "LED1")
	)
	(segment
		(start 162.37077 103.12011)
		(end 162.4898 103.23914)
		(width 0.2032)
		(layer "In3.Cu")
		(net "LED1")
	)
	(segment
		(start 77.7216 68.48317)
		(end 79.29949 70.06106)
		(width 0.2032)
		(layer "In3.Cu")
		(net "LED1")
	)
	(segment
		(start 180.40996 129.22193)
		(end 182.06162 129.22193)
		(width 0.2032)
		(layer "In3.Cu")
		(net "LED1")
	)
	(segment
		(start 79.29949 70.79409)
		(end 79.29949 70.06106)
		(width 0.2032)
		(layer "In3.Cu")
		(net "LED1")
	)
	(segment
		(start 81.8216 77.11341)
		(end 81.8216 72.3162)
		(width 0.2032)
		(layer "In3.Cu")
		(net "LED1")
	)
	(segment
		(start 78.2216 80.71341)
		(end 81.8216 77.11341)
		(width 0.2032)
		(layer "In3.Cu")
		(net "LED1")
	)
	(segment
		(start 78.95147 51.2162)
		(end 81.1216 51.2162)
		(width 0.2032)
		(layer "In3.Cu")
		(net "LED1")
	)
	(segment
		(start 156.86413 100.03559)
		(end 158.92407 100.03559)
		(width 0.2032)
		(layer "In3.Cu")
		(net "LED1")
	)
	(segment
		(start 143.008 99.8026)
		(end 156.63115 99.8026)
		(width 0.2032)
		(layer "In3.Cu")
		(net "LED1")
	)
	(segment
		(start 159.3216 101.00568)
		(end 159.3216 100.43312)
		(width 0.2032)
		(layer "In3.Cu")
		(net "LED1")
	)
	(segment
		(start 160.42551 103.12011)
		(end 162.37077 103.12011)
		(width 0.2032)
		(layer "In3.Cu")
		(net "LED1")
	)
	(segment
		(start 85.18305 98.9162)
		(end 114.2216 98.9162)
		(width 0.2032)
		(layer "In3.Cu")
		(net "LED1")
	)
	(segment
		(start 79.29949 70.79409)
		(end 80.4216 71.9162)
		(width 0.2032)
		(layer "In3.Cu")
		(net "LED1")
	)
	(segment
		(start 158.92407 100.03559)
		(end 159.3216 100.43312)
		(width 0.2032)
		(layer "In3.Cu")
		(net "LED1")
	)
	(segment
		(start 159.06108 101.2662)
		(end 159.3216 101.00568)
		(width 0.2032)
		(layer "In3.Cu")
		(net "LED1")
	)
	(segment
		(start 131.25781 93.19986)
		(end 135.27414 97.2162)
		(width 0.2032)
		(layer "In3.Cu")
		(net "LED1")
	)
	(segment
		(start 182.03259 128.72316)
		(end 184.0342 128.72316)
		(width 0.2032)
		(layer "F.Cu")
		(net "LED2")
	)
	(segment
		(start 182.03259 128.72316)
		(end 182.03259 128.61302)
		(width 0.2032)
		(layer "F.Cu")
		(net "LED2")
	)
	(via
		(at 81.3216 53.0162)
		(size 0.4064)
		(drill 0.2032)
		(layers "F.Cu" "B.Cu")
		(net "LED2")
	)
	(via
		(at 182.03259 128.61302)
		(size 0.4064)
		(drill 0.2032)
		(layers "F.Cu" "B.Cu")
		(tenting
			(front yes)
			(back yes)
		)
		(net "LED2")
	)
	(segment
		(start 80.0966 52.7162)
		(end 81.0216 52.7162)
		(width 0.2032)
		(layer "B.Cu")
		(net "LED2")
	)
	(segment
		(start 81.0216 52.7162)
		(end 81.3216 53.0162)
		(width 0.2032)
		(layer "B.Cu")
		(net "LED2")
	)
	(segment
		(start 178.65119 126.6162)
		(end 180.64801 128.61302)
		(width 0.2032)
		(layer "In3.Cu")
		(net "LED2")
	)
	(segment
		(start 176.83639 126.6162)
		(end 178.65119 126.6162)
		(width 0.2032)
		(layer "In3.Cu")
		(net "LED2")
	)
	(segment
		(start 78.8216 91.52796)
		(end 85.80984 98.5162)
		(width 0.2032)
		(layer "In3.Cu")
		(net "LED2")
	)
	(segment
		(start 140.55837 96.886)
		(end 143.14477 99.4724)
		(width 0.2032)
		(layer "In3.Cu")
		(net "LED2")
	)
	(segment
		(start 114.0216 98.5162)
		(end 120.1216 92.4162)
		(width 0.2032)
		(layer "In3.Cu")
		(net "LED2")
	)
	(segment
		(start 163.3534 109.9844)
		(end 163.3534 109.148)
		(width 0.2032)
		(layer "In3.Cu")
		(net "LED2")
	)
	(segment
		(start 80.4966 55.70453)
		(end 80.4966 53.8412)
		(width 0.2032)
		(layer "In3.Cu")
		(net "LED2")
	)
	(segment
		(start 78.5216 67.5162)
		(end 79.1216 66.9162)
		(width 0.2032)
		(layer "In3.Cu")
		(net "LED2")
	)
	(segment
		(start 162.8253 123.05293)
		(end 166.48857 126.7162)
		(width 0.2032)
		(layer "In3.Cu")
		(net "LED2")
	)
	(segment
		(start 162.8253 123.05293)
		(end 162.8253 110.5125)
		(width 0.2032)
		(layer "In3.Cu")
		(net "LED2")
	)
	(segment
		(start 166.48857 126.7162)
		(end 173.61094 126.7162)
		(width 0.2032)
		(layer "In3.Cu")
		(net "LED2")
	)
	(segment
		(start 163.01363 108.80823)
		(end 163.3534 109.148)
		(width 0.2032)
		(layer "In3.Cu")
		(net "LED2")
	)
	(segment
		(start 156.81171 99.5162)
		(end 159.11425 99.5162)
		(width 0.2032)
		(layer "In3.Cu")
		(net "LED2")
	)
	(segment
		(start 79.1216 66.9162)
		(end 79.1216 65.9162)
		(width 0.2032)
		(layer "In3.Cu")
		(net "LED2")
	)
	(segment
		(start 135.4216 96.886)
		(end 140.55837 96.886)
		(width 0.2032)
		(layer "In3.Cu")
		(net "LED2")
	)
	(segment
		(start 80.9216 71.2162)
		(end 82.1216 71.2162)
		(width 0.2032)
		(layer "In3.Cu")
		(net "LED2")
	)
	(segment
		(start 156.76792 99.4724)
		(end 156.81171 99.5162)
		(width 0.2032)
		(layer "In3.Cu")
		(net "LED2")
	)
	(segment
		(start 81.7216 61.3162)
		(end 82.1216 60.9162)
		(width 0.2032)
		(layer "In3.Cu")
		(net "LED2")
	)
	(segment
		(start 173.61094 126.7162)
		(end 174.31094 126.0162)
		(width 0.2032)
		(layer "In3.Cu")
		(net "LED2")
	)
	(segment
		(start 159.11425 99.5162)
		(end 160.22807 100.63002)
		(width 0.2032)
		(layer "In3.Cu")
		(net "LED2")
	)
	(segment
		(start 85.80984 98.5162)
		(end 114.0216 98.5162)
		(width 0.2032)
		(layer "In3.Cu")
		(net "LED2")
	)
	(segment
		(start 78.8216 91.52796)
		(end 78.8216 81.34828)
		(width 0.2032)
		(layer "In3.Cu")
		(net "LED2")
	)
	(segment
		(start 80.4966 53.8412)
		(end 81.3216 53.0162)
		(width 0.2032)
		(layer "In3.Cu")
		(net "LED2")
	)
	(segment
		(start 79.1216 65.9162)
		(end 81.7216 63.3162)
		(width 0.2032)
		(layer "In3.Cu")
		(net "LED2")
	)
	(segment
		(start 160.82251 102.61711)
		(end 162.33474 102.61711)
		(width 0.2032)
		(layer "In3.Cu")
		(net "LED2")
	)
	(segment
		(start 143.14477 99.4724)
		(end 156.76792 99.4724)
		(width 0.2032)
		(layer "In3.Cu")
		(net "LED2")
	)
	(segment
		(start 160.22807 102.02267)
		(end 160.22807 100.63002)
		(width 0.2032)
		(layer "In3.Cu")
		(net "LED2")
	)
	(segment
		(start 82.1216 71.2162)
		(end 82.6216 71.7162)
		(width 0.2032)
		(layer "In3.Cu")
		(net "LED2")
	)
	(segment
		(start 180.64801 128.61302)
		(end 182.03259 128.61302)
		(width 0.2032)
		(layer "In3.Cu")
		(net "LED2")
	)
	(segment
		(start 130.9518 92.4162)
		(end 135.4216 96.886)
		(width 0.2032)
		(layer "In3.Cu")
		(net "LED2")
	)
	(segment
		(start 162.33474 102.61711)
		(end 162.82 103.10237)
		(width 0.2032)
		(layer "In3.Cu")
		(net "LED2")
	)
	(segment
		(start 78.5216 68.8162)
		(end 80.9216 71.2162)
		(width 0.2032)
		(layer "In3.Cu")
		(net "LED2")
	)
	(segment
		(start 162.82 103.16454)
		(end 162.82 103.10237)
		(width 0.2032)
		(layer "In3.Cu")
		(net "LED2")
	)
	(segment
		(start 174.31094 126.0162)
		(end 176.23639 126.0162)
		(width 0.2032)
		(layer "In3.Cu")
		(net "LED2")
	)
	(segment
		(start 162.82 103.16454)
		(end 163.01363 103.35817)
		(width 0.2032)
		(layer "In3.Cu")
		(net "LED2")
	)
	(segment
		(start 82.6216 77.54828)
		(end 82.6216 71.7162)
		(width 0.2032)
		(layer "In3.Cu")
		(net "LED2")
	)
	(segment
		(start 160.22807 102.02267)
		(end 160.82251 102.61711)
		(width 0.2032)
		(layer "In3.Cu")
		(net "LED2")
	)
	(segment
		(start 78.5216 68.8162)
		(end 78.5216 67.5162)
		(width 0.2032)
		(layer "In3.Cu")
		(net "LED2")
	)
	(segment
		(start 162.8253 110.5125)
		(end 163.3534 109.9844)
		(width 0.2032)
		(layer "In3.Cu")
		(net "LED2")
	)
	(segment
		(start 80.4966 55.70453)
		(end 82.1216 57.32953)
		(width 0.2032)
		(layer "In3.Cu")
		(net "LED2")
	)
	(segment
		(start 163.01363 108.80823)
		(end 163.01363 103.35817)
		(width 0.2032)
		(layer "In3.Cu")
		(net "LED2")
	)
	(segment
		(start 78.8216 81.34828)
		(end 82.6216 77.54828)
		(width 0.2032)
		(layer "In3.Cu")
		(net "LED2")
	)
	(segment
		(start 120.1216 92.4162)
		(end 130.9518 92.4162)
		(width 0.2032)
		(layer "In3.Cu")
		(net "LED2")
	)
	(segment
		(start 82.1216 60.9162)
		(end 82.1216 57.32953)
		(width 0.2032)
		(layer "In3.Cu")
		(net "LED2")
	)
	(segment
		(start 176.23639 126.0162)
		(end 176.83639 126.6162)
		(width 0.2032)
		(layer "In3.Cu")
		(net "LED2")
	)
	(segment
		(start 81.7216 63.3162)
		(end 81.7216 61.3162)
		(width 0.2032)
		(layer "In3.Cu")
		(net "LED2")
	)
	(segment
		(start 207.96803 130.59893)
		(end 207.96803 129.31977)
		(width 0.254)
		(layer "F.Cu")
		(net "GND")
	)
	(segment
		(start 74.75606 104.2162)
		(end 74.78883 104.24897)
		(width 0.2032)
		(layer "F.Cu")
		(net "GND")
	)
	(segment
		(start 206.47457 130.51076)
		(end 206.47754 130.51373)
		(width 0.254)
		(layer "F.Cu")
		(net "GND")
	)
	(segment
		(start 163.57227 100.61247)
		(end 163.57227 99.284)
		(width 0.2032)
		(layer "F.Cu")
		(net "GND")
	)
	(segment
		(start 228.58714 132.0162)
		(end 229.38529 132.0162)
		(width 0.254)
		(layer "F.Cu")
		(net "GND")
	)
	(segment
		(start 159.14668 135.20183)
		(end 159.14668 135.14685)
		(width 0.2032)
		(layer "F.Cu")
		(net "GND")
	)
	(segment
		(start 136.41149 120.22057)
		(end 136.43486 120.24394)
		(width 0.2032)
		(layer "F.Cu")
		(net "GND")
	)
	(segment
		(start 143.54156 157.7576)
		(end 143.5466 157.75256)
		(width 0.508)
		(layer "F.Cu")
		(net "GND")
	)
	(segment
		(start 89.85225 86.64271)
		(end 89.93125 86.56371)
		(width 0.254)
		(layer "F.Cu")
		(net "GND")
	)
	(segment
		(start 188.07713 114.73003)
		(end 188.08397 114.72319)
		(width 0.2032)
		(layer "F.Cu")
		(net "GND")
	)
	(segment
		(start 165.50561 115.2162)
		(end 166.2716 115.2162)
		(width 0.254)
		(layer "F.Cu")
		(net "GND")
	)
	(segment
		(start 130.69244 116.78704)
		(end 130.69244 116.71498)
		(width 0.254)
		(layer "F.Cu")
		(net "GND")
	)
	(segment
		(start 123.5416 154.3286)
		(end 124.2716 154.3286)
		(width 0.508)
		(layer "F.Cu")
		(net "GND")
	)
	(segment
		(start 216.9716 130.7412)
		(end 216.9716 129.3162)
		(width 0.254)
		(layer "F.Cu")
		(net "GND")
	)
	(segment
		(start 152.1216 129.7162)
		(end 152.8716 129.7162)
		(width 0.2032)
		(layer "F.Cu")
		(net "GND")
	)
	(segment
		(start 210.9216 130.6412)
		(end 210.9716 130.6412)
		(width 0.2032)
		(layer "F.Cu")
		(net "GND")
	)
	(segment
		(start 114.43493 84.8432)
		(end 114.58572 84.69241)
		(width 0.254)
		(layer "F.Cu")
		(net "GND")
	)
	(segment
		(start 109.4716 59.7286)
		(end 111.9216 59.7286)
		(width 0.762)
		(layer "F.Cu")
		(net "GND")
	)
	(segment
		(start 184.0342 114.72319)
		(end 184.04104 114.73003)
		(width 0.2032)
		(layer "F.Cu")
		(net "GND")
	)
	(segment
		(start 225.7216 124.9162)
		(end 225.7341 124.9287)
		(width 0.2032)
		(layer "F.Cu")
		(net "GND")
	)
	(segment
		(start 114.58572 83.5612)
		(end 114.88072 83.2662)
		(width 0.254)
		(layer "F.Cu")
		(net "GND")
	)
	(segment
		(start 114.9216 71.7662)
		(end 116.3466 71.7662)
		(width 0.254)
		(layer "F.Cu")
		(net "GND")
	)
	(segment
		(start 163.54358 82.0086)
		(end 164.0026 82.46763)
		(width 0.762)
		(layer "F.Cu")
		(net "GND")
	)
	(segment
		(start 229.08736 118.13811)
		(end 229.08736 117.76297)
		(width 0.254)
		(layer "F.Cu")
		(net "GND")
	)
	(segment
		(start 199.9716 130.79975)
		(end 199.9716 129.3162)
		(width 0.254)
		(layer "F.Cu")
		(net "GND")
	)
	(segment
		(start 225.7341 124.9287)
		(end 226.9341 124.9287)
		(width 0.2032)
		(layer "F.Cu")
		(net "GND")
	)
	(segment
		(start 156.64668 139.59186)
		(end 156.64668 139.53687)
		(width 0.2032)
		(layer "F.Cu")
		(net "GND")
	)
	(segment
		(start 164.54656 135.29198)
		(end 164.64668 135.19186)
		(width 0.2032)
		(layer "F.Cu")
		(net "GND")
	)
	(segment
		(start 168.53128 103.2928)
		(end 168.54889 103.31041)
		(width 0.2032)
		(layer "F.Cu")
		(net "GND")
	)
	(segment
		(start 136.41149 122.72069)
		(end 137.49124 122.72069)
		(width 0.2032)
		(layer "F.Cu")
		(net "GND")
	)
	(segment
		(start 139.00639 117.71959)
		(end 140.46015 117.71959)
		(width 0.2032)
		(layer "F.Cu")
		(net "GND")
	)
	(segment
		(start 161.0724 101.76915)
		(end 161.10467 101.73688)
		(width 0.2032)
		(layer "F.Cu")
		(net "GND")
	)
	(segment
		(start 206.47457 130.51076)
		(end 206.47457 129.31917)
		(width 0.254)
		(layer "F.Cu")
		(net "GND")
	)
	(segment
		(start 137.80147 127.71068)
		(end 137.81148 127.70067)
		(width 0.2032)
		(layer "F.Cu")
		(net "GND")
	)
	(segment
		(start 188.07705 127.22995)
		(end 188.08397 127.22304)
		(width 0.2032)
		(layer "F.Cu")
		(net "GND")
	)
	(segment
		(start 185.33983 114.73003)
		(end 185.34668 114.73688)
		(width 0.2032)
		(layer "F.Cu")
		(net "GND")
	)
	(segment
		(start 103.6216 83.17365)
		(end 103.6216 83.1162)
		(width 0.508)
		(layer "F.Cu")
		(net "GND")
	)
	(segment
		(start 166.07239 100.61259)
		(end 166.07239 99.284)
		(width 0.2032)
		(layer "F.Cu")
		(net "GND")
	)
	(segment
		(start 139.07095 112.75979)
		(end 139.09049 112.74025)
		(width 0.2032)
		(layer "F.Cu")
		(net "GND")
	)
	(segment
		(start 83.33158 84.34655)
		(end 83.37282 84.34655)
		(width 0.254)
		(layer "F.Cu")
		(net "GND")
	)
	(segment
		(start 184.0342 124.72317)
		(end 185.03737 124.72317)
		(width 0.2032)
		(layer "F.Cu")
		(net "GND")
	)
	(segment
		(start 123.95712 118.28091)
		(end 125.25657 118.28091)
		(width 0.254)
		(layer "F.Cu")
		(net "GND")
	)
	(segment
		(start 163.52968 101.81187)
		(end 163.53929 101.82149)
		(width 0.2032)
		(layer "F.Cu")
		(net "GND")
	)
	(segment
		(start 197.8716 130.8412)
		(end 197.9216 130.8412)
		(width 0.762)
		(layer "F.Cu")
		(net "GND")
	)
	(segment
		(start 160.4216 85.5662)
		(end 161.77911 85.5662)
		(width 0.762)
		(layer "F.Cu")
		(net "GND")
	)
	(segment
		(start 197.8716 130.8412)
		(end 197.8716 128.5412)
		(width 0.762)
		(layer "F.Cu")
		(net "GND")
	)
	(segment
		(start 94.4216 80.4162)
		(end 95.81945 80.4162)
		(width 0.254)
		(layer "F.Cu")
		(net "GND")
	)
	(segment
		(start 138.95866 122.43627)
		(end 139.24308 122.72069)
		(width 0.2032)
		(layer "F.Cu")
		(net "GND")
	)
	(segment
		(start 114.8216 60.2662)
		(end 114.8216 60.2162)
		(width 0.2032)
		(layer "F.Cu")
		(net "GND")
	)
	(segment
		(start 139.01343 125.22872)
		(end 140.45311 125.22872)
		(width 0.2032)
		(layer "F.Cu")
		(net "GND")
	)
	(segment
		(start 114.8466 56.2412)
		(end 116.3216 56.2412)
		(width 0.254)
		(layer "F.Cu")
		(net "GND")
	)
	(segment
		(start 130.69244 116.78704)
		(end 130.7216 116.8162)
		(width 0.254)
		(layer "F.Cu")
		(net "GND")
	)
	(segment
		(start 222.8216 129.3162)
		(end 223.5216 129.3162)
		(width 0.254)
		(layer "F.Cu")
		(net "GND")
	)
	(segment
		(start 163.04669 135.13688)
		(end 163.04669 135.13689)
		(width 0.2032)
		(layer "F.Cu")
		(net "GND")
	)
	(segment
		(start 154.8216 115.2162)
		(end 154.8216 114.13156)
		(width 0.2032)
		(layer "F.Cu")
		(net "GND")
	)
	(segment
		(start 127.02679 154.41678)
		(end 127.33893 154.65301)
		(width 0.508)
		(layer "F.Cu")
		(net "GND")
	)
	(segment
		(start 159.0467 140.93687)
		(end 159.0467 139.79184)
		(width 0.2032)
		(layer "F.Cu")
		(net "GND")
	)
	(segment
		(start 158.54779 103.30929)
		(end 158.54891 103.31041)
		(width 0.2032)
		(layer "F.Cu")
		(net "GND")
	)
	(segment
		(start 188.08113 119.72602)
		(end 188.08397 119.72318)
		(width 0.2032)
		(layer "F.Cu")
		(net "GND")
	)
	(segment
		(start 230.7269 99.2862)
		(end 230.8916 99.2862)
		(width 0.762)
		(layer "F.Cu")
		(net "GND")
	)
	(segment
		(start 153.57196 103.28737)
		(end 153.57196 101.83749)
		(width 0.2032)
		(layer "F.Cu")
		(net "GND")
	)
	(segment
		(start 114.8216 54.6662)
		(end 117.1216 54.6662)
		(width 0.762)
		(layer "F.Cu")
		(net "GND")
	)
	(segment
		(start 114.9216 75.3662)
		(end 114.9216 75.3162)
		(width 0.762)
		(layer "F.Cu")
		(net "GND")
	)
	(segment
		(start 114.9216 75.3662)
		(end 117.1216 75.3662)
		(width 0.762)
		(layer "F.Cu")
		(net "GND")
	)
	(segment
		(start 114.9216 61.7662)
		(end 114.9216 61.7162)
		(width 0.2032)
		(layer "F.Cu")
		(net "GND")
	)
	(segment
		(start 226.6566 72.9162)
		(end 226.6566 70.9162)
		(width 0.254)
		(layer "F.Cu")
		(net "GND")
	)
	(segment
		(start 137.80332 125.22872)
		(end 137.81148 125.23687)
		(width 0.2032)
		(layer "F.Cu")
		(net "GND")
	)
	(segment
		(start 184.04112 127.22995)
		(end 185.33975 127.22995)
		(width 0.2032)
		(layer "F.Cu")
		(net "GND")
	)
	(segment
		(start 88.9116 68.66847)
		(end 90.61139 68.66847)
		(width 0.254)
		(layer "F.Cu")
		(net "GND")
	)
	(segment
		(start 186.8536 127.22995)
		(end 188.07705 127.22995)
		(width 0.2032)
		(layer "F.Cu")
		(net "GND")
	)
	(segment
		(start 209.4716 130.6412)
		(end 209.4716 129.3162)
		(width 0.254)
		(layer "F.Cu")
		(net "GND")
	)
	(segment
		(start 207.96445 130.6025)
		(end 207.96803 130.59893)
		(width 0.254)
		(layer "F.Cu")
		(net "GND")
	)
	(segment
		(start 77.19563 111.1162)
		(end 77.19563 110.0912)
		(width 0.2032)
		(layer "F.Cu")
		(net "GND")
	)
	(segment
		(start 206.4716 129.3162)
		(end 206.47457 129.31917)
		(width 0.254)
		(layer "F.Cu")
		(net "GND")
	)
	(segment
		(start 186.84668 114.73688)
		(end 186.85352 114.73003)
		(width 0.2032)
		(layer "F.Cu")
		(net "GND")
	)
	(segment
		(start 137.42772 156.98475)
		(end 137.42772 154.65972)
		(width 0.508)
		(layer "F.Cu")
		(net "GND")
	)
	(segment
		(start 126.5266 83.7662)
		(end 126.5266 82.3212)
		(width 0.254)
		(layer "F.Cu")
		(net "GND")
	)
	(segment
		(start 159.0467 139.79184)
		(end 159.24668 139.59186)
		(width 0.2032)
		(layer "F.Cu")
		(net "GND")
	)
	(segment
		(start 123.96284 116.8162)
		(end 124.02212 116.75691)
		(width 0.254)
		(layer "F.Cu")
		(net "GND")
	)
	(segment
		(start 86.70687 87.86371)
		(end 86.70687 87.26371)
		(width 0.254)
		(layer "F.Cu")
		(net "GND")
	)
	(segment
		(start 137.81036 117.71959)
		(end 137.81148 117.71847)
		(width 0.2032)
		(layer "F.Cu")
		(net "GND")
	)
	(segment
		(start 153.52168 100.61187)
		(end 153.5353 100.59825)
		(width 0.2032)
		(layer "F.Cu")
		(net "GND")
	)
	(segment
		(start 136.41451 112.71769)
		(end 137.88466 112.71769)
		(width 0.2032)
		(layer "F.Cu")
		(net "GND")
	)
	(segment
		(start 77.6966 141.1662)
		(end 77.7216 141.1412)
		(width 0.2032)
		(layer "F.Cu")
		(net "GND")
	)
	(segment
		(start 204.9216 130.7412)
		(end 204.9716 130.7412)
		(width 0.2032)
		(layer "F.Cu")
		(net "GND")
	)
	(segment
		(start 123.89978 118.33825)
		(end 123.95712 118.28091)
		(width 0.254)
		(layer "F.Cu")
		(net "GND")
	)
	(segment
		(start 156.04904 100.51026)
		(end 156.12067 100.58189)
		(width 0.2032)
		(layer "F.Cu")
		(net "GND")
	)
	(segment
		(start 86.70687 87.26371)
		(end 88.35686 87.26371)
		(width 0.254)
		(layer "F.Cu")
		(net "GND")
	)
	(segment
		(start 185.33976 122.22996)
		(end 185.34668 122.23688)
		(width 0.2032)
		(layer "F.Cu")
		(net "GND")
	)
	(segment
		(start 138.7854 82.56865)
		(end 138.8534 82.50065)
		(width 0.508)
		(layer "F.Cu")
		(net "GND")
	)
	(segment
		(start 153.54892 103.31041)
		(end 153.57196 103.28737)
		(width 0.2032)
		(layer "F.Cu")
		(net "GND")
	)
	(segment
		(start 172.1466 114.9412)
		(end 173.33362 114.9412)
		(width 0.254)
		(layer "F.Cu")
		(net "GND")
	)
	(segment
		(start 111.98072 83.51278)
		(end 111.98072 83.4662)
		(width 0.254)
		(layer "F.Cu")
		(net "GND")
	)
	(segment
		(start 114.33072 84.8452)
		(end 114.33272 84.8432)
		(width 0.254)
		(layer "F.Cu")
		(net "GND")
	)
	(segment
		(start 139.24308 122.72069)
		(end 140.46126 122.72069)
		(width 0.2032)
		(layer "F.Cu")
		(net "GND")
	)
	(segment
		(start 135.9716 154.1786)
		(end 136.44022 154.64722)
		(width 0.508)
		(layer "F.Cu")
		(net "GND")
	)
	(segment
		(start 127.54159 155.05901)
		(end 127.54159 155.05901)
		(width 0.508)
		(layer "F.Cu")
		(net "GND")
	)
	(segment
		(start 229.08736 118.13811)
		(end 229.56546 118.6162)
		(width 0.254)
		(layer "F.Cu")
		(net "GND")
	)
	(segment
		(start 115.0216 66.3162)
		(end 115.0216 66.2662)
		(width 0.2032)
		(layer "F.Cu")
		(net "GND")
	)
	(segment
		(start 112.6066 82.1312)
		(end 112.6066 81.31362)
		(width 0.254)
		(layer "F.Cu")
		(net "GND")
	)
	(segment
		(start 185.33976 117.22996)
		(end 185.34668 117.23688)
		(width 0.2032)
		(layer "F.Cu")
		(net "GND")
	)
	(segment
		(start 203.4216 130.8412)
		(end 203.4716 130.8412)
		(width 0.2032)
		(layer "F.Cu")
		(net "GND")
	)
	(segment
		(start 143.5466 157.75256)
		(end 143.5466 154.1786)
		(width 0.508)
		(layer "F.Cu")
		(net "GND")
	)
	(segment
		(start 133.51523 157.07224)
		(end 133.52158 157.0786)
		(width 0.508)
		(layer "F.Cu")
		(net "GND")
	)
	(segment
		(start 88.45686 87.18871)
		(end 89.00286 86.64271)
		(width 0.254)
		(layer "F.Cu")
		(net "GND")
	)
	(segment
		(start 223.9616 144.8562)
		(end 225.1716 144.8562)
		(width 0.254)
		(layer "F.Cu")
		(net "GND")
	)
	(segment
		(start 114.8216 56.2162)
		(end 114.8466 56.2412)
		(width 0.2032)
		(layer "F.Cu")
		(net "GND")
	)
	(segment
		(start 143.7216 106.11212)
		(end 143.7216 105.3662)
		(width 0.2032)
		(layer "F.Cu")
		(net "GND")
	)
	(segment
		(start 77.19563 120.3912)
		(end 77.19563 119.3662)
		(width 0.2032)
		(layer "F.Cu")
		(net "GND")
	)
	(segment
		(start 194.1216 124.1412)
		(end 194.1216 123.4162)
		(width 0.2032)
		(layer "F.Cu")
		(net "GND")
	)
	(segment
		(start 135.99148 154.1786)
		(end 136.9466 154.1786)
		(width 0.508)
		(layer "F.Cu")
		(net "GND")
	)
	(segment
		(start 93.70686 84.23871)
		(end 93.70686 82.56371)
		(width 0.254)
		(layer "F.Cu")
		(net "GND")
	)
	(segment
		(start 139.99147 154.1786)
		(end 140.30235 154.53599)
		(width 0.508)
		(layer "F.Cu")
		(net "GND")
	)
	(segment
		(start 230.85084 107.52995)
		(end 230.85584 107.53495)
		(width 0.762)
		(layer "F.Cu")
		(net "GND")
	)
	(segment
		(start 96.03187 86.56371)
		(end 97.70686 86.56371)
		(width 0.254)
		(layer "F.Cu")
		(net "GND")
	)
	(segment
		(start 132.224 154.3036)
		(end 132.52158 154.60118)
		(width 0.508)
		(layer "F.Cu")
		(net "GND")
	)
	(segment
		(start 156.54658 136.8871)
		(end 156.54663 136.88705)
		(width 0.2032)
		(layer "F.Cu")
		(net "GND")
	)
	(segment
		(start 112.3216 82.4162)
		(end 112.6066 82.1312)
		(width 0.254)
		(layer "F.Cu")
		(net "GND")
	)
	(segment
		(start 131.87 154.3036)
		(end 132.224 154.3036)
		(width 0.508)
		(layer "F.Cu")
		(net "GND")
	)
	(segment
		(start 114.9216 63.2662)
		(end 114.9216 63.2162)
		(width 0.2032)
		(layer "F.Cu")
		(net "GND")
	)
	(segment
		(start 166.04668 136.8871)
		(end 166.04668 135.29185)
		(width 0.2032)
		(layer "F.Cu")
		(net "GND")
	)
	(segment
		(start 114.9216 71.7662)
		(end 114.9216 71.7162)
		(width 0.2032)
		(layer "F.Cu")
		(net "GND")
	)
	(segment
		(start 188.07706 117.22996)
		(end 188.08397 117.22306)
		(width 0.2032)
		(layer "F.Cu")
		(net "GND")
	)
	(segment
		(start 136.41149 115.22058)
		(end 136.41984 115.21223)
		(width 0.2032)
		(layer "F.Cu")
		(net "GND")
	)
	(segment
		(start 204.9716 130.7412)
		(end 204.9716 129.3162)
		(width 0.254)
		(layer "F.Cu")
		(net "GND")
	)
	(segment
		(start 203.4716 130.8412)
		(end 203.4716 129.3162)
		(width 0.254)
		(layer "F.Cu")
		(net "GND")
	)
	(segment
		(start 133.51523 155.99134)
		(end 133.51523 154.57938)
		(width 0.508)
		(layer "F.Cu")
		(net "GND")
	)
	(segment
		(start 139.12721 120.24394)
		(end 140.4379 120.24394)
		(width 0.2032)
		(layer "F.Cu")
		(net "GND")
	)
	(segment
		(start 110.1716 57.46258)
		(end 110.1716 56.464)
		(width 0.2032)
		(layer "F.Cu")
		(net "GND")
	)
	(segment
		(start 133.21764 154.2818)
		(end 133.51523 154.57938)
		(width 0.508)
		(layer "F.Cu")
		(net "GND")
	)
	(segment
		(start 186.85359 117.22996)
		(end 188.07706 117.22996)
		(width 0.2032)
		(layer "F.Cu")
		(net "GND")
	)
	(segment
		(start 159.0467 136.8871)
		(end 159.0467 135.30181)
		(width 0.2032)
		(layer "F.Cu")
		(net "GND")
	)
	(segment
		(start 120.3216 80.7162)
		(end 120.3216 79.7662)
		(width 0.2032)
		(layer "F.Cu")
		(net "GND")
	)
	(segment
		(start 78.9966 101.1662)
		(end 79.0216 101.1412)
		(width 0.2032)
		(layer "F.Cu")
		(net "GND")
	)
	(segment
		(start 116.54161 157.7576)
		(end 116.54161 154.34359)
		(width 0.508)
		(layer "F.Cu")
		(net "GND")
	)
	(segment
		(start 137.88466 112.71769)
		(end 137.88768 112.71467)
		(width 0.2032)
		(layer "F.Cu")
		(net "GND")
	)
	(segment
		(start 140.45126 127.71068)
		(end 140.46126 127.72068)
		(width 0.2032)
		(layer "F.Cu")
		(net "GND")
	)
	(segment
		(start 184.0342 127.22304)
		(end 184.04112 127.22995)
		(width 0.2032)
		(layer "F.Cu")
		(net "GND")
	)
	(segment
		(start 214.9716 130.7412)
		(end 214.9716 129.3162)
		(width 0.254)
		(layer "F.Cu")
		(net "GND")
	)
	(segment
		(start 154.04671 139.69183)
		(end 154.14668 139.59186)
		(width 0.2032)
		(layer "F.Cu")
		(net "GND")
	)
	(segment
		(start 184.04111 122.22996)
		(end 185.33976 122.22996)
		(width 0.2032)
		(layer "F.Cu")
		(net "GND")
	)
	(segment
		(start 168.53128 99.27824)
		(end 168.54889 99.26063)
		(width 0.2032)
		(layer "F.Cu")
		(net "GND")
	)
	(segment
		(start 79.0216 101.1412)
		(end 79.0216 100.6162)
		(width 0.2032)
		(layer "F.Cu")
		(net "GND")
	)
	(segment
		(start 164.0026 83.3472)
		(end 164.0026 82.46763)
		(width 0.762)
		(layer "F.Cu")
		(net "GND")
	)
	(segment
		(start 180.90984 104.04999)
		(end 180.90984 102.82796)
		(width 0.254)
		(layer "F.Cu")
		(net "GND")
	)
	(segment
		(start 166.2716 116.4162)
		(end 166.2716 115.2162)
		(width 0.254)
		(layer "F.Cu")
		(net "GND")
	)
	(segment
		(start 137.49124 122.72069)
		(end 137.82153 122.39041)
		(width 0.2032)
		(layer "F.Cu")
		(net "GND")
	)
	(segment
		(start 216.4716 130.7412)
		(end 216.4716 129.3162)
		(width 0.254)
		(layer "F.Cu")
		(net "GND")
	)
	(segment
		(start 153.5353 99.27426)
		(end 153.54892 99.26063)
		(width 0.2032)
		(layer "F.Cu")
		(net "GND")
	)
	(segment
		(start 230.85084 104.98995)
		(end 230.85584 104.99495)
		(width 0.762)
		(layer "F.Cu")
		(net "GND")
	)
	(segment
		(start 114.9216 64.7662)
		(end 116.3466 64.7662)
		(width 0.254)
		(layer "F.Cu")
		(net "GND")
	)
	(segment
		(start 158.54891 100.43413)
		(end 158.54891 99.26063)
		(width 0.2032)
		(layer "F.Cu")
		(net "GND")
	)
	(segment
		(start 114.86305 56.7662)
		(end 116.3466 56.7662)
		(width 0.254)
		(layer "F.Cu")
		(net "GND")
	)
	(segment
		(start 89.00286 86.64271)
		(end 89.85225 86.64271)
		(width 0.254)
		(layer "F.Cu")
		(net "GND")
	)
	(segment
		(start 184.0411 112.22997)
		(end 185.33977 112.22997)
		(width 0.2032)
		(layer "F.Cu")
		(net "GND")
	)
	(segment
		(start 140.45692 115.22493)
		(end 140.46126 115.22058)
		(width 0.2032)
		(layer "F.Cu")
		(net "GND")
	)
	(segment
		(start 139.00528 117.71847)
		(end 139.00639 117.71959)
		(width 0.2032)
		(layer "F.Cu")
		(net "GND")
	)
	(segment
		(start 93.70686 88.8887)
		(end 93.72286 88.8887)
		(width 0.254)
		(layer "F.Cu")
		(net "GND")
	)
	(segment
		(start 156.54658 140.93687)
		(end 156.54658 139.69196)
		(width 0.2032)
		(layer "F.Cu")
		(net "GND")
	)
	(segment
		(start 186.84668 127.23688)
		(end 186.8536 127.22995)
		(width 0.2032)
		(layer "F.Cu")
		(net "GND")
	)
	(segment
		(start 140.44173 112.74025)
		(end 140.46126 112.72071)
		(width 0.2032)
		(layer "F.Cu")
		(net "GND")
	)
	(segment
		(start 104.75022 84.61749)
		(end 104.76635 84.61749)
		(width 0.254)
		(layer "F.Cu")
		(net "GND")
	)
	(segment
		(start 163.5489 99.26063)
		(end 163.57227 99.284)
		(width 0.2032)
		(layer "F.Cu")
		(net "GND")
	)
	(segment
		(start 139.09049 112.74025)
		(end 140.44173 112.74025)
		(width 0.2032)
		(layer "F.Cu")
		(net "GND")
	)
	(segment
		(start 184.0342 122.22305)
		(end 184.04111 122.22996)
		(width 0.2032)
		(layer "F.Cu")
		(net "GND")
	)
	(segment
		(start 156.04904 102.08949)
		(end 156.21867 101.91987)
		(width 0.2032)
		(layer "F.Cu")
		(net "GND")
	)
	(segment
		(start 114.8216 54.7162)
		(end 114.8216 54.6662)
		(width 0.762)
		(layer "F.Cu")
		(net "GND")
	)
	(segment
		(start 124.02212 116.75691)
		(end 125.25657 116.75691)
		(width 0.254)
		(layer "F.Cu")
		(net "GND")
	)
	(segment
		(start 139.09667 120.27447)
		(end 139.12721 120.24394)
		(width 0.2032)
		(layer "F.Cu")
		(net "GND")
	)
	(segment
		(start 184.04104 114.73003)
		(end 185.33983 114.73003)
		(width 0.2032)
		(layer "F.Cu")
		(net "GND")
	)
	(segment
		(start 229.6216 129.3162)
		(end 229.6216 127.3912)
		(width 0.254)
		(layer "F.Cu")
		(net "GND")
	)
	(segment
		(start 224.0416 134.6962)
		(end 225.1716 134.6962)
		(width 0.254)
		(layer "F.Cu")
		(net "GND")
	)
	(segment
		(start 209.4716 130.6412)
		(end 209.5216 130.6412)
		(width 0.2032)
		(layer "F.Cu")
		(net "GND")
	)
	(segment
		(start 199.4216 130.8412)
		(end 199.4466 130.8162)
		(width 0.2032)
		(layer "F.Cu")
		(net "GND")
	)
	(segment
		(start 166.04902 99.26063)
		(end 166.07239 99.284)
		(width 0.2032)
		(layer "F.Cu")
		(net "GND")
	)
	(segment
		(start 159.24668 139.59186)
		(end 159.24668 139.53687)
		(width 0.2032)
		(layer "F.Cu")
		(net "GND")
	)
	(segment
		(start 137.90472 115.21223)
		(end 137.91308 115.20387)
		(width 0.2032)
		(layer "F.Cu")
		(net "GND")
	)
	(segment
		(start 158.3216 128.7162)
		(end 158.3216 127.80128)
		(width 0.2032)
		(layer "F.Cu")
		(net "GND")
	)
	(segment
		(start 186.84668 112.23688)
		(end 186.85358 112.22997)
		(width 0.2032)
		(layer "F.Cu")
		(net "GND")
	)
	(segment
		(start 163.04669 136.8871)
		(end 163.04669 135.13689)
		(width 0.2032)
		(layer "F.Cu")
		(net "GND")
	)
	(segment
		(start 228.3966 116.3317)
		(end 230.31363 116.3317)
		(width 0.254)
		(layer "F.Cu")
		(net "GND")
	)
	(segment
		(start 186.84668 125.03247)
		(end 186.90166 125.03247)
		(width 0.2032)
		(layer "F.Cu")
		(net "GND")
	)
	(segment
		(start 161.04903 103.31041)
		(end 161.0724 103.28704)
		(width 0.2032)
		(layer "F.Cu")
		(net "GND")
	)
	(segment
		(start 113.52511 157.74109)
		(end 113.52511 154.36162)
		(width 0.508)
		(layer "F.Cu")
		(net "GND")
	)
	(segment
		(start 78.99659 113.2662)
		(end 81.04219 113.2662)
		(width 0.2032)
		(layer "F.Cu")
		(net "GND")
	)
	(segment
		(start 131.8482 154.2818)
		(end 131.87 154.3036)
		(width 0.508)
		(layer "F.Cu")
		(net "GND")
	)
	(segment
		(start 77.19563 138.1162)
		(end 77.19563 137.0912)
		(width 0.2032)
		(layer "F.Cu")
		(net "GND")
	)
	(segment
		(start 188.06061 124.74654)
		(end 188.08397 124.72317)
		(width 0.2032)
		(layer "F.Cu")
		(net "GND")
	)
	(segment
		(start 126.5216 82.3162)
		(end 126.5266 82.3212)
		(width 0.254)
		(layer "F.Cu")
		(net "GND")
	)
	(segment
		(start 161.54657 136.23914)
		(end 161.54657 135.27822)
		(width 0.254)
		(layer "F.Cu")
		(net "GND")
	)
	(segment
		(start 161.0724 100.6046)
		(end 161.10467 100.63688)
		(width 0.2032)
		(layer "F.Cu")
		(net "GND")
	)
	(segment
		(start 158.69668 100.63688)
		(end 158.69668 100.58189)
		(width 0.2032)
		(layer "F.Cu")
		(net "GND")
	)
	(segment
		(start 184.0342 119.72318)
		(end 184.03704 119.72602)
		(width 0.2032)
		(layer "F.Cu")
		(net "GND")
	)
	(segment
		(start 74.78883 105.28343)
		(end 74.8216 105.3162)
		(width 0.2032)
		(layer "F.Cu")
		(net "GND")
	)
	(segment
		(start 136.9466 154.1786)
		(end 137.42772 154.65972)
		(width 0.508)
		(layer "F.Cu")
		(net "GND")
	)
	(segment
		(start 200.5592 134.2162)
		(end 200.5592 132.1162)
		(width 0.762)
		(layer "F.Cu")
		(net "GND")
	)
	(segment
		(start 184.0342 117.22306)
		(end 184.04111 117.22996)
		(width 0.2032)
		(layer "F.Cu")
		(net "GND")
	)
	(segment
		(start 110.83072 85.0162)
		(end 112.01823 85.0162)
		(width 0.254)
		(layer "F.Cu")
		(net "GND")
	)
	(segment
		(start 158.54668 101.81187)
		(end 158.54779 101.81299)
		(width 0.2032)
		(layer "F.Cu")
		(net "GND")
	)
	(segment
		(start 186.85358 112.22997)
		(end 188.07707 112.22997)
		(width 0.2032)
		(layer "F.Cu")
		(net "GND")
	)
	(segment
		(start 115.0216 67.7662)
		(end 116.3466 67.7662)
		(width 0.254)
		(layer "F.Cu")
		(net "GND")
	)
	(segment
		(start 130.22637 116.24891)
		(end 130.69244 116.71498)
		(width 0.254)
		(layer "F.Cu")
		(net "GND")
	)
	(segment
		(start 78.99659 127.7662)
		(end 78.99659 126.9162)
		(width 0.2032)
		(layer "F.Cu")
		(net "GND")
	)
	(segment
		(start 121.1216 79.1162)
		(end 122.1216 79.1162)
		(width 0.2032)
		(layer "F.Cu")
		(net "GND")
	)
	(segment
		(start 226.9341 124.9287)
		(end 226.9466 124.9412)
		(width 0.2032)
		(layer "F.Cu")
		(net "GND")
	)
	(segment
		(start 109.48401 67.7162)
		(end 110.9216 67.7162)
		(width 0.762)
		(layer "F.Cu")
		(net "GND")
	)
	(segment
		(start 200.5216 132.1162)
		(end 200.5592 132.1162)
		(width 0.762)
		(layer "F.Cu")
		(net "GND")
	)
	(segment
		(start 136.41149 125.22056)
		(end 136.41964 125.22872)
		(width 0.2032)
		(layer "F.Cu")
		(net "GND")
	)
	(segment
		(start 133.51523 157.07224)
		(end 133.51523 155.99134)
		(width 0.508)
		(layer "F.Cu")
		(net "GND")
	)
	(segment
		(start 113.1216 80.91363)
		(end 113.1216 79.3162)
		(width 0.254)
		(layer "F.Cu")
		(net "GND")
	)
	(segment
		(start 187.1876 124.74654)
		(end 188.06061 124.74654)
		(width 0.2032)
		(layer "F.Cu")
		(net "GND")
	)
	(segment
		(start 83.48998 84.46371)
		(end 84.25686 84.46371)
		(width 0.254)
		(layer "F.Cu")
		(net "GND")
	)
	(segment
		(start 74.78883 105.28343)
		(end 74.78883 104.24897)
		(width 0.2032)
		(layer "F.Cu")
		(net "GND")
	)
	(segment
		(start 137.82153 122.39041)
		(end 137.83194 122.39041)
		(width 0.2032)
		(layer "F.Cu")
		(net "GND")
	)
	(segment
		(start 156.54658 139.69196)
		(end 156.64668 139.59186)
		(width 0.2032)
		(layer "F.Cu")
		(net "GND")
	)
	(segment
		(start 127.54159 157.7576)
		(end 127.54159 155.05901)
		(width 0.508)
		(layer "F.Cu")
		(net "GND")
	)
	(segment
		(start 161.0724 100.6046)
		(end 161.0724 99.284)
		(width 0.2032)
		(layer "F.Cu")
		(net "GND")
	)
	(segment
		(start 168.51368 100.63669)
		(end 168.53128 100.61908)
		(width 0.2032)
		(layer "F.Cu")
		(net "GND")
	)
	(segment
		(start 229.0716 117.7472)
		(end 229.08736 117.76297)
		(width 0.254)
		(layer "F.Cu")
		(net "GND")
	)
	(segment
		(start 114.9216 73.2662)
		(end 116.3466 73.2662)
		(width 0.254)
		(layer "F.Cu")
		(net "GND")
	)
	(segment
		(start 73.53981 115.798)
		(end 73.53981 115.5162)
		(width 0.2032)
		(layer "F.Cu")
		(net "GND")
	)
	(segment
		(start 168.53128 103.2928)
		(end 168.53128 101.81973)
		(width 0.2032)
		(layer "F.Cu")
		(net "GND")
	)
	(segment
		(start 169.5216 82.8162)
		(end 169.5216 81.4162)
		(width 0.635)
		(layer "F.Cu")
		(net "GND")
	)
	(segment
		(start 154.04671 136.8871)
		(end 154.04671 135.1369)
		(width 0.2032)
		(layer "F.Cu")
		(net "GND")
	)
	(segment
		(start 199.4466 130.8162)
		(end 199.4466 129.3412)
		(width 0.254)
		(layer "F.Cu")
		(net "GND")
	)
	(segment
		(start 136.40433 84.34267)
		(end 136.40433 83.1162)
		(width 0.762)
		(layer "F.Cu")
		(net "GND")
	)
	(segment
		(start 73.53981 115.5162)
		(end 74.25606 115.5162)
		(width 0.2032)
		(layer "F.Cu")
		(net "GND")
	)
	(segment
		(start 114.9216 61.7662)
		(end 116.3466 61.7662)
		(width 0.254)
		(layer "F.Cu")
		(net "GND")
	)
	(segment
		(start 112.83072 84.9537)
		(end 112.83072 84.3162)
		(width 0.254)
		(layer "F.Cu")
		(net "GND")
	)
	(segment
		(start 161.64668 135.17811)
		(end 161.64668 135.13688)
		(width 0.254)
		(layer "F.Cu")
		(net "GND")
	)
	(segment
		(start 133.54158 157.7576)
		(end 133.54158 156.0177)
		(width 0.508)
		(layer "F.Cu")
		(net "GND")
	)
	(segment
		(start 114.9216 64.7662)
		(end 114.9216 64.7162)
		(width 0.2032)
		(layer "F.Cu")
		(net "GND")
	)
	(segment
		(start 156.04904 103.31041)
		(end 156.04904 102.08949)
		(width 0.2032)
		(layer "F.Cu")
		(net "GND")
	)
	(segment
		(start 77.19563 107.1412)
		(end 77.19563 106.1162)
		(width 0.2032)
		(layer "F.Cu")
		(net "GND")
	)
	(segment
		(start 77.7216 141.1412)
		(end 77.7216 140.3162)
		(width 0.2032)
		(layer "F.Cu")
		(net "GND")
	)
	(segment
		(start 138.96448 127.71068)
		(end 140.45126 127.71068)
		(width 0.2032)
		(layer "F.Cu")
		(net "GND")
	)
	(segment
		(start 156.04904 100.51026)
		(end 156.04904 99.26063)
		(width 0.2032)
		(layer "F.Cu")
		(net "GND")
	)
	(segment
		(start 171.34767 82.97132)
		(end 171.34767 81.66165)
		(width 0.635)
		(layer "F.Cu")
		(net "GND")
	)
	(segment
		(start 133.51523 155.99134)
		(end 133.54158 156.0177)
		(width 0.508)
		(layer "F.Cu")
		(net "GND")
	)
	(segment
		(start 167.54655 135.39198)
		(end 167.74668 135.19186)
		(width 0.2032)
		(layer "F.Cu")
		(net "GND")
	)
	(segment
		(start 167.74668 135.19186)
		(end 167.74668 135.13688)
		(width 0.2032)
		(layer "F.Cu")
		(net "GND")
	)
	(segment
		(start 161.54657 135.27822)
		(end 161.64668 135.17811)
		(width 0.254)
		(layer "F.Cu")
		(net "GND")
	)
	(segment
		(start 163.53929 103.30079)
		(end 163.5489 103.31041)
		(width 0.2032)
		(layer "F.Cu")
		(net "GND")
	)
	(segment
		(start 136.41984 115.21223)
		(end 137.90472 115.21223)
		(width 0.2032)
		(layer "F.Cu")
		(net "GND")
	)
	(segment
		(start 114.58572 84.69241)
		(end 114.58572 83.5612)
		(width 0.254)
		(layer "F.Cu")
		(net "GND")
	)
	(segment
		(start 168.53128 100.61908)
		(end 168.53128 99.27824)
		(width 0.2032)
		(layer "F.Cu")
		(net "GND")
	)
	(segment
		(start 116.54161 154.34359)
		(end 116.5566 154.3286)
		(width 0.508)
		(layer "F.Cu")
		(net "GND")
	)
	(segment
		(start 135.9716 154.1786)
		(end 135.99148 154.1786)
		(width 0.508)
		(layer "F.Cu")
		(net "GND")
	)
	(segment
		(start 193.3716 134.81302)
		(end 193.3716 133.764)
		(width 0.254)
		(layer "F.Cu")
		(net "GND")
	)
	(segment
		(start 83.37282 84.34655)
		(end 83.48998 84.46371)
		(width 0.254)
		(layer "F.Cu")
		(net "GND")
	)
	(segment
		(start 230.7269 96.7462)
		(end 230.7916 96.7462)
		(width 0.762)
		(layer "F.Cu")
		(net "GND")
	)
	(segment
		(start 153.5216 128.9162)
		(end 153.5216 128.23384)
		(width 0.2032)
		(layer "F.Cu")
		(net "GND")
	)
	(segment
		(start 144.5216 104.7162)
		(end 145.4216 104.7162)
		(width 0.2032)
		(layer "F.Cu")
		(net "GND")
	)
	(segment
		(start 140.42772 156.98475)
		(end 140.42772 154.87014)
		(width 0.508)
		(layer "F.Cu")
		(net "GND")
	)
	(segment
		(start 113.1216 82.4162)
		(end 113.1216 82.4162)
		(width 0.254)
		(layer "F.Cu")
		(net "GND")
	)
	(segment
		(start 218.5716 130.7412)
		(end 218.5716 128.5412)
		(width 0.762)
		(layer "F.Cu")
		(net "GND")
	)
	(segment
		(start 229.5216 123.0162)
		(end 229.6216 123.1162)
		(width 0.254)
		(layer "F.Cu")
		(net "GND")
	)
	(segment
		(start 192.6216 122.6162)
		(end 193.4716 122.6162)
		(width 0.2032)
		(layer "F.Cu")
		(net "GND")
	)
	(segment
		(start 153.57196 101.83749)
		(end 153.595 101.81444)
		(width 0.2032)
		(layer "F.Cu")
		(net "GND")
	)
	(segment
		(start 132.6241 88.7187)
		(end 132.6266 88.7162)
		(width 0.254)
		(layer "F.Cu")
		(net "GND")
	)
	(segment
		(start 136.44022 156.99725)
		(end 136.44022 154.64722)
		(width 0.508)
		(layer "F.Cu")
		(net "GND")
	)
	(segment
		(start 169.04668 136.8871)
		(end 169.04668 135.13688)
		(width 0.2032)
		(layer "F.Cu")
		(net "GND")
	)
	(segment
		(start 169.4716 82.8162)
		(end 169.5216 82.8162)
		(width 0.635)
		(layer "F.Cu")
		(net "GND")
	)
	(segment
		(start 136.41149 127.72068)
		(end 136.42149 127.71068)
		(width 0.2032)
		(layer "F.Cu")
		(net "GND")
	)
	(segment
		(start 114.9216 73.7662)
		(end 116.3466 73.7662)
		(width 0.254)
		(layer "F.Cu")
		(net "GND")
	)
	(segment
		(start 114.8216 60.2662)
		(end 116.3466 60.2662)
		(width 0.254)
		(layer "F.Cu")
		(net "GND")
	)
	(segment
		(start 214.9216 130.7412)
		(end 214.9716 130.7412)
		(width 0.2032)
		(layer "F.Cu")
		(net "GND")
	)
	(segment
		(start 137.42772 156.98475)
		(end 137.52157 157.0786)
		(width 0.508)
		(layer "F.Cu")
		(net "GND")
	)
	(segment
		(start 153.5353 100.59825)
		(end 153.5353 99.27426)
		(width 0.2032)
		(layer "F.Cu")
		(net "GND")
	)
	(segment
		(start 184.04111 117.22996)
		(end 185.33976 117.22996)
		(width 0.2032)
		(layer "F.Cu")
		(net "GND")
	)
	(segment
		(start 138.95448 127.70067)
		(end 138.96448 127.71068)
		(width 0.2032)
		(layer "F.Cu")
		(net "GND")
	)
	(segment
		(start 163.53929 103.30079)
		(end 163.53929 101.82149)
		(width 0.2032)
		(layer "F.Cu")
		(net "GND")
	)
	(segment
		(start 161.04903 99.26063)
		(end 161.0724 99.284)
		(width 0.2032)
		(layer "F.Cu")
		(net "GND")
	)
	(segment
		(start 115.73072 87.0162)
		(end 116.18072 87.4662)
		(width 0.254)
		(layer "F.Cu")
		(net "GND")
	)
	(segment
		(start 158.3216 131.0162)
		(end 158.3216 130.3162)
		(width 0.2032)
		(layer "F.Cu")
		(net "GND")
	)
	(segment
		(start 97.70686 86.57955)
		(end 97.70686 86.56371)
		(width 0.254)
		(layer "F.Cu")
		(net "GND")
	)
	(segment
		(start 154.04671 140.93687)
		(end 154.04671 139.69183)
		(width 0.2032)
		(layer "F.Cu")
		(net "GND")
	)
	(segment
		(start 180.90984 102.82796)
		(end 180.9216 102.8162)
		(width 0.254)
		(layer "F.Cu")
		(net "GND")
	)
	(segment
		(start 124.49973 157.71574)
		(end 124.5416 157.7576)
		(width 0.508)
		(layer "F.Cu")
		(net "GND")
	)
	(segment
		(start 140.46015 117.71959)
		(end 140.46126 117.7207)
		(width 0.2032)
		(layer "F.Cu")
		(net "GND")
	)
	(segment
		(start 129.52609 154.37508)
		(end 129.54159 154.35959)
		(width 0.508)
		(layer "F.Cu")
		(net "GND")
	)
	(segment
		(start 164.0026 83.3472)
		(end 164.1716 83.5162)
		(width 0.762)
		(layer "F.Cu")
		(net "GND")
	)
	(segment
		(start 115.0216 66.2662)
		(end 116.3466 66.2662)
		(width 0.254)
		(layer "F.Cu")
		(net "GND")
	)
	(segment
		(start 72.65433 143.8162)
		(end 73.55606 143.8162)
		(width 0.2032)
		(layer "F.Cu")
		(net "GND")
	)
	(segment
		(start 156.21867 101.91987)
		(end 156.21867 101.86488)
		(width 0.2032)
		(layer "F.Cu")
		(net "GND")
	)
	(segment
		(start 199.4466 129.3412)
		(end 199.4716 129.3162)
		(width 0.2032)
		(layer "F.Cu")
		(net "GND")
	)
	(segment
		(start 139.08582 115.22493)
		(end 140.45692 115.22493)
		(width 0.2032)
		(layer "F.Cu")
		(net "GND")
	)
	(segment
		(start 113.52511 157.74109)
		(end 113.54162 157.7576)
		(width 0.508)
		(layer "F.Cu")
		(net "GND")
	)
	(segment
		(start 115.14322 87.0162)
		(end 115.73072 87.0162)
		(width 0.254)
		(layer "F.Cu")
		(net "GND")
	)
	(segment
		(start 208.5592 134.2162)
		(end 208.5592 131.5162)
		(width 0.762)
		(layer "F.Cu")
		(net "GND")
	)
	(segment
		(start 184.03704 119.72602)
		(end 185.34383 119.72602)
		(width 0.2032)
		(layer "F.Cu")
		(net "GND")
	)
	(segment
		(start 70.6716 103.1162)
		(end 71.1216 102.6662)
		(width 0.2032)
		(layer "F.Cu")
		(net "GND")
	)
	(segment
		(start 127.54159 155.05901)
		(end 127.54159 155.05901)
		(width 0.508)
		(layer "F.Cu")
		(net "GND")
	)
	(segment
		(start 136.4126 117.71959)
		(end 137.81036 117.71959)
		(width 0.2032)
		(layer "F.Cu")
		(net "GND")
	)
	(segment
		(start 162.30042 82.0086)
		(end 163.54358 82.0086)
		(width 0.762)
		(layer "F.Cu")
		(net "GND")
	)
	(segment
		(start 86.95686 90.06371)
		(end 86.95686 89.06371)
		(width 0.254)
		(layer "F.Cu")
		(net "GND")
	)
	(segment
		(start 184.0342 112.22307)
		(end 184.0411 112.22997)
		(width 0.2032)
		(layer "F.Cu")
		(net "GND")
	)
	(segment
		(start 123.9216 116.8162)
		(end 123.96284 116.8162)
		(width 0.254)
		(layer "F.Cu")
		(net "GND")
	)
	(segment
		(start 188.07706 122.22996)
		(end 188.08397 122.22305)
		(width 0.2032)
		(layer "F.Cu")
		(net "GND")
	)
	(segment
		(start 158.54891 100.43413)
		(end 158.69668 100.58189)
		(width 0.2032)
		(layer "F.Cu")
		(net "GND")
	)
	(segment
		(start 166.07239 100.61259)
		(end 166.09668 100.63688)
		(width 0.2032)
		(layer "F.Cu")
		(net "GND")
	)
	(segment
		(start 138.7854 83.8662)
		(end 138.7854 82.56865)
		(width 0.508)
		(layer "F.Cu")
		(net "GND")
	)
	(segment
		(start 77.19563 124.3662)
		(end 77.19563 123.3412)
		(width 0.2032)
		(layer "F.Cu")
		(net "GND")
	)
	(segment
		(start 185.33975 127.22995)
		(end 185.34668 127.23688)
		(width 0.2032)
		(layer "F.Cu")
		(net "GND")
	)
	(segment
		(start 152.6419 116.0162)
		(end 154.1716 116.0162)
		(width 0.2032)
		(layer "F.Cu")
		(net "GND")
	)
	(segment
		(start 161.4216 130.3162)
		(end 162.47976 130.3162)
		(width 0.2032)
		(layer "F.Cu")
		(net "GND")
	)
	(segment
		(start 86.90686 82.56371)
		(end 86.90686 82.56371)
		(width 0.254)
		(layer "F.Cu")
		(net "GND")
	)
	(segment
		(start 158.54779 103.30929)
		(end 158.54779 101.81299)
		(width 0.2032)
		(layer "F.Cu")
		(net "GND")
	)
	(segment
		(start 140.42772 156.98475)
		(end 140.52157 157.0786)
		(width 0.508)
		(layer "F.Cu")
		(net "GND")
	)
	(segment
		(start 89.93125 86.56371)
		(end 91.38187 86.56371)
		(width 0.254)
		(layer "F.Cu")
		(net "GND")
	)
	(segment
		(start 208.3216 131.5162)
		(end 208.5592 131.5162)
		(width 0.762)
		(layer "F.Cu")
		(net "GND")
	)
	(segment
		(start 139.00528 125.23687)
		(end 139.01343 125.22872)
		(width 0.2032)
		(layer "F.Cu")
		(net "GND")
	)
	(segment
		(start 153.5216 131.2068)
		(end 153.5216 130.5162)
		(width 0.2032)
		(layer "F.Cu")
		(net "GND")
	)
	(segment
		(start 114.9216 73.2662)
		(end 114.9216 73.2162)
		(width 0.2032)
		(layer "F.Cu")
		(net "GND")
	)
	(segment
		(start 111.9216 59.7286)
		(end 111.9216 59.7162)
		(width 0.762)
		(layer "F.Cu")
		(net "GND")
	)
	(segment
		(start 198.9442 144.96546)
		(end 199.8166 144.96546)
		(width 0.254)
		(layer "F.Cu")
		(net "GND")
	)
	(segment
		(start 115.0216 67.7662)
		(end 115.0216 67.7162)
		(width 0.2032)
		(layer "F.Cu")
		(net "GND")
	)
	(segment
		(start 140.45311 125.22872)
		(end 140.46126 125.22056)
		(width 0.2032)
		(layer "F.Cu")
		(net "GND")
	)
	(segment
		(start 103.6216 83.17365)
		(end 104.75022 83.17365)
		(width 0.508)
		(layer "F.Cu")
		(net "GND")
	)
	(segment
		(start 136.42149 127.71068)
		(end 137.80147 127.71068)
		(width 0.2032)
		(layer "F.Cu")
		(net "GND")
	)
	(segment
		(start 229.56546 118.6162)
		(end 230.13531 118.6162)
		(width 0.254)
		(layer "F.Cu")
		(net "GND")
	)
	(segment
		(start 225.9216 120.3162)
		(end 226.7091 120.3162)
		(width 0.254)
		(layer "F.Cu")
		(net "GND")
	)
	(segment
		(start 132.6216 90.4162)
		(end 132.6241 90.4137)
		(width 0.254)
		(layer "F.Cu")
		(net "GND")
	)
	(segment
		(start 186.84668 117.23688)
		(end 186.85359 117.22996)
		(width 0.2032)
		(layer "F.Cu")
		(net "GND")
	)
	(segment
		(start 168.51368 101.80212)
		(end 168.53128 101.81973)
		(width 0.2032)
		(layer "F.Cu")
		(net "GND")
	)
	(segment
		(start 113.1216 79.3162)
		(end 113.1216 79.3162)
		(width 0.254)
		(layer "F.Cu")
		(net "GND")
	)
	(segment
		(start 104.75022 84.61749)
		(end 104.75022 83.17365)
		(width 0.254)
		(layer "F.Cu")
		(net "GND")
	)
	(segment
		(start 166.04668 135.29185)
		(end 166.14668 135.19186)
		(width 0.2032)
		(layer "F.Cu")
		(net "GND")
	)
	(segment
		(start 154.14668 139.59186)
		(end 154.14668 139.53687)
		(width 0.2032)
		(layer "F.Cu")
		(net "GND")
	)
	(segment
		(start 123.85854 118.33825)
		(end 123.89978 118.33825)
		(width 0.254)
		(layer "F.Cu")
		(net "GND")
	)
	(segment
		(start 159.0467 135.30181)
		(end 159.14668 135.20183)
		(width 0.2032)
		(layer "F.Cu")
		(net "GND")
	)
	(segment
		(start 186.84953 119.72602)
		(end 188.08113 119.72602)
		(width 0.2032)
		(layer "F.Cu")
		(net "GND")
	)
	(segment
		(start 129.52609 157.74211)
		(end 129.52609 154.37508)
		(width 0.508)
		(layer "F.Cu")
		(net "GND")
	)
	(segment
		(start 188.07707 112.22997)
		(end 188.08397 112.22307)
		(width 0.2032)
		(layer "F.Cu")
		(net "GND")
	)
	(segment
		(start 114.9216 63.2662)
		(end 116.3466 63.2662)
		(width 0.254)
		(layer "F.Cu")
		(net "GND")
	)
	(segment
		(start 161.6216 128.4162)
		(end 162.7216 128.4162)
		(width 0.2032)
		(layer "F.Cu")
		(net "GND")
	)
	(segment
		(start 156.12067 100.63688)
		(end 156.12067 100.58189)
		(width 0.2032)
		(layer "F.Cu")
		(net "GND")
	)
	(segment
		(start 164.64668 135.19186)
		(end 164.64668 135.13688)
		(width 0.2032)
		(layer "F.Cu")
		(net "GND")
	)
	(segment
		(start 70.1216 103.1162)
		(end 70.6716 103.1162)
		(width 0.2032)
		(layer "F.Cu")
		(net "GND")
	)
	(segment
		(start 113.83072 90.3162)
		(end 114.18072 90.6662)
		(width 0.254)
		(layer "F.Cu")
		(net "GND")
	)
	(segment
		(start 136.41149 112.72071)
		(end 136.41451 112.71769)
		(width 0.2032)
		(layer "F.Cu")
		(net "GND")
	)
	(segment
		(start 113.1216 82.4162)
		(end 113.1216 80.91363)
		(width 0.254)
		(layer "F.Cu")
		(net "GND")
	)
	(segment
		(start 77.19563 134.1412)
		(end 77.19563 133.1162)
		(width 0.2032)
		(layer "F.Cu")
		(net "GND")
	)
	(segment
		(start 194.1216 121.8162)
		(end 194.1216 121.0912)
		(width 0.2032)
		(layer "F.Cu")
		(net "GND")
	)
	(segment
		(start 142.09943 104.7162)
		(end 142.9216 104.7162)
		(width 0.2032)
		(layer "F.Cu")
		(net "GND")
	)
	(segment
		(start 111.98072 83.51278)
		(end 112.59135 84.1234)
		(width 0.254)
		(layer "F.Cu")
		(net "GND")
	)
	(segment
		(start 118.5216 79.1162)
		(end 119.5216 79.1162)
		(width 0.2032)
		(layer "F.Cu")
		(net "GND")
	)
	(segment
		(start 86.70687 87.26371)
		(end 86.70687 87.0137)
		(width 0.254)
		(layer "F.Cu")
		(net "GND")
	)
	(segment
		(start 136.41964 125.22872)
		(end 137.80332 125.22872)
		(width 0.2032)
		(layer "F.Cu")
		(net "GND")
	)
	(segment
		(start 160.3216 83.8662)
		(end 161.7911 83.8662)
		(width 0.762)
		(layer "F.Cu")
		(net "GND")
	)
	(segment
		(start 116.3216 56.2412)
		(end 116.3466 56.2662)
		(width 0.2032)
		(layer "F.Cu")
		(net "GND")
	)
	(segment
		(start 191.92375 74.5162)
		(end 193.2716 74.5162)
		(width 0.254)
		(layer "F.Cu")
		(net "GND")
	)
	(segment
		(start 104.62869 84.61749)
		(end 104.75022 84.61749)
		(width 0.254)
		(layer "F.Cu")
		(net "GND")
	)
	(segment
		(start 169.04668 139.59186)
		(end 169.14668 139.49186)
		(width 0.2032)
		(layer "F.Cu")
		(net "GND")
	)
	(segment
		(start 185.34383 119.72602)
		(end 185.34668 119.72887)
		(width 0.2032)
		(layer "F.Cu")
		(net "GND")
	)
	(segment
		(start 163.57227 100.61247)
		(end 163.59668 100.63688)
		(width 0.2032)
		(layer "F.Cu")
		(net "GND")
	)
	(segment
		(start 161.55641 139.56654)
		(end 161.61128 139.51167)
		(width 0.254)
		(layer "F.Cu")
		(net "GND")
	)
	(segment
		(start 114.33072 84.9537)
		(end 114.33072 84.8452)
		(width 0.254)
		(layer "F.Cu")
		(net "GND")
	)
	(segment
		(start 111.0216 81.39476)
		(end 111.0216 81.38277)
		(width 0.254)
		(layer "F.Cu")
		(net "GND")
	)
	(segment
		(start 161.0724 103.28704)
		(end 161.0724 101.76915)
		(width 0.2032)
		(layer "F.Cu")
		(net "GND")
	)
	(segment
		(start 132.6241 90.4137)
		(end 132.6241 88.7187)
		(width 0.254)
		(layer "F.Cu")
		(net "GND")
	)
	(segment
		(start 169.04668 140.93687)
		(end 169.04668 139.59186)
		(width 0.2032)
		(layer "F.Cu")
		(net "GND")
	)
	(segment
		(start 136.43486 120.24394)
		(end 137.81614 120.24394)
		(width 0.2032)
		(layer "F.Cu")
		(net "GND")
	)
	(segment
		(start 139.08148 115.22927)
		(end 139.08582 115.22493)
		(width 0.2032)
		(layer "F.Cu")
		(net "GND")
	)
	(segment
		(start 138.90368 122.43627)
		(end 138.95866 122.43627)
		(width 0.2032)
		(layer "F.Cu")
		(net "GND")
	)
	(segment
		(start 104.62869 86.69208)
		(end 104.62869 84.61749)
		(width 0.254)
		(layer "F.Cu")
		(net "GND")
	)
	(segment
		(start 113.83072 90.3162)
		(end 113.83072 89.5787)
		(width 0.254)
		(layer "F.Cu")
		(net "GND")
	)
	(segment
		(start 131.8482 154.2818)
		(end 133.21764 154.2818)
		(width 0.508)
		(layer "F.Cu")
		(net "GND")
	)
	(segment
		(start 112.63792 84.1234)
		(end 112.83072 84.3162)
		(width 0.254)
		(layer "F.Cu")
		(net "GND")
	)
	(segment
		(start 186.84668 122.23688)
		(end 186.85359 122.22996)
		(width 0.2032)
		(layer "F.Cu")
		(net "GND")
	)
	(segment
		(start 106.57869 88.74208)
		(end 107.69929 88.74208)
		(width 0.254)
		(layer "F.Cu")
		(net "GND")
	)
	(segment
		(start 186.85359 122.22996)
		(end 188.07706 122.22996)
		(width 0.2032)
		(layer "F.Cu")
		(net "GND")
	)
	(segment
		(start 172.8716 110.8162)
		(end 173.7216 110.8162)
		(width 0.254)
		(layer "F.Cu")
		(net "GND")
	)
	(segment
		(start 156.54663 135.13692)
		(end 156.54668 135.13688)
		(width 0.2032)
		(layer "F.Cu")
		(net "GND")
	)
	(segment
		(start 114.9216 73.8162)
		(end 114.9216 73.7662)
		(width 0.2032)
		(layer "F.Cu")
		(net "GND")
	)
	(segment
		(start 114.8216 81.5162)
		(end 114.8216 81.48277)
		(width 0.254)
		(layer "F.Cu")
		(net "GND")
	)
	(segment
		(start 216.9716 130.7412)
		(end 217.0216 130.7412)
		(width 0.2032)
		(layer "F.Cu")
		(net "GND")
	)
	(segment
		(start 124.49973 157.71574)
		(end 124.49973 154.55673)
		(width 0.508)
		(layer "F.Cu")
		(net "GND")
	)
	(segment
		(start 216.4216 130.7412)
		(end 216.4716 130.7412)
		(width 0.2032)
		(layer "F.Cu")
		(net "GND")
	)
	(segment
		(start 124.2716 154.3286)
		(end 124.49973 154.55673)
		(width 0.508)
		(layer "F.Cu")
		(net "GND")
	)
	(segment
		(start 109.4716 67.7286)
		(end 109.48401 67.7162)
		(width 0.762)
		(layer "F.Cu")
		(net "GND")
	)
	(segment
		(start 177.47371 144.84763)
		(end 178.68261 144.84763)
		(width 0.254)
		(layer "F.Cu")
		(net "GND")
	)
	(segment
		(start 169.14668 139.49186)
		(end 169.14668 139.43687)
		(width 0.2032)
		(layer "F.Cu")
		(net "GND")
	)
	(segment
		(start 156.8216 129.5162)
		(end 157.6716 129.5162)
		(width 0.2032)
		(layer "F.Cu")
		(net "GND")
	)
	(segment
		(start 166.03535 103.29673)
		(end 166.03535 101.82555)
		(width 0.2032)
		(layer "F.Cu")
		(net "GND")
	)
	(segment
		(start 225.9216 121.4162)
		(end 226.7216 121.4162)
		(width 0.254)
		(layer "F.Cu")
		(net "GND")
	)
	(segment
		(start 186.84668 119.72887)
		(end 186.84953 119.72602)
		(width 0.2032)
		(layer "F.Cu")
		(net "GND")
	)
	(segment
		(start 136.44022 156.99725)
		(end 136.52157 157.0786)
		(width 0.508)
		(layer "F.Cu")
		(net "GND")
	)
	(segment
		(start 229.6216 125.0912)
		(end 229.6216 123.1162)
		(width 0.254)
		(layer "F.Cu")
		(net "GND")
	)
	(segment
		(start 93.72286 90.56371)
		(end 93.72286 88.8887)
		(width 0.254)
		(layer "F.Cu")
		(net "GND")
	)
	(segment
		(start 161.55641 140.9135)
		(end 161.55641 139.56654)
		(width 0.254)
		(layer "F.Cu")
		(net "GND")
	)
	(segment
		(start 112.59135 84.1234)
		(end 112.63792 84.1234)
		(width 0.254)
		(layer "F.Cu")
		(net "GND")
	)
	(segment
		(start 186.90166 125.03247)
		(end 187.1876 124.74654)
		(width 0.2032)
		(layer "F.Cu")
		(net "GND")
	)
	(segment
		(start 185.33977 112.22997)
		(end 185.34668 112.23688)
		(width 0.2032)
		(layer "F.Cu")
		(net "GND")
	)
	(segment
		(start 136.41149 117.7207)
		(end 136.4126 117.71959)
		(width 0.2032)
		(layer "F.Cu")
		(net "GND")
	)
	(segment
		(start 210.22607 144.91546)
		(end 211.2416 144.91546)
		(width 0.254)
		(layer "F.Cu")
		(net "GND")
	)
	(segment
		(start 166.03535 103.29673)
		(end 166.04902 103.31041)
		(width 0.2032)
		(layer "F.Cu")
		(net "GND")
	)
	(segment
		(start 137.81614 120.24394)
		(end 137.84667 120.27447)
		(width 0.2032)
		(layer "F.Cu")
		(net "GND")
	)
	(segment
		(start 114.33272 84.8432)
		(end 114.43493 84.8432)
		(width 0.254)
		(layer "F.Cu")
		(net "GND")
	)
	(segment
		(start 154.8216 117.68242)
		(end 154.8216 116.8162)
		(width 0.2032)
		(layer "F.Cu")
		(net "GND")
	)
	(segment
		(start 140.42772 154.87014)
		(end 140.42772 154.87014)
		(width 0.508)
		(layer "F.Cu")
		(net "GND")
	)
	(segment
		(start 105.92869 86.69208)
		(end 105.92869 85.59208)
		(width 0.254)
		(layer "F.Cu")
		(net "GND")
	)
	(segment
		(start 186.85352 114.73003)
		(end 188.07713 114.73003)
		(width 0.2032)
		(layer "F.Cu")
		(net "GND")
	)
	(segment
		(start 132.52158 157.0786)
		(end 132.52158 154.60118)
		(width 0.508)
		(layer "F.Cu")
		(net "GND")
	)
	(segment
		(start 109.8216 81.61748)
		(end 109.8216 81.61748)
		(width 0.254)
		(layer "F.Cu")
		(net "GND")
	)
	(segment
		(start 156.54663 136.88705)
		(end 156.54663 135.13692)
		(width 0.2032)
		(layer "F.Cu")
		(net "GND")
	)
	(segment
		(start 185.03737 124.72317)
		(end 185.34668 125.03247)
		(width 0.2032)
		(layer "F.Cu")
		(net "GND")
	)
	(segment
		(start 169.42457 89.2162)
		(end 169.42457 87.75622)
		(width 0.254)
		(layer "F.Cu")
		(net "GND")
	)
	(segment
		(start 207.96803 129.31977)
		(end 207.9716 129.3162)
		(width 0.254)
		(layer "F.Cu")
		(net "GND")
	)
	(segment
		(start 166.02168 101.81187)
		(end 166.03535 101.82555)
		(width 0.2032)
		(layer "F.Cu")
		(net "GND")
	)
	(segment
		(start 210.9716 130.6412)
		(end 210.9716 129.3162)
		(width 0.254)
		(layer "F.Cu")
		(net "GND")
	)
	(segment
		(start 167.54655 136.8871)
		(end 167.54655 135.39198)
		(width 0.2032)
		(layer "F.Cu")
		(net "GND")
	)
	(segment
		(start 230.85084 106.25995)
		(end 230.85283 106.25995)
		(width 0.762)
		(layer "F.Cu")
		(net "GND")
	)
	(segment
		(start 189.19017 145.04763)
		(end 190.0576 145.04763)
		(width 0.254)
		(layer "F.Cu")
		(net "GND")
	)
	(segment
		(start 140.42772 154.87014)
		(end 140.42772 154.87014)
		(width 0.508)
		(layer "F.Cu")
		(net "GND")
	)
	(segment
		(start 218.5216 130.7412)
		(end 218.5716 130.7412)
		(width 0.762)
		(layer "F.Cu")
		(net "GND")
	)
	(segment
		(start 164.54656 136.8871)
		(end 164.54656 135.29198)
		(width 0.2032)
		(layer "F.Cu")
		(net "GND")
	)
	(segment
		(start 129.25657 116.24891)
		(end 130.22637 116.24891)
		(width 0.254)
		(layer "F.Cu")
		(net "GND")
	)
	(segment
		(start 140.4379 120.24394)
		(end 140.46126 120.22057)
		(width 0.2032)
		(layer "F.Cu")
		(net "GND")
	)
	(segment
		(start 166.14668 135.19186)
		(end 166.14668 135.13688)
		(width 0.2032)
		(layer "F.Cu")
		(net "GND")
	)
	(via
		(at 114.8216 60.2162)
		(size 0.4064)
		(drill 0.2032)
		(layers "F.Cu" "B.Cu")
		(net "GND")
	)
	(via
		(at 219.9216 128.8162)
		(size 0.4064)
		(drill 0.2032)
		(layers "F.Cu" "B.Cu")
		(net "GND")
	)
	(via
		(at 77.19563 133.1162)
		(size 0.4064)
		(drill 0.2032)
		(layers "F.Cu" "B.Cu")
		(tenting
			(front yes)
			(back yes)
		)
		(net "GND")
	)
	(via
		(at 114.9216 75.3162)
		(size 0.4064)
		(drill 0.2032)
		(layers "F.Cu" "B.Cu")
		(net "GND")
	)
	(via
		(at 139.9216 152.9162)
		(size 0.4064)
		(drill 0.254)
		(layers "F.Cu" "B.Cu")
		(net "GND")
	)
	(via
		(at 131.5216 152.8162)
		(size 0.4064)
		(drill 0.254)
		(layers "F.Cu" "B.Cu")
		(net "GND")
	)
	(via
		(at 103.6216 83.1162)
		(size 0.4064)
		(drill 0.2032)
		(layers "F.Cu" "B.Cu")
		(net "GND")
	)
	(via
		(at 164.64668 135.13688)
		(size 0.4064)
		(drill 0.2032)
		(layers "F.Cu" "B.Cu")
		(tenting
			(front yes)
			(back yes)
		)
		(net "GND")
	)
	(via
		(at 128.7216 149.6162)
		(size 0.4064)
		(drill 0.254)
		(layers "F.Cu" "B.Cu")
		(net "GND")
	)
	(via
		(at 77.1216 97.6162)
		(size 0.4064)
		(drill 0.254)
		(layers "F.Cu" "B.Cu")
		(net "GND")
	)
	(via
		(at 166.14668 135.13688)
		(size 0.4064)
		(drill 0.2032)
		(layers "F.Cu" "B.Cu")
		(tenting
			(front yes)
			(back yes)
		)
		(net "GND")
	)
	(via
		(at 92.60686 86.56371)
		(size 0.4064)
		(drill 0.2032)
		(layers "F.Cu" "B.Cu")
		(net "GND")
	)
	(via
		(at 125.7216 149.7162)
		(size 0.4064)
		(drill 0.254)
		(layers "F.Cu" "B.Cu")
		(net "GND")
	)
	(via
		(at 213.2216 141.5162)
		(size 0.4064)
		(drill 0.2032)
		(layers "F.Cu" "B.Cu")
		(net "GND")
	)
	(via
		(at 167.74668 135.13688)
		(size 0.4064)
		(drill 0.2032)
		(layers "F.Cu" "B.Cu")
		(tenting
			(front yes)
			(back yes)
		)
		(net "GND")
	)
	(via
		(at 97.4216 71.3162)
		(size 0.4064)
		(drill 0.254)
		(layers "F.Cu" "B.Cu")
		(net "GND")
	)
	(via
		(at 113.1216 82.4162)
		(size 0.4064)
		(drill 0.2032)
		(layers "F.Cu" "B.Cu")
		(net "GND")
	)
	(via
		(at 230.7216 63.1162)
		(size 0.4064)
		(drill 0.254)
		(layers "F.Cu" "B.Cu")
		(net "GND")
	)
	(via
		(at 226.6566 72.9162)
		(size 0.4064)
		(drill 0.2032)
		(layers "F.Cu" "B.Cu")
		(net "GND")
	)
	(via
		(at 110.9216 67.7162)
		(size 0.4064)
		(drill 0.2032)
		(layers "F.Cu" "B.Cu")
		(tenting
			(front yes)
			(back yes)
		)
		(net "GND")
	)
	(via
		(at 210.22607 144.91546)
		(size 0.4064)
		(drill 0.2032)
		(layers "F.Cu" "B.Cu")
		(net "GND")
	)
	(via
		(at 213.0216 124.3162)
		(size 0.4064)
		(drill 0.2032)
		(layers "F.Cu" "B.Cu")
		(net "GND")
	)
	(via
		(at 77.19563 138.1162)
		(size 0.4064)
		(drill 0.2032)
		(layers "F.Cu" "B.Cu")
		(tenting
			(front yes)
			(back yes)
		)
		(net "GND")
	)
	(via
		(at 156.8216 129.5162)
		(size 0.4064)
		(drill 0.2032)
		(layers "F.Cu" "B.Cu")
		(net "GND")
	)
	(via
		(at 162.47976 130.3162)
		(size 0.4064)
		(drill 0.2032)
		(layers "F.Cu" "B.Cu")
		(net "GND")
	)
	(via
		(at 100.3216 52.7162)
		(size 0.4064)
		(drill 0.254)
		(layers "F.Cu" "B.Cu")
		(net "GND")
	)
	(via
		(at 210.0216 69.9162)
		(size 0.4064)
		(drill 0.254)
		(layers "F.Cu" "B.Cu")
		(net "GND")
	)
	(via
		(at 165.50561 115.2162)
		(size 0.4064)
		(drill 0.2032)
		(layers "F.Cu" "B.Cu")
		(net "GND")
	)
	(via
		(at 204.9216 130.7412)
		(size 0.4064)
		(drill 0.2032)
		(layers "F.Cu" "B.Cu")
		(net "GND")
	)
	(via
		(at 186.84668 112.23688)
		(size 0.4064)
		(drill 0.2032)
		(layers "F.Cu" "B.Cu")
		(tenting
			(front yes)
			(back yes)
		)
		(net "GND")
	)
	(via
		(at 229.8216 64.2162)
		(size 0.4064)
		(drill 0.254)
		(layers "F.Cu" "B.Cu")
		(net "GND")
	)
	(via
		(at 187.6216 77.4162)
		(size 0.4064)
		(drill 0.254)
		(layers "F.Cu" "B.Cu")
		(net "GND")
	)
	(via
		(at 182.4458 81.46702)
		(size 0.4064)
		(drill 0.254)
		(layers "F.Cu" "B.Cu")
		(net "GND")
	)
	(via
		(at 131.8482 154.2818)
		(size 0.4064)
		(drill 0.2032)
		(layers "F.Cu" "B.Cu")
		(tenting
			(front yes)
			(back yes)
		)
		(net "GND")
	)
	(via
		(at 216.9216 133.83602)
		(size 0.4064)
		(drill 0.2032)
		(layers "F.Cu" "B.Cu")
		(net "GND")
	)
	(via
		(at 186.84668 117.23688)
		(size 0.4064)
		(drill 0.2032)
		(layers "F.Cu" "B.Cu")
		(tenting
			(front yes)
			(back yes)
		)
		(net "GND")
	)
	(via
		(at 100.0216 75.4162)
		(size 0.4064)
		(drill 0.254)
		(layers "F.Cu" "B.Cu")
		(net "GND")
	)
	(via
		(at 95.8981 55.9746)
		(size 0.4064)
		(drill 0.254)
		(layers "F.Cu" "B.Cu")
		(net "GND")
	)
	(via
		(at 153.595 101.81444)
		(size 0.4064)
		(drill 0.2032)
		(layers "F.Cu" "B.Cu")
		(tenting
			(front yes)
			(back yes)
		)
		(net "GND")
	)
	(via
		(at 145.4216 104.7162)
		(size 0.4064)
		(drill 0.2032)
		(layers "F.Cu" "B.Cu")
		(net "GND")
	)
	(via
		(at 124.2216 75.2787)
		(size 0.4064)
		(drill 0.2032)
		(layers "F.Cu" "B.Cu")
		(net "GND")
	)
	(via
		(at 218.5216 130.7412)
		(size 0.4064)
		(drill 0.2032)
		(layers "F.Cu" "B.Cu")
		(net "GND")
	)
	(via
		(at 210.0216 71.8162)
		(size 0.4064)
		(drill 0.254)
		(layers "F.Cu" "B.Cu")
		(net "GND")
	)
	(via
		(at 123.9216 54.6162)
		(size 0.4064)
		(drill 0.2032)
		(layers "F.Cu" "B.Cu")
		(net "GND")
	)
	(via
		(at 188.6216 97.1162)
		(size 0.4064)
		(drill 0.254)
		(layers "F.Cu" "B.Cu")
		(net "GND")
	)
	(via
		(at 230.7916 96.7462)
		(size 0.4064)
		(drill 0.2032)
		(layers "F.Cu" "B.Cu")
		(net "GND")
	)
	(via
		(at 152.6419 116.0162)
		(size 0.4064)
		(drill 0.2032)
		(layers "F.Cu" "B.Cu")
		(net "GND")
	)
	(via
		(at 114.9216 61.7162)
		(size 0.4064)
		(drill 0.2032)
		(layers "F.Cu" "B.Cu")
		(net "GND")
	)
	(via
		(at 166.09668 100.63688)
		(size 0.4064)
		(drill 0.2032)
		(layers "F.Cu" "B.Cu")
		(tenting
			(front yes)
			(back yes)
		)
		(net "GND")
	)
	(via
		(at 125.3216 53.3162)
		(size 0.4064)
		(drill 0.2032)
		(layers "F.Cu" "B.Cu")
		(net "GND")
	)
	(via
		(at 161.10467 100.63688)
		(size 0.4064)
		(drill 0.2032)
		(layers "F.Cu" "B.Cu")
		(tenting
			(front yes)
			(back yes)
		)
		(net "GND")
	)
	(via
		(at 177.47371 144.84763)
		(size 0.4064)
		(drill 0.2032)
		(layers "F.Cu" "B.Cu")
		(net "GND")
	)
	(via
		(at 159.14668 135.14685)
		(size 0.4064)
		(drill 0.2032)
		(layers "F.Cu" "B.Cu")
		(tenting
			(front yes)
			(back yes)
		)
		(net "GND")
	)
	(via
		(at 180.2316 83.79121)
		(size 0.4064)
		(drill 0.254)
		(layers "F.Cu" "B.Cu")
		(net "GND")
	)
	(via
		(at 73.53981 115.798)
		(size 0.4064)
		(drill 0.2032)
		(layers "F.Cu" "B.Cu")
		(net "GND")
	)
	(via
		(at 123.5416 154.3286)
		(size 0.4064)
		(drill 0.2032)
		(layers "F.Cu" "B.Cu")
		(tenting
			(front yes)
			(back yes)
		)
		(net "GND")
	)
	(via
		(at 198.9442 144.96546)
		(size 0.4064)
		(drill 0.2032)
		(layers "F.Cu" "B.Cu")
		(net "GND")
	)
	(via
		(at 97.70686 86.57955)
		(size 0.4064)
		(drill 0.2032)
		(layers "F.Cu" "B.Cu")
		(tenting
			(front yes)
			(back yes)
		)
		(net "GND")
	)
	(via
		(at 187.7216 78.6162)
		(size 0.4064)
		(drill 0.254)
		(layers "F.Cu" "B.Cu")
		(net "GND")
	)
	(via
		(at 206.47754 130.51373)
		(size 0.4064)
		(drill 0.2032)
		(layers "F.Cu" "B.Cu")
		(net "GND")
	)
	(via
		(at 137.81148 125.23687)
		(size 0.4064)
		(drill 0.2032)
		(layers "F.Cu" "B.Cu")
		(tenting
			(front yes)
			(back yes)
		)
		(net "GND")
	)
	(via
		(at 100.0216 74.0162)
		(size 0.4064)
		(drill 0.254)
		(layers "F.Cu" "B.Cu")
		(net "GND")
	)
	(via
		(at 179.5216 92.9162)
		(size 0.4064)
		(drill 0.254)
		(layers "F.Cu" "B.Cu")
		(net "GND")
	)
	(via
		(at 160.94667 143.52447)
		(size 0.4064)
		(drill 0.2032)
		(layers "F.Cu" "B.Cu")
		(tenting
			(front yes)
			(back yes)
		)
		(net "GND")
	)
	(via
		(at 88.9216 58.1162)
		(size 0.4064)
		(drill 0.254)
		(layers "F.Cu" "B.Cu")
		(net "GND")
	)
	(via
		(at 118.5216 79.1162)
		(size 0.4064)
		(drill 0.2032)
		(layers "F.Cu" "B.Cu")
		(net "GND")
	)
	(via
		(at 86.95686 90.06371)
		(size 0.4064)
		(drill 0.2032)
		(layers "F.Cu" "B.Cu")
		(net "GND")
	)
	(via
		(at 208.3216 131.5162)
		(size 0.4064)
		(drill 0.2032)
		(layers "F.Cu" "B.Cu")
		(net "GND")
	)
	(via
		(at 162.30042 82.0086)
		(size 0.4064)
		(drill 0.2032)
		(layers "F.Cu" "B.Cu")
		(net "GND")
	)
	(via
		(at 127.3216 149.5162)
		(size 0.4064)
		(drill 0.254)
		(layers "F.Cu" "B.Cu")
		(net "GND")
	)
	(via
		(at 88.9216 59.3162)
		(size 0.4064)
		(drill 0.254)
		(layers "F.Cu" "B.Cu")
		(net "GND")
	)
	(via
		(at 135.99148 154.1786)
		(size 0.4064)
		(drill 0.2032)
		(layers "F.Cu" "B.Cu")
		(tenting
			(front yes)
			(back yes)
		)
		(net "GND")
	)
	(via
		(at 169.14667 143.62447)
		(size 0.4064)
		(drill 0.2032)
		(layers "F.Cu" "B.Cu")
		(tenting
			(front yes)
			(back yes)
		)
		(net "GND")
	)
	(via
		(at 177.9216 85.79122)
		(size 0.4064)
		(drill 0.254)
		(layers "F.Cu" "B.Cu")
		(net "GND")
	)
	(via
		(at 93.5216 55.7162)
		(size 0.4064)
		(drill 0.254)
		(layers "F.Cu" "B.Cu")
		(net "GND")
	)
	(via
		(at 168.51368 101.80212)
		(size 0.4064)
		(drill 0.2032)
		(layers "F.Cu" "B.Cu")
		(tenting
			(front yes)
			(back yes)
		)
		(net "GND")
	)
	(via
		(at 230.3216 117.1162)
		(size 0.4064)
		(drill 0.2032)
		(layers "F.Cu" "B.Cu")
		(net "GND")
	)
	(via
		(at 94.4216 80.4162)
		(size 0.4064)
		(drill 0.2032)
		(layers "F.Cu" "B.Cu")
		(net "GND")
	)
	(via
		(at 86.5216 59.3162)
		(size 0.4064)
		(drill 0.254)
		(layers "F.Cu" "B.Cu")
		(net "GND")
	)
	(via
		(at 155.87088 92.15619)
		(size 0.4064)
		(drill 0.254)
		(layers "F.Cu" "B.Cu")
		(net "GND")
	)
	(via
		(at 160.6216 138.6162)
		(size 0.4064)
		(drill 0.2032)
		(layers "F.Cu" "B.Cu")
		(tenting
			(front yes)
			(back yes)
		)
		(net "GND")
	)
	(via
		(at 137.81148 117.71847)
		(size 0.4064)
		(drill 0.2032)
		(layers "F.Cu" "B.Cu")
		(tenting
			(front yes)
			(back yes)
		)
		(net "GND")
	)
	(via
		(at 217.0216 130.7412)
		(size 0.4064)
		(drill 0.2032)
		(layers "F.Cu" "B.Cu")
		(net "GND")
	)
	(via
		(at 99.2216 51.2162)
		(size 0.4064)
		(drill 0.254)
		(layers "F.Cu" "B.Cu")
		(net "GND")
	)
	(via
		(at 170.3216 113.8162)
		(size 0.4064)
		(drill 0.2032)
		(layers "F.Cu" "B.Cu")
		(net "GND")
	)
	(via
		(at 86.90686 82.56371)
		(size 0.4064)
		(drill 0.2032)
		(layers "F.Cu" "B.Cu")
		(net "GND")
	)
	(via
		(at 114.9216 71.7162)
		(size 0.4064)
		(drill 0.2032)
		(layers "F.Cu" "B.Cu")
		(net "GND")
	)
	(via
		(at 224.1616 144.8562)
		(size 0.4064)
		(drill 0.2032)
		(layers "F.Cu" "B.Cu")
		(net "GND")
	)
	(via
		(at 186.84668 127.23688)
		(size 0.4064)
		(drill 0.2032)
		(layers "F.Cu" "B.Cu")
		(tenting
			(front yes)
			(back yes)
		)
		(net "GND")
	)
	(via
		(at 140.3216 149.6162)
		(size 0.4064)
		(drill 0.254)
		(layers "F.Cu" "B.Cu")
		(net "GND")
	)
	(via
		(at 78.99659 126.9162)
		(size 0.4064)
		(drill 0.2032)
		(layers "F.Cu" "B.Cu")
		(net "GND")
	)
	(via
		(at 157.5216 86.1162)
		(size 0.4064)
		(drill 0.254)
		(layers "F.Cu" "B.Cu")
		(net "GND")
	)
	(via
		(at 91.2716 58.1162)
		(size 0.4064)
		(drill 0.254)
		(layers "F.Cu" "B.Cu")
		(net "GND")
	)
	(via
		(at 127.02679 154.41678)
		(size 0.4064)
		(drill 0.2032)
		(layers "F.Cu" "B.Cu")
		(tenting
			(front yes)
			(back yes)
		)
		(net "GND")
	)
	(via
		(at 161.2216 138.9162)
		(size 0.4064)
		(drill 0.254)
		(layers "F.Cu" "B.Cu")
		(net "GND")
	)
	(via
		(at 88.9216 60.5162)
		(size 0.4064)
		(drill 0.254)
		(layers "F.Cu" "B.Cu")
		(net "GND")
	)
	(via
		(at 219.01786 121.46985)
		(size 0.4064)
		(drill 0.2032)
		(layers "F.Cu" "B.Cu")
		(net "GND")
	)
	(via
		(at 175.8216 86.1162)
		(size 0.4064)
		(drill 0.254)
		(layers "F.Cu" "B.Cu")
		(net "GND")
	)
	(via
		(at 169.5216 81.4162)
		(size 0.4064)
		(drill 0.2032)
		(layers "F.Cu" "B.Cu")
		(net "GND")
	)
	(via
		(at 208.3898 123.48834)
		(size 0.4064)
		(drill 0.2032)
		(layers "F.Cu" "B.Cu")
		(net "GND")
	)
	(via
		(at 114.9216 73.8162)
		(size 0.4064)
		(drill 0.2032)
		(layers "F.Cu" "B.Cu")
		(net "GND")
	)
	(via
		(at 114.9216 64.7162)
		(size 0.4064)
		(drill 0.2032)
		(layers "F.Cu" "B.Cu")
		(net "GND")
	)
	(via
		(at 186.84668 119.72887)
		(size 0.4064)
		(drill 0.2032)
		(layers "F.Cu" "B.Cu")
		(tenting
			(front yes)
			(back yes)
		)
		(net "GND")
	)
	(via
		(at 154.14668 139.53687)
		(size 0.4064)
		(drill 0.2032)
		(layers "F.Cu" "B.Cu")
		(tenting
			(front yes)
			(back yes)
		)
		(net "GND")
	)
	(via
		(at 180.7216 92.9162)
		(size 0.4064)
		(drill 0.254)
		(layers "F.Cu" "B.Cu")
		(net "GND")
	)
	(via
		(at 185.34668 117.23688)
		(size 0.4064)
		(drill 0.2032)
		(layers "F.Cu" "B.Cu")
		(tenting
			(front yes)
			(back yes)
		)
		(net "GND")
	)
	(via
		(at 208.2216 142.8162)
		(size 0.4064)
		(drill 0.2032)
		(layers "F.Cu" "B.Cu")
		(net "GND")
	)
	(via
		(at 154.04671 135.1369)
		(size 0.4064)
		(drill 0.2032)
		(layers "F.Cu" "B.Cu")
		(tenting
			(front yes)
			(back yes)
		)
		(net "GND")
	)
	(via
		(at 185.34668 127.23688)
		(size 0.4064)
		(drill 0.2032)
		(layers "F.Cu" "B.Cu")
		(tenting
			(front yes)
			(back yes)
		)
		(net "GND")
	)
	(via
		(at 164.54667 143.62447)
		(size 0.4064)
		(drill 0.2032)
		(layers "F.Cu" "B.Cu")
		(tenting
			(front yes)
			(back yes)
		)
		(net "GND")
	)
	(via
		(at 215.4216 120.1162)
		(size 0.4064)
		(drill 0.2032)
		(layers "F.Cu" "B.Cu")
		(net "GND")
	)
	(via
		(at 166.02168 101.81187)
		(size 0.4064)
		(drill 0.2032)
		(layers "F.Cu" "B.Cu")
		(tenting
			(front yes)
			(back yes)
		)
		(net "GND")
	)
	(via
		(at 110.20504 86.6644)
		(size 0.4064)
		(drill 0.2032)
		(layers "F.Cu" "B.Cu")
		(net "GND")
	)
	(via
		(at 114.86305 56.7662)
		(size 0.4064)
		(drill 0.2032)
		(layers "F.Cu" "B.Cu")
		(net "GND")
	)
	(via
		(at 114.8216 81.5162)
		(size 0.4064)
		(drill 0.2032)
		(layers "F.Cu" "B.Cu")
		(net "GND")
	)
	(via
		(at 108.7216 75.5162)
		(size 0.4064)
		(drill 0.2032)
		(layers "F.Cu" "B.Cu")
		(net "GND")
	)
	(via
		(at 114.8216 54.7162)
		(size 0.4064)
		(drill 0.2032)
		(layers "F.Cu" "B.Cu")
		(net "GND")
	)
	(via
		(at 158.69668 100.63688)
		(size 0.4064)
		(drill 0.2032)
		(layers "F.Cu" "B.Cu")
		(tenting
			(front yes)
			(back yes)
		)
		(net "GND")
	)
	(via
		(at 209.64012 123.67896)
		(size 0.4064)
		(drill 0.2032)
		(layers "F.Cu" "B.Cu")
		(net "GND")
	)
	(via
		(at 152.1216 129.7162)
		(size 0.4064)
		(drill 0.2032)
		(layers "F.Cu" "B.Cu")
		(net "GND")
	)
	(via
		(at 158.3216 127.80128)
		(size 0.4064)
		(drill 0.2032)
		(layers "F.Cu" "B.Cu")
		(net "GND")
	)
	(via
		(at 84.1716 56.5662)
		(size 0.4064)
		(drill 0.254)
		(layers "F.Cu" "B.Cu")
		(net "GND")
	)
	(via
		(at 189.0216 78.6162)
		(size 0.4064)
		(drill 0.254)
		(layers "F.Cu" "B.Cu")
		(net "GND")
	)
	(via
		(at 166.02613 138.02987)
		(size 0.4064)
		(drill 0.2032)
		(layers "F.Cu" "B.Cu")
		(tenting
			(front yes)
			(back yes)
		)
		(net "GND")
	)
	(via
		(at 182.9216 82.1162)
		(size 0.4064)
		(drill 0.254)
		(layers "F.Cu" "B.Cu")
		(net "GND")
	)
	(via
		(at 114.18072 90.6662)
		(size 0.4064)
		(drill 0.2032)
		(layers "F.Cu" "B.Cu")
		(net "GND")
	)
	(via
		(at 114.88072 83.2662)
		(size 0.4064)
		(drill 0.2032)
		(layers "F.Cu" "B.Cu")
		(net "GND")
	)
	(via
		(at 93.70686 87.66371)
		(size 0.4064)
		(drill 0.2032)
		(layers "F.Cu" "B.Cu")
		(net "GND")
	)
	(via
		(at 112.3216 82.4162)
		(size 0.4064)
		(drill 0.2032)
		(layers "F.Cu" "B.Cu")
		(net "GND")
	)
	(via
		(at 86.70687 87.86371)
		(size 0.4064)
		(drill 0.2032)
		(layers "F.Cu" "B.Cu")
		(net "GND")
	)
	(via
		(at 135.7216 150.6162)
		(size 0.4064)
		(drill 0.254)
		(layers "F.Cu" "B.Cu")
		(net "GND")
	)
	(via
		(at 139.07095 112.75979)
		(size 0.4064)
		(drill 0.2032)
		(layers "F.Cu" "B.Cu")
		(tenting
			(front yes)
			(back yes)
		)
		(net "GND")
	)
	(via
		(at 137.83194 122.39041)
		(size 0.4064)
		(drill 0.2032)
		(layers "F.Cu" "B.Cu")
		(tenting
			(front yes)
			(back yes)
		)
		(net "GND")
	)
	(via
		(at 161.55641 139.56654)
		(size 0.4064)
		(drill 0.2032)
		(layers "F.Cu" "B.Cu")
		(tenting
			(front yes)
			(back yes)
		)
		(net "GND")
	)
	(via
		(at 178.3216 92.9162)
		(size 0.4064)
		(drill 0.254)
		(layers "F.Cu" "B.Cu")
		(net "GND")
	)
	(via
		(at 76.5216 92.5162)
		(size 0.4064)
		(drill 0.254)
		(layers "F.Cu" "B.Cu")
		(net "GND")
	)
	(via
		(at 143.7216 106.11212)
		(size 0.4064)
		(drill 0.2032)
		(layers "F.Cu" "B.Cu")
		(net "GND")
	)
	(via
		(at 90.61139 68.66847)
		(size 0.4064)
		(drill 0.2032)
		(layers "F.Cu" "B.Cu")
		(net "GND")
	)
	(via
		(at 137.98002 154.23884)
		(size 0.4064)
		(drill 0.2032)
		(layers "F.Cu" "B.Cu")
		(tenting
			(front yes)
			(back yes)
		)
		(net "GND")
	)
	(via
		(at 153.52168 100.61187)
		(size 0.4064)
		(drill 0.2032)
		(layers "F.Cu" "B.Cu")
		(tenting
			(front yes)
			(back yes)
		)
		(net "GND")
	)
	(via
		(at 179.5216 91.7162)
		(size 0.4064)
		(drill 0.254)
		(layers "F.Cu" "B.Cu")
		(net "GND")
	)
	(via
		(at 169.04668 135.13688)
		(size 0.4064)
		(drill 0.2032)
		(layers "F.Cu" "B.Cu")
		(tenting
			(front yes)
			(back yes)
		)
		(net "GND")
	)
	(via
		(at 141.9216 149.7162)
		(size 0.4064)
		(drill 0.254)
		(layers "F.Cu" "B.Cu")
		(net "GND")
	)
	(via
		(at 96.8632 57.7062)
		(size 0.4064)
		(drill 0.254)
		(layers "F.Cu" "B.Cu")
		(net "GND")
	)
	(via
		(at 168.51368 100.63669)
		(size 0.4064)
		(drill 0.2032)
		(layers "F.Cu" "B.Cu")
		(tenting
			(front yes)
			(back yes)
		)
		(net "GND")
	)
	(via
		(at 186.84668 122.23688)
		(size 0.4064)
		(drill 0.2032)
		(layers "F.Cu" "B.Cu")
		(tenting
			(front yes)
			(back yes)
		)
		(net "GND")
	)
	(via
		(at 200.5216 132.1162)
		(size 0.4064)
		(drill 0.2032)
		(layers "F.Cu" "B.Cu")
		(net "GND")
	)
	(via
		(at 153.5216 131.2068)
		(size 0.4064)
		(drill 0.2032)
		(layers "F.Cu" "B.Cu")
		(net "GND")
	)
	(via
		(at 113.1216 79.3162)
		(size 0.4064)
		(drill 0.2032)
		(layers "F.Cu" "B.Cu")
		(net "GND")
	)
	(via
		(at 123.9216 116.8162)
		(size 0.4064)
		(drill 0.2032)
		(layers "F.Cu" "B.Cu")
		(locked yes)
		(tenting
			(front yes)
			(back yes)
		)
		(net "GND")
	)
	(via
		(at 126.5216 54.8162)
		(size 0.4064)
		(drill 0.2032)
		(layers "F.Cu" "B.Cu")
		(net "GND")
	)
	(via
		(at 91.07394 70.79377)
		(size 0.4064)
		(drill 0.254)
		(layers "F.Cu" "B.Cu")
		(net "GND")
	)
	(via
		(at 126.5216 82.3162)
		(size 0.4064)
		(drill 0.2032)
		(layers "F.Cu" "B.Cu")
		(net "GND")
	)
	(via
		(at 94.80686 86.56371)
		(size 0.4064)
		(drill 0.2032)
		(layers "F.Cu" "B.Cu")
		(net "GND")
	)
	(via
		(at 185.34668 112.23688)
		(size 0.4064)
		(drill 0.2032)
		(layers "F.Cu" "B.Cu")
		(tenting
			(front yes)
			(back yes)
		)
		(net "GND")
	)
	(via
		(at 78.8216 57.8162)
		(size 0.4064)
		(drill 0.254)
		(layers "F.Cu" "B.Cu")
		(net "GND")
	)
	(via
		(at 160.3216 83.8662)
		(size 0.4064)
		(drill 0.2032)
		(layers "F.Cu" "B.Cu")
		(net "GND")
	)
	(via
		(at 198.0216 120.0162)
		(size 0.4064)
		(drill 0.2032)
		(layers "F.Cu" "B.Cu")
		(net "GND")
	)
	(via
		(at 110.1716 57.46258)
		(size 0.4064)
		(drill 0.2032)
		(layers "F.Cu" "B.Cu")
		(net "GND")
	)
	(via
		(at 139.08148 115.22927)
		(size 0.4064)
		(drill 0.2032)
		(layers "F.Cu" "B.Cu")
		(tenting
			(front yes)
			(back yes)
		)
		(net "GND")
	)
	(via
		(at 159.7216 138.5162)
		(size 0.4064)
		(drill 0.2032)
		(layers "F.Cu" "B.Cu")
		(tenting
			(front yes)
			(back yes)
		)
		(net "GND")
	)
	(via
		(at 72.65433 143.8162)
		(size 0.4064)
		(drill 0.2032)
		(layers "F.Cu" "B.Cu")
		(net "GND")
	)
	(via
		(at 167.84667 143.62447)
		(size 0.4064)
		(drill 0.2032)
		(layers "F.Cu" "B.Cu")
		(tenting
			(front yes)
			(back yes)
		)
		(net "GND")
	)
	(via
		(at 225.7216 124.9162)
		(size 0.4064)
		(drill 0.2032)
		(layers "F.Cu" "B.Cu")
		(net "GND")
	)
	(via
		(at 139.99147 154.1786)
		(size 0.4064)
		(drill 0.2032)
		(layers "F.Cu" "B.Cu")
		(tenting
			(front yes)
			(back yes)
		)
		(net "GND")
	)
	(via
		(at 171.34767 81.66165)
		(size 0.4064)
		(drill 0.2032)
		(layers "F.Cu" "B.Cu")
		(net "GND")
	)
	(via
		(at 230.85584 104.99495)
		(size 0.4064)
		(drill 0.2032)
		(layers "F.Cu" "B.Cu")
		(net "GND")
	)
	(via
		(at 192.6216 122.6162)
		(size 0.4064)
		(drill 0.2032)
		(layers "F.Cu" "B.Cu")
		(net "GND")
	)
	(via
		(at 134.0216 154.0162)
		(size 0.4064)
		(drill 0.254)
		(layers "F.Cu" "B.Cu")
		(net "GND")
	)
	(via
		(at 77.7216 140.3162)
		(size 0.4064)
		(drill 0.2032)
		(layers "F.Cu" "B.Cu")
		(net "GND")
	)
	(via
		(at 99.2216 62.1162)
		(size 0.4064)
		(drill 0.254)
		(layers "F.Cu" "B.Cu")
		(net "GND")
	)
	(via
		(at 111.98072 83.4662)
		(size 0.4064)
		(drill 0.2032)
		(layers "F.Cu" "B.Cu")
		(net "GND")
	)
	(via
		(at 179.5216 94.1162)
		(size 0.4064)
		(drill 0.254)
		(layers "F.Cu" "B.Cu")
		(net "GND")
	)
	(via
		(at 129.54159 154.35959)
		(size 0.4064)
		(drill 0.2032)
		(layers "F.Cu" "B.Cu")
		(tenting
			(front yes)
			(back yes)
		)
		(net "GND")
	)
	(via
		(at 184.5966 97.2412)
		(size 0.4064)
		(drill 0.254)
		(layers "F.Cu" "B.Cu")
		(net "GND")
	)
	(via
		(at 99.5216 71.3162)
		(size 0.4064)
		(drill 0.254)
		(layers "F.Cu" "B.Cu")
		(net "GND")
	)
	(via
		(at 185.34668 114.73688)
		(size 0.4064)
		(drill 0.2032)
		(layers "F.Cu" "B.Cu")
		(tenting
			(front yes)
			(back yes)
		)
		(net "GND")
	)
	(via
		(at 161.64668 135.13688)
		(size 0.4064)
		(drill 0.2032)
		(layers "F.Cu" "B.Cu")
		(tenting
			(front yes)
			(back yes)
		)
		(net "GND")
	)
	(via
		(at 216.4216 130.7412)
		(size 0.4064)
		(drill 0.2032)
		(layers "F.Cu" "B.Cu")
		(net "GND")
	)
	(via
		(at 87.7216 60.5162)
		(size 0.4064)
		(drill 0.254)
		(layers "F.Cu" "B.Cu")
		(net "GND")
	)
	(via
		(at 99.3216 52.7162)
		(size 0.4064)
		(drill 0.254)
		(layers "F.Cu" "B.Cu")
		(net "GND")
	)
	(via
		(at 230.85283 106.25995)
		(size 0.4064)
		(drill 0.2032)
		(layers "F.Cu" "B.Cu")
		(net "GND")
	)
	(via
		(at 92.60686 85.46371)
		(size 0.4064)
		(drill 0.2032)
		(layers "F.Cu" "B.Cu")
		(net "GND")
	)
	(via
		(at 137.81148 127.70067)
		(size 0.4064)
		(drill 0.2032)
		(layers "F.Cu" "B.Cu")
		(tenting
			(front yes)
			(back yes)
		)
		(net "GND")
	)
	(via
		(at 199.4216 130.8412)
		(size 0.4064)
		(drill 0.2032)
		(layers "F.Cu" "B.Cu")
		(net "GND")
	)
	(via
		(at 124.4216 149.7162)
		(size 0.4064)
		(drill 0.254)
		(layers "F.Cu" "B.Cu")
		(net "GND")
	)
	(via
		(at 216.27302 127.81176)
		(size 0.4064)
		(drill 0.2032)
		(layers "F.Cu" "B.Cu")
		(net "GND")
	)
	(via
		(at 85.4216 64.1412)
		(size 0.4064)
		(drill 0.2032)
		(layers "F.Cu" "B.Cu")
		(net "GND")
	)
	(via
		(at 160.4216 85.5662)
		(size 0.4064)
		(drill 0.2032)
		(layers "F.Cu" "B.Cu")
		(net "GND")
	)
	(via
		(at 163.52968 101.81187)
		(size 0.4064)
		(drill 0.2032)
		(layers "F.Cu" "B.Cu")
		(tenting
			(front yes)
			(back yes)
		)
		(net "GND")
	)
	(via
		(at 156.0216 86.0162)
		(size 0.4064)
		(drill 0.254)
		(layers "F.Cu" "B.Cu")
		(net "GND")
	)
	(via
		(at 216.6216 136.14458)
		(size 0.4064)
		(drill 0.2032)
		(layers "F.Cu" "B.Cu")
		(net "GND")
	)
	(via
		(at 76.4216 97.6162)
		(size 0.4064)
		(drill 0.254)
		(layers "F.Cu" "B.Cu")
		(net "GND")
	)
	(via
		(at 162.24667 143.72448)
		(size 0.4064)
		(drill 0.2032)
		(layers "F.Cu" "B.Cu")
		(tenting
			(front yes)
			(back yes)
		)
		(net "GND")
	)
	(via
		(at 193.3716 134.81302)
		(size 0.4064)
		(drill 0.2032)
		(layers "F.Cu" "B.Cu")
		(net "GND")
	)
	(via
		(at 161.10467 101.73688)
		(size 0.4064)
		(drill 0.2032)
		(layers "F.Cu" "B.Cu")
		(tenting
			(front yes)
			(back yes)
		)
		(net "GND")
	)
	(via
		(at 156.21867 101.86488)
		(size 0.4064)
		(drill 0.2032)
		(layers "F.Cu" "B.Cu")
		(tenting
			(front yes)
			(back yes)
		)
		(net "GND")
	)
	(via
		(at 189.19017 145.04763)
		(size 0.4064)
		(drill 0.2032)
		(layers "F.Cu" "B.Cu")
		(net "GND")
	)
	(via
		(at 194.1216 124.1412)
		(size 0.4064)
		(drill 0.2032)
		(layers "F.Cu" "B.Cu")
		(net "GND")
	)
	(via
		(at 185.34668 125.03247)
		(size 0.4064)
		(drill 0.2032)
		(layers "F.Cu" "B.Cu")
		(tenting
			(front yes)
			(back yes)
		)
		(net "GND")
	)
	(via
		(at 110.83072 85.0162)
		(size 0.4064)
		(drill 0.2032)
		(layers "F.Cu" "B.Cu")
		(net "GND")
	)
	(via
		(at 168.04667 138.42447)
		(size 0.4064)
		(drill 0.2032)
		(layers "F.Cu" "B.Cu")
		(tenting
			(front yes)
			(back yes)
		)
		(net "GND")
	)
	(via
		(at 105.92869 85.59208)
		(size 0.4064)
		(drill 0.2032)
		(layers "F.Cu" "B.Cu")
		(net "GND")
	)
	(via
		(at 167.34667 143.62447)
		(size 0.4064)
		(drill 0.2032)
		(layers "F.Cu" "B.Cu")
		(tenting
			(front yes)
			(back yes)
		)
		(net "GND")
	)
	(via
		(at 84.1716 58.1162)
		(size 0.4064)
		(drill 0.254)
		(layers "F.Cu" "B.Cu")
		(net "GND")
	)
	(via
		(at 154.8216 117.68242)
		(size 0.4064)
		(drill 0.2032)
		(layers "F.Cu" "B.Cu")
		(net "GND")
	)
	(via
		(at 210.0216 72.7162)
		(size 0.4064)
		(drill 0.254)
		(layers "F.Cu" "B.Cu")
		(net "GND")
	)
	(via
		(at 77.19563 106.1162)
		(size 0.4064)
		(drill 0.2032)
		(layers "F.Cu" "B.Cu")
		(tenting
			(front yes)
			(back yes)
		)
		(net "GND")
	)
	(via
		(at 78.3216 59.3162)
		(size 0.4064)
		(drill 0.254)
		(layers "F.Cu" "B.Cu")
		(net "GND")
	)
	(via
		(at 93.5216 57.4162)
		(size 0.4064)
		(drill 0.254)
		(layers "F.Cu" "B.Cu")
		(net "GND")
	)
	(via
		(at 113.54162 154.36162)
		(size 0.4064)
		(drill 0.2032)
		(layers "F.Cu" "B.Cu")
		(tenting
			(front yes)
			(back yes)
		)
		(net "GND")
	)
	(via
		(at 87.7216 59.3162)
		(size 0.4064)
		(drill 0.254)
		(layers "F.Cu" "B.Cu")
		(net "GND")
	)
	(via
		(at 182.5216 80.7162)
		(size 0.4064)
		(drill 0.254)
		(layers "F.Cu" "B.Cu")
		(net "GND")
	)
	(via
		(at 94.539 55.75116)
		(size 0.4064)
		(drill 0.254)
		(layers "F.Cu" "B.Cu")
		(net "GND")
	)
	(via
		(at 230.85584 107.53495)
		(size 0.4064)
		(drill 0.2032)
		(layers "F.Cu" "B.Cu")
		(net "GND")
	)
	(via
		(at 126.3216 152.8162)
		(size 0.4064)
		(drill 0.254)
		(layers "F.Cu" "B.Cu")
		(net "GND")
	)
	(via
		(at 78.34464 57.25711)
		(size 0.4064)
		(drill 0.254)
		(layers "F.Cu" "B.Cu")
		(net "GND")
	)
	(via
		(at 142.09943 104.7162)
		(size 0.4064)
		(drill 0.2032)
		(layers "F.Cu" "B.Cu")
		(net "GND")
	)
	(via
		(at 116.5566 154.3286)
		(size 0.4064)
		(drill 0.2032)
		(layers "F.Cu" "B.Cu")
		(tenting
			(front yes)
			(back yes)
		)
		(net "GND")
	)
	(via
		(at 166.2216 143.6162)
		(size 0.4064)
		(drill 0.2032)
		(layers "F.Cu" "B.Cu")
		(tenting
			(front yes)
			(back yes)
		)
		(net "GND")
	)
	(via
		(at 158.54668 101.81187)
		(size 0.4064)
		(drill 0.2032)
		(layers "F.Cu" "B.Cu")
		(tenting
			(front yes)
			(back yes)
		)
		(net "GND")
	)
	(via
		(at 94.80686 87.66371)
		(size 0.4064)
		(drill 0.2032)
		(layers "F.Cu" "B.Cu")
		(net "GND")
	)
	(via
		(at 77.19563 124.3662)
		(size 0.4064)
		(drill 0.2032)
		(layers "F.Cu" "B.Cu")
		(tenting
			(front yes)
			(back yes)
		)
		(net "GND")
	)
	(via
		(at 184.1216 82.0162)
		(size 0.4064)
		(drill 0.254)
		(layers "F.Cu" "B.Cu")
		(net "GND")
	)
	(via
		(at 95.0216 57.0162)
		(size 0.4064)
		(drill 0.254)
		(layers "F.Cu" "B.Cu")
		(net "GND")
	)
	(via
		(at 94.80686 85.46371)
		(size 0.4064)
		(drill 0.2032)
		(layers "F.Cu" "B.Cu")
		(net "GND")
	)
	(via
		(at 87.7216 58.1162)
		(size 0.4064)
		(drill 0.254)
		(layers "F.Cu" "B.Cu")
		(net "GND")
	)
	(via
		(at 155.92089 96.77419)
		(size 0.4064)
		(drill 0.254)
		(layers "F.Cu" "B.Cu")
		(net "GND")
	)
	(via
		(at 185.34668 122.23688)
		(size 0.4064)
		(drill 0.2032)
		(layers "F.Cu" "B.Cu")
		(tenting
			(front yes)
			(back yes)
		)
		(net "GND")
	)
	(via
		(at 213.20838 127.35397)
		(size 0.4064)
		(drill 0.2032)
		(layers "F.Cu" "B.Cu")
		(net "GND")
	)
	(via
		(at 115.0216 67.7162)
		(size 0.4064)
		(drill 0.2032)
		(layers "F.Cu" "B.Cu")
		(net "GND")
	)
	(via
		(at 181.7216 80.5162)
		(size 0.4064)
		(drill 0.254)
		(layers "F.Cu" "B.Cu")
		(net "GND")
	)
	(via
		(at 139.09667 120.27447)
		(size 0.4064)
		(drill 0.2032)
		(layers "F.Cu" "B.Cu")
		(tenting
			(front yes)
			(back yes)
		)
		(net "GND")
	)
	(via
		(at 178.3216 94.1162)
		(size 0.4064)
		(drill 0.254)
		(layers "F.Cu" "B.Cu")
		(net "GND")
	)
	(via
		(at 220.7216 124.4162)
		(size 0.4064)
		(drill 0.2032)
		(layers "F.Cu" "B.Cu")
		(net "GND")
	)
	(via
		(at 230.31363 116.3317)
		(size 0.4064)
		(drill 0.2032)
		(layers "F.Cu" "B.Cu")
		(net "GND")
	)
	(via
		(at 93.70686 86.56371)
		(size 0.4064)
		(drill 0.2032)
		(layers "F.Cu" "B.Cu")
		(net "GND")
	)
	(via
		(at 70.1216 103.1162)
		(size 0.4064)
		(drill 0.2032)
		(layers "F.Cu" "B.Cu")
		(tenting
			(front yes)
			(back yes)
		)
		(net "GND")
	)
	(via
		(at 207.96445 130.6025)
		(size 0.4064)
		(drill 0.2032)
		(layers "F.Cu" "B.Cu")
		(net "GND")
	)
	(via
		(at 77.2216 92.5162)
		(size 0.4064)
		(drill 0.254)
		(layers "F.Cu" "B.Cu")
		(net "GND")
	)
	(via
		(at 190.2216 86.9162)
		(size 0.4064)
		(drill 0.2032)
		(layers "F.Cu" "B.Cu")
		(net "GND")
	)
	(via
		(at 169.42457 87.75622)
		(size 0.4064)
		(drill 0.2032)
		(layers "F.Cu" "B.Cu")
		(net "GND")
	)
	(via
		(at 156.64668 139.53687)
		(size 0.4064)
		(drill 0.2032)
		(layers "F.Cu" "B.Cu")
		(tenting
			(front yes)
			(back yes)
		)
		(net "GND")
	)
	(via
		(at 110.2216 55.3162)
		(size 0.4064)
		(drill 0.254)
		(layers "F.Cu" "B.Cu")
		(net "GND")
	)
	(via
		(at 210.0216 73.6162)
		(size 0.4064)
		(drill 0.254)
		(layers "F.Cu" "B.Cu")
		(net "GND")
	)
	(via
		(at 102.1216 64.3162)
		(size 0.4064)
		(drill 0.2032)
		(layers "F.Cu" "B.Cu")
		(net "GND")
	)
	(via
		(at 159.24668 139.53687)
		(size 0.4064)
		(drill 0.2032)
		(layers "F.Cu" "B.Cu")
		(tenting
			(front yes)
			(back yes)
		)
		(net "GND")
	)
	(via
		(at 136.40433 83.1162)
		(size 0.4064)
		(drill 0.2032)
		(layers "F.Cu" "B.Cu")
		(net "GND")
	)
	(via
		(at 79.0216 100.6162)
		(size 0.4064)
		(drill 0.2032)
		(layers "F.Cu" "B.Cu")
		(net "GND")
	)
	(via
		(at 184.5966 96.19995)
		(size 0.4064)
		(drill 0.254)
		(layers "F.Cu" "B.Cu")
		(net "GND")
	)
	(via
		(at 230.3216 114.9162)
		(size 0.4064)
		(drill 0.2032)
		(layers "F.Cu" "B.Cu")
		(net "GND")
	)
	(via
		(at 86.5216 58.1162)
		(size 0.4064)
		(drill 0.254)
		(layers "F.Cu" "B.Cu")
		(net "GND")
	)
	(via
		(at 180.9216 102.8162)
		(size 0.4064)
		(drill 0.2032)
		(layers "F.Cu" "B.Cu")
		(net "GND")
	)
	(via
		(at 166.1216 139.5162)
		(size 0.4064)
		(drill 0.2032)
		(layers "F.Cu" "B.Cu")
		(tenting
			(front yes)
			(back yes)
		)
		(net "GND")
	)
	(via
		(at 115.0216 66.3162)
		(size 0.4064)
		(drill 0.2032)
		(layers "F.Cu" "B.Cu")
		(net "GND")
	)
	(via
		(at 158.3216 131.0162)
		(size 0.4064)
		(drill 0.2032)
		(layers "F.Cu" "B.Cu")
		(net "GND")
	)
	(via
		(at 154.8216 114.13156)
		(size 0.4064)
		(drill 0.2032)
		(layers "F.Cu" "B.Cu")
		(net "GND")
	)
	(via
		(at 227.4216 63.5162)
		(size 0.4064)
		(drill 0.254)
		(layers "F.Cu" "B.Cu")
		(net "GND")
	)
	(via
		(at 93.70686 82.56371)
		(size 0.4064)
		(drill 0.2032)
		(layers "F.Cu" "B.Cu")
		(tenting
			(front yes)
			(back yes)
		)
		(net "GND")
	)
	(via
		(at 123.85854 118.33825)
		(size 0.4064)
		(drill 0.2032)
		(layers "F.Cu" "B.Cu")
		(locked yes)
		(tenting
			(front yes)
			(back yes)
		)
		(net "GND")
	)
	(via
		(at 193.2716 74.5162)
		(size 0.4064)
		(drill 0.2032)
		(layers "F.Cu" "B.Cu")
		(net "GND")
	)
	(via
		(at 138.95448 127.70067)
		(size 0.4064)
		(drill 0.2032)
		(layers "F.Cu" "B.Cu")
		(tenting
			(front yes)
			(back yes)
		)
		(net "GND")
	)
	(via
		(at 98.8632 60.0162)
		(size 0.4064)
		(drill 0.254)
		(layers "F.Cu" "B.Cu")
		(net "GND")
	)
	(via
		(at 107.69929 88.74208)
		(size 0.4064)
		(drill 0.2032)
		(layers "F.Cu" "B.Cu")
		(net "GND")
	)
	(via
		(at 74.8216 105.3162)
		(size 0.4064)
		(drill 0.2032)
		(layers "F.Cu" "B.Cu")
		(net "GND")
	)
	(via
		(at 143.5466 154.1786)
		(size 0.4064)
		(drill 0.2032)
		(layers "F.Cu" "B.Cu")
		(tenting
			(front yes)
			(back yes)
		)
		(net "GND")
	)
	(via
		(at 120.3216 80.7162)
		(size 0.4064)
		(drill 0.2032)
		(layers "F.Cu" "B.Cu")
		(net "GND")
	)
	(via
		(at 127.34257 90.2162)
		(size 0.4064)
		(drill 0.2032)
		(layers "F.Cu" "B.Cu")
		(net "GND")
	)
	(via
		(at 171.1216 114.6162)
		(size 0.4064)
		(drill 0.2032)
		(layers "F.Cu" "B.Cu")
		(net "GND")
	)
	(via
		(at 111.0216 81.38277)
		(size 0.4064)
		(drill 0.2032)
		(layers "F.Cu" "B.Cu")
		(net "GND")
	)
	(via
		(at 157.4216 96.8162)
		(size 0.4064)
		(drill 0.254)
		(layers "F.Cu" "B.Cu")
		(net "GND")
	)
	(via
		(at 197.8216 121.7412)
		(size 0.4064)
		(drill 0.2032)
		(layers "F.Cu" "B.Cu")
		(net "GND")
	)
	(via
		(at 138.90368 122.43627)
		(size 0.4064)
		(drill 0.2032)
		(layers "F.Cu" "B.Cu")
		(tenting
			(front yes)
			(back yes)
		)
		(net "GND")
	)
	(via
		(at 91.2716 56.5662)
		(size 0.4064)
		(drill 0.254)
		(layers "F.Cu" "B.Cu")
		(net "GND")
	)
	(via
		(at 193.6216 132.6162)
		(size 0.4064)
		(drill 0.254)
		(layers "F.Cu" "B.Cu")
		(net "GND")
	)
	(via
		(at 139.00528 125.23687)
		(size 0.4064)
		(drill 0.2032)
		(layers "F.Cu" "B.Cu")
		(tenting
			(front yes)
			(back yes)
		)
		(net "GND")
	)
	(via
		(at 114.9216 73.2162)
		(size 0.4064)
		(drill 0.2032)
		(layers "F.Cu" "B.Cu")
		(net "GND")
	)
	(via
		(at 203.4216 130.8412)
		(size 0.4064)
		(drill 0.2032)
		(layers "F.Cu" "B.Cu")
		(net "GND")
	)
	(via
		(at 114.9216 63.2162)
		(size 0.4064)
		(drill 0.2032)
		(layers "F.Cu" "B.Cu")
		(net "GND")
	)
	(via
		(at 186.0216 97.1162)
		(size 0.4064)
		(drill 0.254)
		(layers "F.Cu" "B.Cu")
		(net "GND")
	)
	(via
		(at 164.04667 143.62447)
		(size 0.4064)
		(drill 0.2032)
		(layers "F.Cu" "B.Cu")
		(tenting
			(front yes)
			(back yes)
		)
		(net "GND")
	)
	(via
		(at 230.13531 118.6162)
		(size 0.4064)
		(drill 0.2032)
		(layers "F.Cu" "B.Cu")
		(net "GND")
	)
	(via
		(at 93.72286 90.56371)
		(size 0.4064)
		(drill 0.2032)
		(layers "F.Cu" "B.Cu")
		(tenting
			(front yes)
			(back yes)
		)
		(net "GND")
	)
	(via
		(at 170.3216 115.4162)
		(size 0.4064)
		(drill 0.2032)
		(layers "F.Cu" "B.Cu")
		(net "GND")
	)
	(via
		(at 132.5216 149.5162)
		(size 0.4064)
		(drill 0.254)
		(layers "F.Cu" "B.Cu")
		(net "GND")
	)
	(via
		(at 210.9216 130.6412)
		(size 0.4064)
		(drill 0.2032)
		(layers "F.Cu" "B.Cu")
		(net "GND")
	)
	(via
		(at 130.7216 116.8162)
		(size 0.4064)
		(drill 0.2032)
		(layers "F.Cu" "B.Cu")
		(net "GND")
	)
	(via
		(at 100.3216 51.2162)
		(size 0.4064)
		(drill 0.254)
		(layers "F.Cu" "B.Cu")
		(net "GND")
	)
	(via
		(at 77.19563 111.1162)
		(size 0.4064)
		(drill 0.2032)
		(layers "F.Cu" "B.Cu")
		(tenting
			(front yes)
			(back yes)
		)
		(net "GND")
	)
	(via
		(at 156.54668 135.13688)
		(size 0.4064)
		(drill 0.2032)
		(layers "F.Cu" "B.Cu")
		(tenting
			(front yes)
			(back yes)
		)
		(net "GND")
	)
	(via
		(at 179.7216 84.4162)
		(size 0.4064)
		(drill 0.254)
		(layers "F.Cu" "B.Cu")
		(net "GND")
	)
	(via
		(at 78.8216 60.3162)
		(size 0.4064)
		(drill 0.254)
		(layers "F.Cu" "B.Cu")
		(net "GND")
	)
	(via
		(at 180.3216 83.0162)
		(size 0.4064)
		(drill 0.254)
		(layers "F.Cu" "B.Cu")
		(net "GND")
	)
	(via
		(at 162.7216 128.4162)
		(size 0.4064)
		(drill 0.2032)
		(layers "F.Cu" "B.Cu")
		(net "GND")
	)
	(via
		(at 92.60686 87.66371)
		(size 0.4064)
		(drill 0.2032)
		(layers "F.Cu" "B.Cu")
		(net "GND")
	)
	(via
		(at 126.5216 75.2162)
		(size 0.4064)
		(drill 0.2032)
		(layers "F.Cu" "B.Cu")
		(net "GND")
	)
	(via
		(at 224.27888 124.97422)
		(size 0.4064)
		(drill 0.2032)
		(layers "F.Cu" "B.Cu")
		(net "GND")
	)
	(via
		(at 137.84667 120.27447)
		(size 0.4064)
		(drill 0.2032)
		(layers "F.Cu" "B.Cu")
		(tenting
			(front yes)
			(back yes)
		)
		(net "GND")
	)
	(via
		(at 138.0216 149.9162)
		(size 0.4064)
		(drill 0.254)
		(layers "F.Cu" "B.Cu")
		(net "GND")
	)
	(via
		(at 156.8216 86.1162)
		(size 0.4064)
		(drill 0.254)
		(layers "F.Cu" "B.Cu")
		(net "GND")
	)
	(via
		(at 98.9216 74.0162)
		(size 0.4064)
		(drill 0.254)
		(layers "F.Cu" "B.Cu")
		(net "GND")
	)
	(via
		(at 84.8216 66.3162)
		(size 0.4064)
		(drill 0.2032)
		(layers "F.Cu" "B.Cu")
		(net "GND")
	)
	(via
		(at 139.00528 117.71847)
		(size 0.4064)
		(drill 0.2032)
		(layers "F.Cu" "B.Cu")
		(tenting
			(front yes)
			(back yes)
		)
		(net "GND")
	)
	(via
		(at 201.1216 120.1162)
		(size 0.4064)
		(drill 0.2032)
		(layers "F.Cu" "B.Cu")
		(net "GND")
	)
	(via
		(at 155.85422 91.306)
		(size 0.4064)
		(drill 0.254)
		(layers "F.Cu" "B.Cu")
		(net "GND")
	)
	(via
		(at 185.34668 119.72887)
		(size 0.4064)
		(drill 0.2032)
		(layers "F.Cu" "B.Cu")
		(tenting
			(front yes)
			(back yes)
		)
		(net "GND")
	)
	(via
		(at 229.6216 63.2162)
		(size 0.4064)
		(drill 0.254)
		(layers "F.Cu" "B.Cu")
		(net "GND")
	)
	(via
		(at 162.74667 143.62447)
		(size 0.4064)
		(drill 0.2032)
		(layers "F.Cu" "B.Cu")
		(tenting
			(front yes)
			(back yes)
		)
		(net "GND")
	)
	(via
		(at 183.0716 94.1162)
		(size 0.4064)
		(drill 0.254)
		(layers "F.Cu" "B.Cu")
		(net "GND")
	)
	(via
		(at 229.38529 132.0162)
		(size 0.4064)
		(drill 0.2032)
		(layers "F.Cu" "B.Cu")
		(net "GND")
	)
	(via
		(at 175.4216 87.1162)
		(size 0.4064)
		(drill 0.254)
		(layers "F.Cu" "B.Cu")
		(net "GND")
	)
	(via
		(at 173.7216 110.8162)
		(size 0.4064)
		(drill 0.2032)
		(layers "F.Cu" "B.Cu")
		(net "GND")
	)
	(via
		(at 230.8916 99.2862)
		(size 0.4064)
		(drill 0.2032)
		(layers "F.Cu" "B.Cu")
		(net "GND")
	)
	(via
		(at 110.68072 89.9662)
		(size 0.4064)
		(drill 0.2032)
		(layers "F.Cu" "B.Cu")
		(net "GND")
	)
	(via
		(at 187.8216 97.1162)
		(size 0.4064)
		(drill 0.254)
		(layers "F.Cu" "B.Cu")
		(net "GND")
	)
	(via
		(at 169.14668 139.43687)
		(size 0.4064)
		(drill 0.2032)
		(layers "F.Cu" "B.Cu")
		(tenting
			(front yes)
			(back yes)
		)
		(net "GND")
	)
	(via
		(at 162.9216 139.6162)
		(size 0.4064)
		(drill 0.254)
		(layers "F.Cu" "B.Cu")
		(net "GND")
	)
	(via
		(at 197.9216 130.8412)
		(size 0.4064)
		(drill 0.2032)
		(layers "F.Cu" "B.Cu")
		(net "GND")
	)
	(via
		(at 135.7216 152.8162)
		(size 0.4064)
		(drill 0.254)
		(layers "F.Cu" "B.Cu")
		(net "GND")
	)
	(via
		(at 111.9216 59.7162)
		(size 0.4064)
		(drill 0.2032)
		(layers "F.Cu" "B.Cu")
		(tenting
			(front yes)
			(back yes)
		)
		(net "GND")
	)
	(via
		(at 186.9216 97.1162)
		(size 0.4064)
		(drill 0.254)
		(layers "F.Cu" "B.Cu")
		(net "GND")
	)
	(via
		(at 224.2416 134.6962)
		(size 0.4064)
		(drill 0.2032)
		(layers "F.Cu" "B.Cu")
		(net "GND")
	)
	(via
		(at 222.8216 129.3162)
		(size 0.4064)
		(drill 0.2032)
		(layers "F.Cu" "B.Cu")
		(net "GND")
	)
	(via
		(at 77.19563 119.3662)
		(size 0.4064)
		(drill 0.2032)
		(layers "F.Cu" "B.Cu")
		(tenting
			(front yes)
			(back yes)
		)
		(net "GND")
	)
	(via
		(at 106.5216 75.2162)
		(size 0.4064)
		(drill 0.2032)
		(layers "F.Cu" "B.Cu")
		(net "GND")
	)
	(via
		(at 122.1216 79.1162)
		(size 0.4064)
		(drill 0.2032)
		(layers "F.Cu" "B.Cu")
		(net "GND")
	)
	(via
		(at 227.5216 64.8162)
		(size 0.4064)
		(drill 0.254)
		(layers "F.Cu" "B.Cu")
		(net "GND")
	)
	(via
		(at 137.88768 112.71467)
		(size 0.4064)
		(drill 0.2032)
		(layers "F.Cu" "B.Cu")
		(tenting
			(front yes)
			(back yes)
		)
		(net "GND")
	)
	(via
		(at 77.8216 97.6162)
		(size 0.4064)
		(drill 0.254)
		(layers "F.Cu" "B.Cu")
		(net "GND")
	)
	(via
		(at 185.2216 81.4162)
		(size 0.4064)
		(drill 0.254)
		(layers "F.Cu" "B.Cu")
		(net "GND")
	)
	(via
		(at 132.6216 90.4162)
		(size 0.4064)
		(drill 0.2032)
		(layers "F.Cu" "B.Cu")
		(net "GND")
	)
	(via
		(at 99.5216 70.3162)
		(size 0.4064)
		(drill 0.254)
		(layers "F.Cu" "B.Cu")
		(net "GND")
	)
	(via
		(at 120.18072 84.9562)
		(size 0.4064)
		(drill 0.254)
		(layers "F.Cu" "B.Cu")
		(net "GND")
	)
	(via
		(at 156.12067 100.63688)
		(size 0.4064)
		(drill 0.2032)
		(layers "F.Cu" "B.Cu")
		(tenting
			(front yes)
			(back yes)
		)
		(net "GND")
	)
	(via
		(at 219.8216 124.4162)
		(size 0.4064)
		(drill 0.2032)
		(layers "F.Cu" "B.Cu")
		(net "GND")
	)
	(via
		(at 78.0216 92.5162)
		(size 0.4064)
		(drill 0.254)
		(layers "F.Cu" "B.Cu")
		(net "GND")
	)
	(via
		(at 83.33158 84.34655)
		(size 0.4064)
		(drill 0.2032)
		(layers "F.Cu" "B.Cu")
		(net "GND")
	)
	(via
		(at 223.3216 75.4162)
		(size 0.4064)
		(drill 0.2032)
		(layers "F.Cu" "B.Cu")
		(net "GND")
	)
	(via
		(at 163.59668 100.63688)
		(size 0.4064)
		(drill 0.2032)
		(layers "F.Cu" "B.Cu")
		(tenting
			(front yes)
			(back yes)
		)
		(net "GND")
	)
	(via
		(at 186.84668 125.03247)
		(size 0.4064)
		(drill 0.2032)
		(layers "F.Cu" "B.Cu")
		(tenting
			(front yes)
			(back yes)
		)
		(net "GND")
	)
	(via
		(at 81.04219 113.2662)
		(size 0.4064)
		(drill 0.2032)
		(layers "F.Cu" "B.Cu")
		(net "GND")
	)
	(via
		(at 138.8534 82.50065)
		(size 0.4064)
		(drill 0.2032)
		(layers "F.Cu" "B.Cu")
		(net "GND")
	)
	(via
		(at 175.8216 86.7162)
		(size 0.4064)
		(drill 0.254)
		(layers "F.Cu" "B.Cu")
		(net "GND")
	)
	(via
		(at 137.91308 115.20387)
		(size 0.4064)
		(drill 0.2032)
		(layers "F.Cu" "B.Cu")
		(tenting
			(front yes)
			(back yes)
		)
		(net "GND")
	)
	(via
		(at 114.8216 56.2162)
		(size 0.4064)
		(drill 0.2032)
		(layers "F.Cu" "B.Cu")
		(net "GND")
	)
	(via
		(at 162.94576 138.37131)
		(size 0.4064)
		(drill 0.254)
		(layers "F.Cu" "B.Cu")
		(net "GND")
	)
	(via
		(at 189.0216 77.4162)
		(size 0.4064)
		(drill 0.254)
		(layers "F.Cu" "B.Cu")
		(net "GND")
	)
	(via
		(at 163.04669 135.13688)
		(size 0.4064)
		(drill 0.2032)
		(layers "F.Cu" "B.Cu")
		(tenting
			(front yes)
			(back yes)
		)
		(net "GND")
	)
	(via
		(at 210.0216 70.8162)
		(size 0.4064)
		(drill 0.254)
		(layers "F.Cu" "B.Cu")
		(net "GND")
	)
	(via
		(at 153.5216 128.23384)
		(size 0.4064)
		(drill 0.2032)
		(layers "F.Cu" "B.Cu")
		(net "GND")
	)
	(via
		(at 199.9716 130.79975)
		(size 0.4064)
		(drill 0.2032)
		(layers "F.Cu" "B.Cu")
		(net "GND")
	)
	(via
		(at 185.0216 82.1162)
		(size 0.4064)
		(drill 0.254)
		(layers "F.Cu" "B.Cu")
		(net "GND")
	)
	(via
		(at 102.0216 67.12863)
		(size 0.4064)
		(drill 0.2032)
		(layers "F.Cu" "B.Cu")
		(net "GND")
	)
	(via
		(at 209.55931 127.41131)
		(size 0.4064)
		(drill 0.2032)
		(layers "F.Cu" "B.Cu")
		(net "GND")
	)
	(via
		(at 230.85084 108.79995)
		(size 0.4064)
		(drill 0.2032)
		(layers "F.Cu" "B.Cu")
		(net "GND")
	)
	(via
		(at 97.4216 70.3162)
		(size 0.4064)
		(drill 0.254)
		(layers "F.Cu" "B.Cu")
		(net "GND")
	)
	(via
		(at 178.3216 91.7162)
		(size 0.4064)
		(drill 0.254)
		(layers "F.Cu" "B.Cu")
		(net "GND")
	)
	(via
		(at 173.33362 114.9412)
		(size 0.4064)
		(drill 0.2032)
		(layers "F.Cu" "B.Cu")
		(net "GND")
	)
	(via
		(at 120.9216 83.5162)
		(size 0.4064)
		(drill 0.2032)
		(layers "F.Cu" "B.Cu")
		(net "GND")
	)
	(via
		(at 214.9216 130.7412)
		(size 0.4064)
		(drill 0.2032)
		(layers "F.Cu" "B.Cu")
		(net "GND")
	)
	(via
		(at 183.77014 97.2412)
		(size 0.4064)
		(drill 0.254)
		(layers "F.Cu" "B.Cu")
		(net "GND")
	)
	(via
		(at 133.81736 149.56971)
		(size 0.4064)
		(drill 0.254)
		(layers "F.Cu" "B.Cu")
		(net "GND")
	)
	(via
		(at 169.5216 114.6162)
		(size 0.4064)
		(drill 0.2032)
		(layers "F.Cu" "B.Cu")
		(net "GND")
	)
	(via
		(at 98.9216 75.4162)
		(size 0.4064)
		(drill 0.254)
		(layers "F.Cu" "B.Cu")
		(net "GND")
	)
	(via
		(at 209.5216 130.6412)
		(size 0.4064)
		(drill 0.2032)
		(layers "F.Cu" "B.Cu")
		(net "GND")
	)
	(via
		(at 130.0216 152.6162)
		(size 0.4064)
		(drill 0.254)
		(layers "F.Cu" "B.Cu")
		(net "GND")
	)
	(via
		(at 116.18072 87.4662)
		(size 0.4064)
		(drill 0.2032)
		(layers "F.Cu" "B.Cu")
		(net "GND")
	)
	(via
		(at 165.66821 143.74007)
		(size 0.4064)
		(drill 0.2032)
		(layers "F.Cu" "B.Cu")
		(tenting
			(front yes)
			(back yes)
		)
		(net "GND")
	)
	(via
		(at 156.7216 96.8162)
		(size 0.4064)
		(drill 0.254)
		(layers "F.Cu" "B.Cu")
		(net "GND")
	)
	(via
		(at 225.61788 117.75248)
		(size 0.4064)
		(drill 0.2032)
		(layers "F.Cu" "B.Cu")
		(net "GND")
	)
	(via
		(at 93.70686 85.46371)
		(size 0.4064)
		(drill 0.2032)
		(layers "F.Cu" "B.Cu")
		(net "GND")
	)
	(via
		(at 194.1216 121.0912)
		(size 0.4064)
		(drill 0.2032)
		(layers "F.Cu" "B.Cu")
		(net "GND")
	)
	(via
		(at 164.6216 139.5162)
		(size 0.4064)
		(drill 0.2032)
		(layers "F.Cu" "B.Cu")
		(tenting
			(front yes)
			(back yes)
		)
		(net "GND")
	)
	(via
		(at 186.84668 114.73688)
		(size 0.4064)
		(drill 0.2032)
		(layers "F.Cu" "B.Cu")
		(tenting
			(front yes)
			(back yes)
		)
		(net "GND")
	)
	(via
		(at 225.9216 120.3162)
		(size 0.4064)
		(drill 0.2032)
		(layers "F.Cu" "B.Cu")
		(net "GND")
	)
	(via
		(at 225.9216 121.4162)
		(size 0.4064)
		(drill 0.2032)
		(layers "F.Cu" "B.Cu")
		(net "GND")
	)
	(via
		(at 164.7216 138.0162)
		(size 0.4064)
		(drill 0.254)
		(layers "F.Cu" "B.Cu")
		(net "GND")
	)
	(via
		(at 220.41054 125.06419)
		(size 0.4064)
		(drill 0.2032)
		(layers "F.Cu" "B.Cu")
		(net "GND")
	)
	(via
		(at 228.5216 63.3162)
		(size 0.4064)
		(drill 0.254)
		(layers "F.Cu" "B.Cu")
		(net "GND")
	)
	(via
		(at 93.5216 56.6162)
		(size 0.4064)
		(drill 0.254)
		(layers "F.Cu" "B.Cu")
		(net "GND")
	)
	(via
		(at 109.8216 81.61748)
		(size 0.4064)
		(drill 0.2032)
		(layers "F.Cu" "B.Cu")
		(net "GND")
	)
	(via
		(at 225.32162 115.0464)
		(size 0.4064)
		(drill 0.2032)
		(layers "F.Cu" "B.Cu")
		(net "GND")
	)
	(via
		(at 120.18072 88.4762)
		(size 0.4064)
		(drill 0.254)
		(layers "F.Cu" "B.Cu")
		(net "GND")
	)
	(via
		(at 180.7216 94.1162)
		(size 0.4064)
		(drill 0.254)
		(layers "F.Cu" "B.Cu")
		(net "GND")
	)
	(arc
		(start 127.338923 154.653006)
		(mid 127.488107 154.832121)
		(end 127.541589 155.059007)
		(width 0.508)
		(layer "F.Cu")
		(net "GND")
	)
	(arc
		(start 140.302348 154.535981)
		(mid 140.395345 154.691687)
		(end 140.42772 154.870138)
		(width 0.508)
		(layer "F.Cu")
		(net "GND")
	)
	(segment
		(start 84.1716 56.5662)
		(end 84.6966 56.0412)
		(width 0.254)
		(layer "B.Cu")
		(net "GND")
	)
	(segment
		(start 168.15457 91.0162)
		(end 169.45457 91.0162)
		(width 0.254)
		(layer "B.Cu")
		(net "GND")
	)
	(segment
		(start 98.0216 70.3162)
		(end 98.0216 67.6162)
		(width 0.762)
		(layer "B.Cu")
		(net "GND")
	)
	(segment
		(start 114.89322 84.3887)
		(end 114.90572 84.4012)
		(width 0.254)
		(layer "B.Cu")
		(net "GND")
	)
	(segment
		(start 138.30404 154.38605)
		(end 138.30444 154.38644)
		(width 0.508)
		(layer "B.Cu")
		(net "GND")
	)
	(segment
		(start 112.4216 80.14809)
		(end 112.4216 80.11363)
		(width 0.254)
		(layer "B.Cu")
		(net "GND")
	)
	(segment
		(start 221.3245 124.8191)
		(end 221.8933 125.3879)
		(width 0.254)
		(layer "B.Cu")
		(net "GND")
	)
	(segment
		(start 215.80631 127.40091)
		(end 215.80631 126.90091)
		(width 0.254)
		(layer "B.Cu")
		(net "GND")
	)
	(segment
		(start 208.3216 134.4334)
		(end 208.3216 131.5162)
		(width 0.762)
		(layer "B.Cu")
		(net "GND")
	)
	(segment
		(start 225.6016 115.83602)
		(end 225.6016 115.2962)
		(width 0.254)
		(layer "B.Cu")
		(net "GND")
	)
	(segment
		(start 228.2216 115.7162)
		(end 228.8371 116.3317)
		(width 0.254)
		(layer "B.Cu")
		(net "GND")
	)
	(segment
		(start 213.21777 127.34458)
		(end 213.21777 126.42791)
		(width 0.254)
		(layer "B.Cu")
		(net "GND")
	)
	(segment
		(start 180.7216 92.9162)
		(end 181.5216 92.9162)
		(width 0.254)
		(layer "B.Cu")
		(net "GND")
	)
	(segment
		(start 184.2304 94.15)
		(end 184.3966 94.3162)
		(width 0.254)
		(layer "B.Cu")
		(net "GND")
	)
	(segment
		(start 139.41997 156.977)
		(end 139.41997 154.8823)
		(width 0.508)
		(layer "B.Cu")
		(net "GND")
	)
	(segment
		(start 182.6466 91.7912)
		(end 183.19649 91.7912)
		(width 0.254)
		(layer "B.Cu")
		(net "GND")
	)
	(segment
		(start 134.60718 156.993)
		(end 134.60718 154.72978)
		(width 0.508)
		(layer "B.Cu")
		(net "GND")
	)
	(segment
		(start 152.6419 116.0162)
		(end 154.45606 116.0162)
		(width 0.2032)
		(layer "B.Cu")
		(net "GND")
	)
	(segment
		(start 138.30444 154.38644)
		(end 138.50272 154.58472)
		(width 0.508)
		(layer "B.Cu")
		(net "GND")
	)
	(segment
		(start 197.8216 121.1162)
		(end 198.15606 121.1162)
		(width 0.254)
		(layer "B.Cu")
		(net "GND")
	)
	(segment
		(start 127.34257 90.2162)
		(end 127.34257 89.36431)
		(width 0.254)
		(layer "B.Cu")
		(net "GND")
	)
	(segment
		(start 139.41997 156.977)
		(end 139.52157 157.0786)
		(width 0.508)
		(layer "B.Cu")
		(net "GND")
	)
	(segment
		(start 193.6216 132.6162)
		(end 193.6216 132.56121)
		(width 0.2032)
		(layer "B.Cu")
		(net "GND")
	)
	(segment
		(start 143.7216 106.11212)
		(end 143.7216 105.08174)
		(width 0.2032)
		(layer "B.Cu")
		(net "GND")
	)
	(segment
		(start 110.9216 67.7162)
		(end 111.2216 67.4162)
		(width 0.762)
		(layer "B.Cu")
		(net "GND")
	)
	(segment
		(start 213.02996 125.10956)
		(end 213.02996 124.32455)
		(width 0.254)
		(layer "B.Cu")
		(net "GND")
	)
	(segment
		(start 213.2328 141.505)
		(end 213.2328 140.12161)
		(width 0.762)
		(layer "B.Cu")
		(net "GND")
	)
	(segment
		(start 223.3216 75.4162)
		(end 223.3216 75.4162)
		(width 0.254)
		(layer "B.Cu")
		(net "GND")
	)
	(segment
		(start 106.00719 75.2162)
		(end 106.5216 75.2162)
		(width 0.762)
		(layer "B.Cu")
		(net "GND")
	)
	(segment
		(start 193.50119 132.4408)
		(end 193.50119 131.78004)
		(width 0.2032)
		(layer "B.Cu")
		(net "GND")
	)
	(segment
		(start 109.87414 67.7286)
		(end 109.88655 67.7162)
		(width 0.762)
		(layer "B.Cu")
		(net "GND")
	)
	(segment
		(start 142.57795 157.02222)
		(end 142.57795 154.70118)
		(width 0.508)
		(layer "B.Cu")
		(net "GND")
	)
	(segment
		(start 114.88072 83.2662)
		(end 114.89322 83.2787)
		(width 0.254)
		(layer "B.Cu")
		(net "GND")
	)
	(segment
		(start 113.09244 79.34536)
		(end 113.1216 79.3162)
		(width 0.254)
		(layer "B.Cu")
		(net "GND")
	)
	(segment
		(start 88.5116 68.63346)
		(end 90.61139 68.63346)
		(width 0.254)
		(layer "B.Cu")
		(net "GND")
	)
	(segment
		(start 142.52156 157.0786)
		(end 142.55295 157.04721)
		(width 0.508)
		(layer "B.Cu")
		(net "GND")
	)
	(segment
		(start 90.3466 55.6412)
		(end 91.2716 56.5662)
		(width 0.254)
		(layer "B.Cu")
		(net "GND")
	)
	(segment
		(start 168.15457 94.2162)
		(end 168.15457 91.0162)
		(width 0.254)
		(layer "B.Cu")
		(net "GND")
	)
	(segment
		(start 219.74379 128.63839)
		(end 219.74379 128.15995)
		(width 0.508)
		(layer "B.Cu")
		(net "GND")
	)
	(segment
		(start 198.0216 120.0162)
		(end 198.0216 119.2162)
		(width 0.254)
		(layer "B.Cu")
		(net "GND")
	)
	(segment
		(start 220.8216 125.83428)
		(end 220.8216 125.47931)
		(width 0.254)
		(layer "B.Cu")
		(net "GND")
	)
	(segment
		(start 222.8216 129.3162)
		(end 223.06236 129.3162)
		(width 0.508)
		(layer "B.Cu")
		(net "GND")
	)
	(segment
		(start 192.6216 122.6162)
		(end 193.75606 122.6162)
		(width 0.2032)
		(layer "B.Cu")
		(net "GND")
	)
	(segment
		(start 113.09244 79.44279)
		(end 113.09244 79.34536)
		(width 0.254)
		(layer "B.Cu")
		(net "GND")
	)
	(segment
		(start 114.68036 81.6162)
		(end 114.78036 81.5162)
		(width 0.254)
		(layer "B.Cu")
		(net "GND")
	)
	(segment
		(start 135.55295 154.59725)
		(end 135.74394 154.40626)
		(width 0.508)
		(layer "B.Cu")
		(net "GND")
	)
	(segment
		(start 142.54156 157.7576)
		(end 142.55295 157.74622)
		(width 0.508)
		(layer "B.Cu")
		(net "GND")
	)
	(segment
		(start 208.3898 123.52958)
		(end 208.4616 123.60137)
		(width 0.254)
		(layer "B.Cu")
		(net "GND")
	)
	(segment
		(start 220.8216 125.83428)
		(end 221.3783 125.83428)
		(width 0.254)
		(layer "B.Cu")
		(net "GND")
	)
	(segment
		(start 110.20396 86.6644)
		(end 110.20504 86.6644)
		(width 0.254)
		(layer "B.Cu")
		(net "GND")
	)
	(segment
		(start 197.8216 121.7412)
		(end 197.8216 121.1162)
		(width 0.254)
		(layer "B.Cu")
		(net "GND")
	)
	(segment
		(start 169.45457 91.0162)
		(end 169.71457 91.0162)
		(width 0.254)
		(layer "B.Cu")
		(net "GND")
	)
	(segment
		(start 213.0216 124.3162)
		(end 213.02996 124.32455)
		(width 0.254)
		(layer "B.Cu")
		(net "GND")
	)
	(segment
		(start 216.21716 127.81176)
		(end 216.27302 127.81176)
		(width 0.254)
		(layer "B.Cu")
		(net "GND")
	)
	(segment
		(start 108.7216 75.5162)
		(end 108.7216 75.5162)
		(width 0.762)
		(layer "B.Cu")
		(net "GND")
	)
	(segment
		(start 228.18714 115.7162)
		(end 228.2216 115.7162)
		(width 0.254)
		(layer "B.Cu")
		(net "GND")
	)
	(segment
		(start 96.5216 70.3162)
		(end 96.5216 67.48277)
		(width 0.762)
		(layer "B.Cu")
		(net "GND")
	)
	(segment
		(start 127.3216 90.2162)
		(end 127.34257 90.2162)
		(width 0.254)
		(layer "B.Cu")
		(net "GND")
	)
	(segment
		(start 169.48367 114.6162)
		(end 169.5216 114.6162)
		(width 0.254)
		(layer "B.Cu")
		(net "GND")
	)
	(segment
		(start 127.89069 88.8162)
		(end 128.7716 88.8162)
		(width 0.254)
		(layer "B.Cu")
		(net "GND")
	)
	(segment
		(start 152.1216 129.7162)
		(end 153.15606 129.7162)
		(width 0.2032)
		(layer "B.Cu")
		(net "GND")
	)
	(segment
		(start 139.12239 154.58472)
		(end 139.41997 154.8823)
		(width 0.508)
		(layer "B.Cu")
		(net "GND")
	)
	(segment
		(start 209.55931 127.41131)
		(end 209.55931 127.37007)
		(width 0.254)
		(layer "B.Cu")
		(net "GND")
	)
	(segment
		(start 226.6216 72.9162)
		(end 226.6216 71.6162)
		(width 0.254)
		(layer "B.Cu")
		(net "GND")
	)
	(segment
		(start 96.90016 75.4162)
		(end 98.9216 75.4162)
		(width 0.762)
		(layer "B.Cu")
		(net "GND")
	)
	(segment
		(start 169.42457 89.4162)
		(end 169.45457 89.4162)
		(width 0.254)
		(layer "B.Cu")
		(net "GND")
	)
	(segment
		(start 84.8216 66.3162)
		(end 84.8216 66.12847)
		(width 0.254)
		(layer "B.Cu")
		(net "GND")
	)
	(segment
		(start 225.3518 115.0464)
		(end 225.6016 115.2962)
		(width 0.254)
		(layer "B.Cu")
		(net "GND")
	)
	(segment
		(start 85.4216 64.1412)
		(end 86.55491 64.1412)
		(width 0.254)
		(layer "B.Cu")
		(net "GND")
	)
	(segment
		(start 99.7216 70.3162)
		(end 99.7216 67.36217)
		(width 0.762)
		(layer "B.Cu")
		(net "GND")
	)
	(segment
		(start 114.78036 81.5162)
		(end 114.8216 81.5162)
		(width 0.254)
		(layer "B.Cu")
		(net "GND")
	)
	(segment
		(start 120.3216 80.7162)
		(end 120.3216 79.48174)
		(width 0.2032)
		(layer "B.Cu")
		(net "GND")
	)
	(segment
		(start 102.0216 67.12863)
		(end 102.0491 67.15612)
		(width 0.254)
		(layer "B.Cu")
		(net "GND")
	)
	(segment
		(start 183.19649 91.7912)
		(end 183.19649 91.7662)
		(width 0.254)
		(layer "B.Cu")
		(net "GND")
	)
	(segment
		(start 97.4216 70.3162)
		(end 98.0216 70.3162)
		(width 0.762)
		(layer "B.Cu")
		(net "GND")
	)
	(segment
		(start 126.5216 75.2162)
		(end 126.5216 74.48174)
		(width 0.254)
		(layer "B.Cu")
		(net "GND")
	)
	(segment
		(start 87.1116 68.89347)
		(end 88.5116 68.89347)
		(width 0.254)
		(layer "B.Cu")
		(net "GND")
	)
	(segment
		(start 138.50272 157.05975)
		(end 138.52157 157.0786)
		(width 0.508)
		(layer "B.Cu")
		(net "GND")
	)
	(segment
		(start 116.04815 87.4662)
		(end 116.18072 87.4662)
		(width 0.254)
		(layer "B.Cu")
		(net "GND")
	)
	(segment
		(start 215.80631 127.40091)
		(end 216.21716 127.81176)
		(width 0.254)
		(layer "B.Cu")
		(net "GND")
	)
	(segment
		(start 84.6966 56.0412)
		(end 84.6966 55.0162)
		(width 0.254)
		(layer "B.Cu")
		(net "GND")
	)
	(segment
		(start 127.34257 89.36431)
		(end 127.89069 88.8162)
		(width 0.254)
		(layer "B.Cu")
		(net "GND")
	)
	(segment
		(start 124.07407 75.2787)
		(end 124.2216 75.2787)
		(width 0.254)
		(layer "B.Cu")
		(net "GND")
	)
	(segment
		(start 221.14489 124.8191)
		(end 221.3245 124.8191)
		(width 0.254)
		(layer "B.Cu")
		(net "GND")
	)
	(segment
		(start 225.32162 115.0464)
		(end 225.3518 115.0464)
		(width 0.254)
		(layer "B.Cu")
		(net "GND")
	)
	(segment
		(start 198.0216 119.2162)
		(end 198.05606 119.2162)
		(width 0.254)
		(layer "B.Cu")
		(net "GND")
	)
	(segment
		(start 215.77331 126.86792)
		(end 215.80631 126.90091)
		(width 0.254)
		(layer "B.Cu")
		(net "GND")
	)
	(segment
		(start 134.52158 157.0786)
		(end 134.60718 156.993)
		(width 0.508)
		(layer "B.Cu")
		(net "GND")
	)
	(segment
		(start 180.30985 103.42795)
		(end 180.9216 102.8162)
		(width 0.254)
		(layer "B.Cu")
		(net "GND")
	)
	(segment
		(start 219.66362 124.57418)
		(end 219.8216 124.4162)
		(width 0.508)
		(layer "B.Cu")
		(net "GND")
	)
	(segment
		(start 220.41054 125.06825)
		(end 220.8216 125.47931)
		(width 0.254)
		(layer "B.Cu")
		(net "GND")
	)
	(segment
		(start 179.5216 91.7162)
		(end 181.83511 91.7162)
		(width 0.254)
		(layer "B.Cu")
		(net "GND")
	)
	(segment
		(start 110.26048 55.27732)
		(end 110.26048 54.92024)
		(width 0.2032)
		(layer "B.Cu")
		(net "GND")
	)
	(segment
		(start 110.2216 55.3162)
		(end 110.26048 55.27732)
		(width 0.2032)
		(layer "B.Cu")
		(net "GND")
	)
	(segment
		(start 220.41054 125.06825)
		(end 220.41054 125.06419)
		(width 0.254)
		(layer "B.Cu")
		(net "GND")
	)
	(segment
		(start 193.50119 132.4408)
		(end 193.6216 132.56121)
		(width 0.2032)
		(layer "B.Cu")
		(net "GND")
	)
	(segment
		(start 223.95733 125.00337)
		(end 224.24973 125.00337)
		(width 0.254)
		(layer "B.Cu")
		(net "GND")
	)
	(segment
		(start 135.52158 157.0786)
		(end 135.55295 157.04722)
		(width 0.508)
		(layer "B.Cu")
		(net "GND")
	)
	(segment
		(start 219.66362 125.23155)
		(end 219.66362 124.57418)
		(width 0.508)
		(layer "B.Cu")
		(net "GND")
	)
	(segment
		(start 129.54159 157.7576)
		(end 129.54159 154.35959)
		(width 0.508)
		(layer "B.Cu")
		(net "GND")
	)
	(segment
		(start 215.50606 121.4405)
		(end 215.50606 120.1162)
		(width 0.254)
		(layer "B.Cu")
		(net "GND")
	)
	(segment
		(start 181.5216 92.9162)
		(end 182.6466 91.7912)
		(width 0.254)
		(layer "B.Cu")
		(net "GND")
	)
	(segment
		(start 218.11214 121.4412)
		(end 219.01786 121.4412)
		(width 0.254)
		(layer "B.Cu")
		(net "GND")
	)
	(segment
		(start 201.43713 121.19078)
		(end 201.43713 120.1162)
		(width 0.254)
		(layer "B.Cu")
		(net "GND")
	)
	(segment
		(start 88.5116 68.89347)
		(end 88.5116 68.63346)
		(width 0.254)
		(layer "B.Cu")
		(net "GND")
	)
	(segment
		(start 112.4216 80.11363)
		(end 113.09244 79.44279)
		(width 0.254)
		(layer "B.Cu")
		(net "GND")
	)
	(segment
		(start 208.2216 141.2162)
		(end 208.5592 141.2162)
		(width 0.762)
		(layer "B.Cu")
		(net "GND")
	)
	(segment
		(start 220.74199 124.4162)
		(end 221.14489 124.8191)
		(width 0.254)
		(layer "B.Cu")
		(net "GND")
	)
	(segment
		(start 142.57795 154.70118)
		(end 143.10053 154.1786)
		(width 0.508)
		(layer "B.Cu")
		(net "GND")
	)
	(segment
		(start 124.07407 75.2787)
		(end 124.07407 74.53174)
		(width 0.254)
		(layer "B.Cu")
		(net "GND")
	)
	(segment
		(start 201.1216 120.1162)
		(end 201.43713 120.1162)
		(width 0.254)
		(layer "B.Cu")
		(net "GND")
	)
	(segment
		(start 225.6016 117.7362)
		(end 225.6016 116.83603)
		(width 0.254)
		(layer "B.Cu")
		(net "GND")
	)
	(segment
		(start 181.83511 91.7162)
		(end 181.83511 88.8162)
		(width 0.254)
		(layer "B.Cu")
		(net "GND")
	)
	(segment
		(start 123.5416 157.7576)
		(end 123.5416 154.3286)
		(width 0.508)
		(layer "B.Cu")
		(net "GND")
	)
	(segment
		(start 169.42457 89.4162)
		(end 169.42457 87.75622)
		(width 0.254)
		(layer "B.Cu")
		(net "GND")
	)
	(segment
		(start 116.04815 87.4662)
		(end 116.04815 86.68239)
		(width 0.254)
		(layer "B.Cu")
		(net "GND")
	)
	(segment
		(start 208.5592 141.2162)
		(end 208.5592 138.64087)
		(width 0.762)
		(layer "B.Cu")
		(net "GND")
	)
	(segment
		(start 213.02996 125.10956)
		(end 213.03831 125.11792)
		(width 0.254)
		(layer "B.Cu")
		(net "GND")
	)
	(segment
		(start 99.5216 70.3162)
		(end 99.7216 70.3162)
		(width 0.762)
		(layer "B.Cu")
		(net "GND")
	)
	(segment
		(start 219.01786 121.46985)
		(end 219.01786 121.4412)
		(width 0.254)
		(layer "B.Cu")
		(net "GND")
	)
	(segment
		(start 175.8216 86.7162)
		(end 177.25502 86.7162)
		(width 0.2032)
		(layer "B.Cu")
		(net "GND")
	)
	(segment
		(start 209.64012 123.67896)
		(end 209.76195 123.80078)
		(width 0.254)
		(layer "B.Cu")
		(net "GND")
	)
	(segment
		(start 96.5216 70.3162)
		(end 97.4216 70.3162)
		(width 0.762)
		(layer "B.Cu")
		(net "GND")
	)
	(segment
		(start 132.6216 90.4162)
		(end 132.6716 90.3662)
		(width 0.254)
		(layer "B.Cu")
		(net "GND")
	)
	(segment
		(start 131.54158 157.7576)
		(end 131.54158 154.58842)
		(width 0.508)
		(layer "B.Cu")
		(net "GND")
	)
	(segment
		(start 98.8632 60.0162)
		(end 98.8632 59.2162)
		(width 0.762)
		(layer "B.Cu")
		(net "GND")
	)
	(segment
		(start 134.60718 154.72978)
		(end 134.92076 154.4162)
		(width 0.508)
		(layer "B.Cu")
		(net "GND")
	)
	(segment
		(start 169.45457 91.0162)
		(end 169.45457 89.4162)
		(width 0.254)
		(layer "B.Cu")
		(net "GND")
	)
	(segment
		(start 213.2216 140.11041)
		(end 213.2216 139.0162)
		(width 0.762)
		(layer "B.Cu")
		(net "GND")
	)
	(segment
		(start 138.50272 157.05975)
		(end 138.50272 154.58472)
		(width 0.508)
		(layer "B.Cu")
		(net "GND")
	)
	(segment
		(start 221.8933 126.23428)
		(end 221.8933 125.3879)
		(width 0.254)
		(layer "B.Cu")
		(net "GND")
	)
	(segment
		(start 169.15866 114.2912)
		(end 169.48367 114.6162)
		(width 0.254)
		(layer "B.Cu")
		(net "GND")
	)
	(segment
		(start 229.2216 113.8162)
		(end 230.3216 114.9162)
		(width 0.254)
		(layer "B.Cu")
		(net "GND")
	)
	(segment
		(start 135.75388 154.4162)
		(end 135.99148 154.1786)
		(width 0.508)
		(layer "B.Cu")
		(net "GND")
	)
	(segment
		(start 132.6716 90.3662)
		(end 132.6716 88.6162)
		(width 0.254)
		(layer "B.Cu")
		(net "GND")
	)
	(segment
		(start 183.0716 94.1162)
		(end 183.6568 94.1162)
		(width 0.254)
		(layer "B.Cu")
		(net "GND")
	)
	(segment
		(start 142.55295 157.04721)
		(end 142.57795 157.02222)
		(width 0.508)
		(layer "B.Cu")
		(net "GND")
	)
	(segment
		(start 102.1216 64.3162)
		(end 102.1216 64.3162)
		(width 0.254)
		(layer "B.Cu")
		(net "GND")
	)
	(segment
		(start 156.8216 129.5162)
		(end 157.95606 129.5162)
		(width 0.2032)
		(layer "B.Cu")
		(net "GND")
	)
	(segment
		(start 180.30985 104.5162)
		(end 180.30985 103.42795)
		(width 0.254)
		(layer "B.Cu")
		(net "GND")
	)
	(segment
		(start 209.6236 127.30579)
		(end 209.6236 126.9142)
		(width 0.254)
		(layer "B.Cu")
		(net "GND")
	)
	(segment
		(start 216.6216 136.2162)
		(end 216.6216 136.14458)
		(width 0.762)
		(layer "B.Cu")
		(net "GND")
	)
	(segment
		(start 223.3216 75.4162)
		(end 224.1216 75.4162)
		(width 0.254)
		(layer "B.Cu")
		(net "GND")
	)
	(segment
		(start 110.26048 54.92024)
		(end 110.66622 54.5145)
		(width 0.2032)
		(layer "B.Cu")
		(net "GND")
	)
	(segment
		(start 134.92076 154.4162)
		(end 135.75388 154.4162)
		(width 0.508)
		(layer "B.Cu")
		(net "GND")
	)
	(segment
		(start 109.88655 67.7162)
		(end 110.9216 67.7162)
		(width 0.762)
		(layer "B.Cu")
		(net "GND")
	)
	(segment
		(start 111.2216 67.4162)
		(end 113.5216 67.4162)
		(width 0.762)
		(layer "B.Cu")
		(net "GND")
	)
	(segment
		(start 219.74379 128.63839)
		(end 219.9216 128.8162)
		(width 0.508)
		(layer "B.Cu")
		(net "GND")
	)
	(segment
		(start 98.8632 59.2162)
		(end 100.35503 59.2162)
		(width 0.762)
		(layer "B.Cu")
		(net "GND")
	)
	(segment
		(start 90.61139 68.66847)
		(end 90.61139 68.63346)
		(width 0.254)
		(layer "B.Cu")
		(net "GND")
	)
	(segment
		(start 212.6216 139.0162)
		(end 213.2216 139.0162)
		(width 0.762)
		(layer "B.Cu")
		(net "GND")
	)
	(segment
		(start 225.37414 75.4162)
		(end 225.37414 75.40021)
		(width 0.254)
		(layer "B.Cu")
		(net "GND")
	)
	(segment
		(start 126.54159 155.01903)
		(end 126.54159 155.01902)
		(width 0.508)
		(layer "B.Cu")
		(net "GND")
	)
	(segment
		(start 168.48713 114.2912)
		(end 169.15866 114.2912)
		(width 0.254)
		(layer "B.Cu")
		(net "GND")
	)
	(segment
		(start 215.4216 120.1162)
		(end 215.50606 120.1162)
		(width 0.254)
		(layer "B.Cu")
		(net "GND")
	)
	(segment
		(start 208.2216 142.8162)
		(end 208.2216 142.8162)
		(width 0.762)
		(layer "B.Cu")
		(net "GND")
	)
	(segment
		(start 183.6906 94.15)
		(end 184.2304 94.15)
		(width 0.254)
		(layer "B.Cu")
		(net "GND")
	)
	(segment
		(start 138.50272 154.58472)
		(end 139.12239 154.58472)
		(width 0.508)
		(layer "B.Cu")
		(net "GND")
	)
	(segment
		(start 126.7607 154.60117)
		(end 127.02679 154.41678)
		(width 0.508)
		(layer "B.Cu")
		(net "GND")
	)
	(segment
		(start 104.9741 74.05812)
		(end 104.9741 71.7286)
		(width 0.762)
		(layer "B.Cu")
		(net "GND")
	)
	(segment
		(start 142.55295 157.74622)
		(end 142.55295 157.04721)
		(width 0.508)
		(layer "B.Cu")
		(net "GND")
	)
	(segment
		(start 223.56155 125.43362)
		(end 223.56155 125.39916)
		(width 0.254)
		(layer "B.Cu")
		(net "GND")
	)
	(segment
		(start 223.49198 128.24729)
		(end 223.56155 128.17772)
		(width 0.508)
		(layer "B.Cu")
		(net "GND")
	)
	(segment
		(start 104.9741 74.18312)
		(end 104.9741 74.05812)
		(width 0.762)
		(layer "B.Cu")
		(net "GND")
	)
	(segment
		(start 110.20216 86.6662)
		(end 110.20396 86.6644)
		(width 0.254)
		(layer "B.Cu")
		(net "GND")
	)
	(segment
		(start 110.66622 54.5145)
		(end 110.66622 54.48004)
		(width 0.2032)
		(layer "B.Cu")
		(net "GND")
	)
	(segment
		(start 90.3466 55.6412)
		(end 90.3466 54.9162)
		(width 0.254)
		(layer "B.Cu")
		(net "GND")
	)
	(segment
		(start 226.6216 71.6162)
		(end 226.6216 70.3162)
		(width 0.254)
		(layer "B.Cu")
		(net "GND")
	)
	(segment
		(start 220.7216 124.4162)
		(end 220.74199 124.4162)
		(width 0.254)
		(layer "B.Cu")
		(net "GND")
	)
	(segment
		(start 123.9216 55.50066)
		(end 123.9216 54.6162)
		(width 0.254)
		(layer "B.Cu")
		(net "GND")
	)
	(segment
		(start 113.54162 157.7576)
		(end 113.54162 154.36162)
		(width 0.508)
		(layer "B.Cu")
		(net "GND")
	)
	(segment
		(start 223.06236 129.3162)
		(end 223.49198 128.88658)
		(width 0.508)
		(layer "B.Cu")
		(net "GND")
	)
	(segment
		(start 208.4616 124.1362)
		(end 208.4616 123.60137)
		(width 0.254)
		(layer "B.Cu")
		(net "GND")
	)
	(segment
		(start 126.5216 55.55066)
		(end 126.5216 54.8162)
		(width 0.254)
		(layer "B.Cu")
		(net "GND")
	)
	(segment
		(start 209.55931 127.37007)
		(end 209.6236 127.30579)
		(width 0.254)
		(layer "B.Cu")
		(net "GND")
	)
	(segment
		(start 108.7216 73.1686)
		(end 108.72193 73.1686)
		(width 0.762)
		(layer "B.Cu")
		(net "GND")
	)
	(segment
		(start 223.49198 128.88658)
		(end 223.49198 128.24729)
		(width 0.508)
		(layer "B.Cu")
		(net "GND")
	)
	(segment
		(start 143.10053 154.1786)
		(end 143.5466 154.1786)
		(width 0.508)
		(layer "B.Cu")
		(net "GND")
	)
	(segment
		(start 125.3216 54.05066)
		(end 125.3216 53.3162)
		(width 0.254)
		(layer "B.Cu")
		(net "GND")
	)
	(segment
		(start 110.68072 89.9662)
		(end 111.48072 89.9662)
		(width 0.254)
		(layer "B.Cu")
		(net "GND")
	)
	(segment
		(start 228.5259 113.8162)
		(end 229.2216 113.8162)
		(width 0.254)
		(layer "B.Cu")
		(net "GND")
	)
	(segment
		(start 183.6568 94.1162)
		(end 183.6906 94.15)
		(width 0.254)
		(layer "B.Cu")
		(net "GND")
	)
	(segment
		(start 224.24973 125.00337)
		(end 224.27888 124.97422)
		(width 0.254)
		(layer "B.Cu")
		(net "GND")
	)
	(segment
		(start 226.6216 70.3162)
		(end 226.8816 70.3162)
		(width 0.254)
		(layer "B.Cu")
		(net "GND")
	)
	(segment
		(start 114.86073 83.2462)
		(end 114.88072 83.2662)
		(width 0.254)
		(layer "B.Cu")
		(net "GND")
	)
	(segment
		(start 208.3216 134.4334)
		(end 208.5592 134.4334)
		(width 0.762)
		(layer "B.Cu")
		(net "GND")
	)
	(segment
		(start 209.6236 126.9142)
		(end 209.8216 126.7162)
		(width 0.254)
		(layer "B.Cu")
		(net "GND")
	)
	(segment
		(start 213.20838 127.35397)
		(end 213.21777 127.34458)
		(width 0.254)
		(layer "B.Cu")
		(net "GND")
	)
	(segment
		(start 216.9216 133.83602)
		(end 216.9216 133.8162)
		(width 0.762)
		(layer "B.Cu")
		(net "GND")
	)
	(segment
		(start 223.56155 125.39916)
		(end 223.95733 125.00337)
		(width 0.254)
		(layer "B.Cu")
		(net "GND")
	)
	(segment
		(start 208.3898 123.52958)
		(end 208.3898 123.48834)
		(width 0.254)
		(layer "B.Cu")
		(net "GND")
	)
	(segment
		(start 120.9216 83.5162)
		(end 121.0216 83.5162)
		(width 0.254)
		(layer "B.Cu")
		(net "GND")
	)
	(segment
		(start 108.7216 75.5162)
		(end 108.7216 73.1686)
		(width 0.762)
		(layer "B.Cu")
		(net "GND")
	)
	(segment
		(start 209.76195 123.80078)
		(end 210.41727 123.80078)
		(width 0.254)
		(layer "B.Cu")
		(net "GND")
	)
	(segment
		(start 114.89322 84.3887)
		(end 114.89322 83.2787)
		(width 0.254)
		(layer "B.Cu")
		(net "GND")
	)
	(segment
		(start 213.2216 141.5162)
		(end 213.2328 141.505)
		(width 0.762)
		(layer "B.Cu")
		(net "GND")
	)
	(segment
		(start 104.9741 74.18312)
		(end 106.00719 75.2162)
		(width 0.762)
		(layer "B.Cu")
		(net "GND")
	)
	(segment
		(start 208.2216 142.8162)
		(end 208.2216 141.2162)
		(width 0.762)
		(layer "B.Cu")
		(net "GND")
	)
	(segment
		(start 114.0216 81.6162)
		(end 114.68036 81.6162)
		(width 0.254)
		(layer "B.Cu")
		(net "GND")
	)
	(segment
		(start 135.55295 157.04722)
		(end 135.55295 154.59725)
		(width 0.508)
		(layer "B.Cu")
		(net "GND")
	)
	(segment
		(start 215.60331 126.86792)
		(end 215.77331 126.86792)
		(width 0.254)
		(layer "B.Cu")
		(net "GND")
	)
	(segment
		(start 123.8966 55.50066)
		(end 123.9216 55.50066)
		(width 0.254)
		(layer "B.Cu")
		(net "GND")
	)
	(segment
		(start 224.1216 75.4162)
		(end 225.37414 75.4162)
		(width 0.254)
		(layer "B.Cu")
		(net "GND")
	)
	(segment
		(start 137.98002 154.23884)
		(end 137.9806 154.23889)
		(width 0.508)
		(layer "B.Cu")
		(net "GND")
	)
	(segment
		(start 219.66155 125.23362)
		(end 219.66362 125.23155)
		(width 0.508)
		(layer "B.Cu")
		(net "GND")
	)
	(segment
		(start 228.8371 116.3317)
		(end 230.31363 116.3317)
		(width 0.254)
		(layer "B.Cu")
		(net "GND")
	)
	(segment
		(start 228.52516 132.0162)
		(end 229.38529 132.0162)
		(width 0.254)
		(layer "B.Cu")
		(net "GND")
	)
	(segment
		(start 219.66155 128.07772)
		(end 219.74379 128.15995)
		(width 0.508)
		(layer "B.Cu")
		(net "GND")
	)
	(segment
		(start 131.54158 154.58842)
		(end 131.8482 154.2818)
		(width 0.508)
		(layer "B.Cu")
		(net "GND")
	)
	(segment
		(start 213.2216 140.11041)
		(end 213.2328 140.12161)
		(width 0.762)
		(layer "B.Cu")
		(net "GND")
	)
	(segment
		(start 104.6741 71.7286)
		(end 104.9741 71.7286)
		(width 0.762)
		(layer "B.Cu")
		(net "GND")
	)
	(segment
		(start 225.6016 117.7362)
		(end 225.61788 117.75248)
		(width 0.254)
		(layer "B.Cu")
		(net "GND")
	)
	(segment
		(start 83.9116 66.12847)
		(end 84.8216 66.12847)
		(width 0.254)
		(layer "B.Cu")
		(net "GND")
	)
	(segment
		(start 96.90016 75.4162)
		(end 96.90016 74.7162)
		(width 0.762)
		(layer "B.Cu")
		(net "GND")
	)
	(segment
		(start 126.54159 157.7576)
		(end 126.54159 155.01903)
		(width 0.508)
		(layer "B.Cu")
		(net "GND")
	)
	(segment
		(start 226.6216 72.9162)
		(end 226.6566 72.9162)
		(width 0.254)
		(layer "B.Cu")
		(net "GND")
	)
	(arc
		(start 126.54159 155.019027)
		(mid 126.599689 154.783119)
		(end 126.760694 154.601169)
		(width 0.508)
		(layer "B.Cu")
		(net "GND")
	)
	(arc
		(start 137.980597 154.238883)
		(mid 138.155604 154.283261)
		(end 138.304038 154.386044)
		(width 0.508)
		(layer "B.Cu")
		(net "GND")
	)
	(segment
		(start 214.69945 145.56546)
		(end 214.75443 145.56546)
		(width 0.2032)
		(layer "F.Cu")
		(net "FPGA_TMS")
	)
	(segment
		(start 214.90443 145.71545)
		(end 215.8416 145.71545)
		(width 0.2032)
		(layer "F.Cu")
		(net "FPGA_TMS")
	)
	(segment
		(start 197.9216 146.50253)
		(end 198.16313 146.74406)
		(width 0.2032)
		(layer "F.Cu")
		(net "FPGA_TMS")
	)
	(segment
		(start 143.50051 109.8162)
		(end 149.1216 115.43729)
		(width 0.2032)
		(layer "F.Cu")
		(net "FPGA_TMS")
	)
	(segment
		(start 198.16313 146.74406)
		(end 214.35743 146.74406)
		(width 0.2032)
		(layer "F.Cu")
		(net "FPGA_TMS")
	)
	(segment
		(start 214.75443 145.56546)
		(end 214.90443 145.71545)
		(width 0.2032)
		(layer "F.Cu")
		(net "FPGA_TMS")
	)
	(segment
		(start 152.82803 123.2162)
		(end 177.5216 123.2162)
		(width 0.2032)
		(layer "F.Cu")
		(net "FPGA_TMS")
	)
	(segment
		(start 136.0216 107.4162)
		(end 139.47198 107.4162)
		(width 0.2032)
		(layer "F.Cu")
		(net "FPGA_TMS")
	)
	(segment
		(start 215.8416 145.96545)
		(end 215.8416 145.71545)
		(width 0.2032)
		(layer "F.Cu")
		(net "FPGA_TMS")
	)
	(segment
		(start 139.47198 107.4162)
		(end 141.87198 109.8162)
		(width 0.2032)
		(layer "F.Cu")
		(net "FPGA_TMS")
	)
	(segment
		(start 214.76263 146.33885)
		(end 215.4682 146.33885)
		(width 0.2032)
		(layer "F.Cu")
		(net "FPGA_TMS")
	)
	(segment
		(start 183.9216 143.5162)
		(end 196.5216 143.5162)
		(width 0.2032)
		(layer "F.Cu")
		(net "FPGA_TMS")
	)
	(segment
		(start 179.49257 139.08717)
		(end 179.49257 125.18717)
		(width 0.2032)
		(layer "F.Cu")
		(net "FPGA_TMS")
	)
	(segment
		(start 179.49257 139.08717)
		(end 183.9216 143.5162)
		(width 0.2032)
		(layer "F.Cu")
		(net "FPGA_TMS")
	)
	(segment
		(start 134.89615 110.22059)
		(end 136.41149 110.22059)
		(width 0.2032)
		(layer "F.Cu")
		(net "FPGA_TMS")
	)
	(segment
		(start 134.89615 110.22059)
		(end 134.89615 108.54165)
		(width 0.2032)
		(layer "F.Cu")
		(net "FPGA_TMS")
	)
	(segment
		(start 213.4916 145.56546)
		(end 214.69945 145.56546)
		(width 0.2032)
		(layer "F.Cu")
		(net "FPGA_TMS")
	)
	(segment
		(start 149.1216 119.50977)
		(end 152.82803 123.2162)
		(width 0.2032)
		(layer "F.Cu")
		(net "FPGA_TMS")
	)
	(segment
		(start 196.5216 143.5162)
		(end 197.9216 144.9162)
		(width 0.2032)
		(layer "F.Cu")
		(net "FPGA_TMS")
	)
	(segment
		(start 149.1216 119.50977)
		(end 149.1216 115.43729)
		(width 0.2032)
		(layer "F.Cu")
		(net "FPGA_TMS")
	)
	(segment
		(start 215.4682 146.33885)
		(end 215.8416 145.96545)
		(width 0.2032)
		(layer "F.Cu")
		(net "FPGA_TMS")
	)
	(segment
		(start 134.89615 108.54165)
		(end 136.0216 107.4162)
		(width 0.2032)
		(layer "F.Cu")
		(net "FPGA_TMS")
	)
	(segment
		(start 141.87198 109.8162)
		(end 143.50051 109.8162)
		(width 0.2032)
		(layer "F.Cu")
		(net "FPGA_TMS")
	)
	(segment
		(start 214.35743 146.74406)
		(end 214.76263 146.33885)
		(width 0.2032)
		(layer "F.Cu")
		(net "FPGA_TMS")
	)
	(segment
		(start 197.9216 146.50253)
		(end 197.9216 144.9162)
		(width 0.2032)
		(layer "F.Cu")
		(net "FPGA_TMS")
	)
	(segment
		(start 177.5216 123.2162)
		(end 179.49257 125.18717)
		(width 0.2032)
		(layer "F.Cu")
		(net "FPGA_TMS")
	)
	(via
		(at 214.69945 145.56546)
		(size 0.4064)
		(drill 0.2032)
		(layers "F.Cu" "B.Cu")
		(net "FPGA_TMS")
	)
	(segment
		(start 225.4716 114.3162)
		(end 225.4716 112.7162)
		(width 0.254)
		(layer "F.Cu")
		(net "+3.3V")
	)
	(segment
		(start 128.8166 90.1212)
		(end 128.8166 88.7162)
		(width 0.2032)
		(layer "F.Cu")
		(net "+3.3V")
	)
	(segment
		(start 108.3216 83.17365)
		(end 108.3216 78.7162)
		(width 1.27)
		(layer "F.Cu")
		(net "+3.3V")
	)
	(segment
		(start 144.5216 94.6162)
		(end 147.8216 94.6162)
		(width 1.016)
		(layer "F.Cu")
		(net "+3.3V")
	)
	(segment
		(start 143.84063 101.17057)
		(end 146.47597 101.17057)
		(width 0.2032)
		(layer "F.Cu")
		(net "+3.3V")
	)
	(segment
		(start 225.4716 111.1162)
		(end 226.7216 111.1162)
		(width 0.254)
		(layer "F.Cu")
		(net "+3.3V")
	)
	(segment
		(start 147.8216 96.0162)
		(end 148.89456 97.08916)
		(width 0.2032)
		(layer "F.Cu")
		(net "+3.3V")
	)
	(segment
		(start 75.7216 130.55066)
		(end 75.7216 129.87335)
		(width 0.2032)
		(layer "F.Cu")
		(net "+3.3V")
	)
	(segment
		(start 83.51039 83.21562)
		(end 83.72706 83.43229)
		(width 0.2032)
		(layer "F.Cu")
		(net "+3.3V")
	)
	(segment
		(start 210.22086 146.21546)
		(end 211.2416 146.21546)
		(width 0.254)
		(layer "F.Cu")
		(net "+3.3V")
	)
	(segment
		(start 88.45686 86.06371)
		(end 91.38187 86.06371)
		(width 0.2032)
		(layer "F.Cu")
		(net "+3.3V")
	)
	(segment
		(start 147.8216 96.0162)
		(end 147.8216 94.6562)
		(width 0.2032)
		(layer "F.Cu")
		(net "+3.3V")
	)
	(segment
		(start 67.39683 143.2162)
		(end 67.4466 143.2162)
		(width 0.254)
		(layer "F.Cu")
		(net "+3.3V")
	)
	(segment
		(start 117.4216 50.9162)
		(end 118.7216 52.2162)
		(width 0.254)
		(layer "F.Cu")
		(net "+3.3V")
	)
	(segment
		(start 107.8216 84.7162)
		(end 108.3216 84.2162)
		(width 0.762)
		(layer "F.Cu")
		(net "+3.3V")
	)
	(segment
		(start 80.1716 50.3662)
		(end 81.4216 50.3662)
		(width 0.2032)
		(layer "F.Cu")
		(net "+3.3V")
	)
	(segment
		(start 83.45541 83.21562)
		(end 83.51039 83.21562)
		(width 0.2032)
		(layer "F.Cu")
		(net "+3.3V")
	)
	(segment
		(start 75.6216 103.46121)
		(end 75.7982 103.28461)
		(width 0.2032)
		(layer "F.Cu")
		(net "+3.3V")
	)
	(segment
		(start 148.7216 102.9162)
		(end 148.89456 102.74324)
		(width 0.2032)
		(layer "F.Cu")
		(net "+3.3V")
	)
	(segment
		(start 175.9966 115.5662)
		(end 175.9966 114.3662)
		(width 0.254)
		(layer "F.Cu")
		(net "+3.3V")
	)
	(segment
		(start 175.7341 110.9037)
		(end 175.7341 110.1287)
		(width 0.254)
		(layer "F.Cu")
		(net "+3.3V")
	)
	(segment
		(start 170.3216 119.2412)
		(end 171.4216 119.2412)
		(width 0.254)
		(layer "F.Cu")
		(net "+3.3V")
	)
	(segment
		(start 112.0216 65.72859)
		(end 112.0216 65.7162)
		(width 0.762)
		(layer "F.Cu")
		(net "+3.3V")
	)
	(segment
		(start 67.39683 143.86615)
		(end 67.39683 143.2162)
		(width 0.254)
		(layer "F.Cu")
		(net "+3.3V")
	)
	(segment
		(start 67.4466 84.0662)
		(end 69.6216 84.0662)
		(width 0.254)
		(layer "F.Cu")
		(net "+3.3V")
	)
	(segment
		(start 107.7111 86.69208)
		(end 107.7111 86.62449)
		(width 0.2032)
		(layer "F.Cu")
		(net "+3.3V")
	)
	(segment
		(start 88.45686 86.06371)
		(end 88.45686 85.8137)
		(width 0.2032)
		(layer "F.Cu")
		(net "+3.3V")
	)
	(segment
		(start 106.15022 83.17365)
		(end 106.15828 83.18172)
		(width 0.762)
		(layer "F.Cu")
		(net "+3.3V")
	)
	(segment
		(start 189.13371 146.34763)
		(end 190.0576 146.34763)
		(width 0.254)
		(layer "F.Cu")
		(net "+3.3V")
	)
	(segment
		(start 75.84659 115.4162)
		(end 75.84659 114.7662)
		(width 0.2032)
		(layer "F.Cu")
		(net "+3.3V")
	)
	(segment
		(start 67.4216 129.8412)
		(end 67.4466 129.8162)
		(width 0.254)
		(layer "F.Cu")
		(net "+3.3V")
	)
	(segment
		(start 74.28713 142.6662)
		(end 74.5466 142.6662)
		(width 0.254)
		(layer "F.Cu")
		(net "+3.3V")
	)
	(segment
		(start 84.25687 83.46371)
		(end 84.25687 82.56371)
		(width 0.2032)
		(layer "F.Cu")
		(net "+3.3V")
	)
	(segment
		(start 147.8216 94.6562)
		(end 153.7216 94.6562)
		(width 1.016)
		(layer "F.Cu")
		(net "+3.3V")
	)
	(segment
		(start 106.57869 86.69208)
		(end 107.7111 86.69208)
		(width 0.2032)
		(layer "F.Cu")
		(net "+3.3V")
	)
	(segment
		(start 123.8966 56.0162)
		(end 125.3216 56.0162)
		(width 0.254)
		(layer "F.Cu")
		(net "+3.3V")
	)
	(segment
		(start 109.4716 65.72859)
		(end 112.0216 65.72859)
		(width 0.762)
		(layer "F.Cu")
		(net "+3.3V")
	)
	(segment
		(start 88.9116 71.39368)
		(end 88.9116 69.93847)
		(width 0.2032)
		(layer "F.Cu")
		(net "+3.3V")
	)
	(segment
		(start 175.7216 110.1162)
		(end 175.7341 110.1287)
		(width 0.254)
		(layer "F.Cu")
		(net "+3.3V")
	)
	(segment
		(start 86.70687 85.8137)
		(end 88.45686 85.8137)
		(width 0.2032)
		(layer "F.Cu")
		(net "+3.3V")
	)
	(segment
		(start 219.1216 104.0162)
		(end 219.2216 104.1162)
		(width 0.254)
		(layer "F.Cu")
		(net "+3.3V")
	)
	(segment
		(start 158.9716 129.5162)
		(end 159.79245 129.5162)
		(width 0.2032)
		(layer "F.Cu")
		(net "+3.3V")
	)
	(segment
		(start 172.9216 119.2412)
		(end 174.1216 119.2412)
		(width 0.254)
		(layer "F.Cu")
		(net "+3.3V")
	)
	(segment
		(start 169.5966 119.2412)
		(end 170.3216 119.2412)
		(width 0.254)
		(layer "F.Cu")
		(net "+3.3V")
	)
	(segment
		(start 143.7216 104.0662)
		(end 143.7216 103.0162)
		(width 0.2032)
		(layer "F.Cu")
		(net "+3.3V")
	)
	(segment
		(start 122.7166 83.7662)
		(end 122.7166 82.02113)
		(width 0.2032)
		(layer "F.Cu")
		(net "+3.3V")
	)
	(segment
		(start 72.19476 114.7162)
		(end 72.9966 114.7162)
		(width 0.2032)
		(layer "F.Cu")
		(net "+3.3V")
	)
	(segment
		(start 112.2216 50.9162)
		(end 117.4216 50.9162)
		(width 0.254)
		(layer "F.Cu")
		(net "+3.3V")
	)
	(segment
		(start 143.7216 101.2896)
		(end 143.84063 101.17057)
		(width 0.2032)
		(layer "F.Cu")
		(net "+3.3V")
	)
	(segment
		(start 195.6216 122.6162)
		(end 197.2216 121.0162)
		(width 0.254)
		(layer "F.Cu")
		(net "+3.3V")
	)
	(segment
		(start 107.5216 85.0162)
		(end 107.8216 84.7162)
		(width 0.762)
		(layer "F.Cu")
		(net "+3.3V")
	)
	(segment
		(start 79.92555 68.0162)
		(end 81.1216 68.0162)
		(width 0.762)
		(layer "F.Cu")
		(net "+3.3V")
	)
	(segment
		(start 123.8966 57.0162)
		(end 125.2216 57.0162)
		(width 0.254)
		(layer "F.Cu")
		(net "+3.3V")
	)
	(segment
		(start 110.6216 75.5162)
		(end 112.0216 74.1162)
		(width 0.762)
		(layer "F.Cu")
		(net "+3.3V")
	)
	(segment
		(start 168.15457 91.0162)
		(end 171.53957 91.0162)
		(width 0.2032)
		(layer "F.Cu")
		(net "+3.3V")
	)
	(segment
		(start 75.7216 129.87335)
		(end 75.7216 129.2662)
		(width 0.2032)
		(layer "F.Cu")
		(net "+3.3V")
	)
	(segment
		(start 67.4466 73.1162)
		(end 69.16228 73.1162)
		(width 0.254)
		(layer "F.Cu")
		(net "+3.3V")
	)
	(segment
		(start 105.92869 89.79208)
		(end 105.92869 88.74208)
		(width 0.2032)
		(layer "F.Cu")
		(net "+3.3V")
	)
	(segment
		(start 110.1216 76.9162)
		(end 110.1216 75.5162)
		(width 1.27)
		(layer "F.Cu")
		(net "+3.3V")
	)
	(segment
		(start 170.85457 85.8162)
		(end 170.9216 85.8162)
		(width 0.2032)
		(layer "F.Cu")
		(net "+3.3V")
	)
	(segment
		(start 69.51284 100.4662)
		(end 70.9216 100.4662)
		(width 0.254)
		(layer "F.Cu")
		(net "+3.3V")
	)
	(segment
		(start 70.9216 127.0162)
		(end 70.92161 127.0162)
		(width 0.381)
		(layer "F.Cu")
		(net "+3.3V")
	)
	(segment
		(start 69.46284 100.4162)
		(end 69.51284 100.4662)
		(width 0.254)
		(layer "F.Cu")
		(net "+3.3V")
	)
	(segment
		(start 74.28713 143.8162)
		(end 75.3216 143.8162)
		(width 0.254)
		(layer "F.Cu")
		(net "+3.3V")
	)
	(segment
		(start 75.48713 104.2162)
		(end 75.6216 104.2162)
		(width 0.2032)
		(layer "F.Cu")
		(net "+3.3V")
	)
	(segment
		(start 170.9216 85.8162)
		(end 171.53957 85.8162)
		(width 0.2032)
		(layer "F.Cu")
		(net "+3.3V")
	)
	(segment
		(start 77.1216 115.9162)
		(end 78.0966 115.9162)
		(width 0.2032)
		(layer "F.Cu")
		(net "+3.3V")
	)
	(segment
		(start 123.8966 74.0162)
		(end 125.3216 74.0162)
		(width 0.254)
		(layer "F.Cu")
		(net "+3.3V")
	)
	(segment
		(start 175.9466 115.6162)
		(end 175.9966 115.5662)
		(width 0.254)
		(layer "F.Cu")
		(net "+3.3V")
	)
	(segment
		(start 77.12077 104.0162)
		(end 77.9966 104.0162)
		(width 0.2032)
		(layer "F.Cu")
		(net "+3.3V")
	)
	(segment
		(start 105.20369 85.81708)
		(end 105.27869 85.89208)
		(width 0.2032)
		(layer "F.Cu")
		(net "+3.3V")
	)
	(segment
		(start 79.9216 68.01225)
		(end 79.92555 68.0162)
		(width 0.762)
		(layer "F.Cu")
		(net "+3.3V")
	)
	(segment
		(start 108.3216 78.7162)
		(end 110.1216 76.9162)
		(width 1.27)
		(layer "F.Cu")
		(net "+3.3V")
	)
	(segment
		(start 169.1216 119.7162)
		(end 169.5966 119.2412)
		(width 0.254)
		(layer "F.Cu")
		(net "+3.3V")
	)
	(segment
		(start 129.6216 63.4162)
		(end 133.0216 63.4162)
		(width 0.254)
		(layer "F.Cu")
		(net "+3.3V")
	)
	(segment
		(start 107.5216 85.3162)
		(end 107.5216 85.0162)
		(width 0.762)
		(layer "F.Cu")
		(net "+3.3V")
	)
	(segment
		(start 83.72706 83.43229)
		(end 84.22545 83.43229)
		(width 0.2032)
		(layer "F.Cu")
		(net "+3.3V")
	)
	(segment
		(start 165.65247 110.4162)
		(end 166.4966 110.4162)
		(width 0.254)
		(layer "F.Cu")
		(net "+3.3V")
	)
	(segment
		(start 75.7216 129.2662)
		(end 75.84659 129.2662)
		(width 0.2032)
		(layer "F.Cu")
		(net "+3.3V")
	)
	(segment
		(start 170.69457 87.8139)
		(end 170.85457 87.8139)
		(width 0.2032)
		(layer "F.Cu")
		(net "+3.3V")
	)
	(segment
		(start 199.00106 146.26546)
		(end 199.8166 146.26546)
		(width 0.254)
		(layer "F.Cu")
		(net "+3.3V")
	)
	(segment
		(start 110.1216 75.5162)
		(end 110.1216 73.7286)
		(width 1.27)
		(layer "F.Cu")
		(net "+3.3V")
	)
	(segment
		(start 147.8216 94.6562)
		(end 147.8216 94.6162)
		(width 0.2032)
		(layer "F.Cu")
		(net "+3.3V")
	)
	(segment
		(start 108.3216 84.2162)
		(end 108.3216 83.17365)
		(width 0.762)
		(layer "F.Cu")
		(net "+3.3V")
	)
	(segment
		(start 175.7341 110.9037)
		(end 175.7466 110.9162)
		(width 0.254)
		(layer "F.Cu")
		(net "+3.3V")
	)
	(segment
		(start 168.15457 91.0162)
		(end 168.15457 89.2162)
		(width 0.2032)
		(layer "F.Cu")
		(net "+3.3V")
	)
	(segment
		(start 148.2216 102.9162)
		(end 148.7216 102.9162)
		(width 0.2032)
		(layer "F.Cu")
		(net "+3.3V")
	)
	(segment
		(start 74.28713 143.8162)
		(end 74.28713 142.6662)
		(width 0.254)
		(layer "F.Cu")
		(net "+3.3V")
	)
	(segment
		(start 75.6216 103.5162)
		(end 75.6216 103.46121)
		(width 0.2032)
		(layer "F.Cu")
		(net "+3.3V")
	)
	(segment
		(start 125.2216 57.0162)
		(end 125.2216 57.0162)
		(width 0.2032)
		(layer "F.Cu")
		(net "+3.3V")
	)
	(segment
		(start 197.2216 121.0162)
		(end 197.2216 120.34298)
		(width 0.254)
		(layer "F.Cu")
		(net "+3.3V")
	)
	(segment
		(start 75.6216 104.2162)
		(end 75.6216 103.5162)
		(width 0.2032)
		(layer "F.Cu")
		(net "+3.3V")
	)
	(segment
		(start 224.05728 139.7762)
		(end 225.1716 139.7762)
		(width 0.762)
		(layer "F.Cu")
		(net "+3.3V")
	)
	(segment
		(start 170.69457 89.2162)
		(end 170.69457 87.8139)
		(width 0.2032)
		(layer "F.Cu")
		(net "+3.3V")
	)
	(segment
		(start 146.47597 101.17057)
		(end 148.2216 102.9162)
		(width 0.2032)
		(layer "F.Cu")
		(net "+3.3V")
	)
	(segment
		(start 80.1716 53.8662)
		(end 81.4216 53.8662)
		(width 0.2032)
		(layer "F.Cu")
		(net "+3.3V")
	)
	(segment
		(start 123.8966 73.5162)
		(end 125.3216 73.5162)
		(width 0.254)
		(layer "F.Cu")
		(net "+3.3V")
	)
	(segment
		(start 75.7982 103.28461)
		(end 75.7982 102.7146)
		(width 0.2032)
		(layer "F.Cu")
		(net "+3.3V")
	)
	(segment
		(start 110.67414 52.46365)
		(end 112.2216 50.9162)
		(width 0.254)
		(layer "F.Cu")
		(net "+3.3V")
	)
	(segment
		(start 189.7216 74.5162)
		(end 189.7216 74.5162)
		(width 0.254)
		(layer "F.Cu")
		(net "+3.3V")
	)
	(segment
		(start 85.45686 85.56371)
		(end 86.70687 85.56371)
		(width 0.2032)
		(layer "F.Cu")
		(net "+3.3V")
	)
	(segment
		(start 110.6716 53.5684)
		(end 110.6716 52.4662)
		(width 0.254)
		(layer "F.Cu")
		(net "+3.3V")
	)
	(segment
		(start 229.1216 70.9162)
		(end 229.1216 70.9162)
		(width 0.2032)
		(layer "F.Cu")
		(net "+3.3V")
	)
	(segment
		(start 66.1216 129.8662)
		(end 66.1466 129.8412)
		(width 0.254)
		(layer "F.Cu")
		(net "+3.3V")
	)
	(segment
		(start 66.1466 129.8412)
		(end 67.4216 129.8412)
		(width 0.254)
		(layer "F.Cu")
		(net "+3.3V")
	)
	(segment
		(start 67.4216 102.8412)
		(end 67.4466 102.8162)
		(width 0.254)
		(layer "F.Cu")
		(net "+3.3V")
	)
	(segment
		(start 193.8716 130.8684)
		(end 193.8716 129.95128)
		(width 0.254)
		(layer "F.Cu")
		(net "+3.3V")
	)
	(segment
		(start 86.70687 85.8137)
		(end 86.70687 85.56371)
		(width 0.2032)
		(layer "F.Cu")
		(net "+3.3V")
	)
	(segment
		(start 80.1716 55.6162)
		(end 81.4216 55.6162)
		(width 0.254)
		(layer "F.Cu")
		(net "+3.3V")
	)
	(segment
		(start 67.4216 84.0912)
		(end 67.4466 84.0662)
		(width 0.254)
		(layer "F.Cu")
		(net "+3.3V")
	)
	(segment
		(start 74.98714 115.5162)
		(end 75.84659 115.5162)
		(width 0.2032)
		(layer "F.Cu")
		(net "+3.3V")
	)
	(segment
		(start 148.89456 102.74324)
		(end 148.89456 97.08916)
		(width 0.2032)
		(layer "F.Cu")
		(net "+3.3V")
	)
	(segment
		(start 106.15828 84.60942)
		(end 106.15828 83.18172)
		(width 0.762)
		(layer "F.Cu")
		(net "+3.3V")
	)
	(segment
		(start 194.7716 122.6162)
		(end 195.6216 122.6162)
		(width 0.254)
		(layer "F.Cu")
		(net "+3.3V")
	)
	(segment
		(start 110.6716 52.4662)
		(end 110.67414 52.46365)
		(width 0.254)
		(layer "F.Cu")
		(net "+3.3V")
	)
	(segment
		(start 179.9216 107.3162)
		(end 179.95984 107.27795)
		(width 0.2032)
		(layer "F.Cu")
		(net "+3.3V")
	)
	(segment
		(start 75.84659 115.5162)
		(end 75.84659 115.4162)
		(width 0.2032)
		(layer "F.Cu")
		(net "+3.3V")
	)
	(segment
		(start 71.8216 144.73521)
		(end 71.8216 143.8412)
		(width 0.254)
		(layer "F.Cu")
		(net "+3.3V")
	)
	(segment
		(start 125.3216 73.5162)
		(end 125.3216 73.4162)
		(width 0.2032)
		(layer "F.Cu")
		(net "+3.3V")
	)
	(segment
		(start 155.4716 116.0162)
		(end 156.88492 116.0162)
		(width 0.2032)
		(layer "F.Cu")
		(net "+3.3V")
	)
	(segment
		(start 84.22545 83.43229)
		(end 84.25687 83.46371)
		(width 0.2032)
		(layer "F.Cu")
		(net "+3.3V")
	)
	(segment
		(start 177.68978 146.14763)
		(end 178.68261 146.14763)
		(width 0.254)
		(layer "F.Cu")
		(net "+3.3V")
	)
	(segment
		(start 75.3216 144.0162)
		(end 75.3216 143.8162)
		(width 0.254)
		(layer "F.Cu")
		(net "+3.3V")
	)
	(segment
		(start 166.88732 114.2912)
		(end 168.4966 114.2912)
		(width 0.254)
		(layer "F.Cu")
		(net "+3.3V")
	)
	(segment
		(start 188.3216 74.5162)
		(end 189.7216 74.5162)
		(width 0.254)
		(layer "F.Cu")
		(net "+3.3V")
	)
	(segment
		(start 110.1216 75.5162)
		(end 110.6216 75.5162)
		(width 0.762)
		(layer "F.Cu")
		(net "+3.3V")
	)
	(segment
		(start 224.6716 93.2162)
		(end 226.12443 93.2162)
		(width 0.254)
		(layer "F.Cu")
		(net "+3.3V")
	)
	(segment
		(start 75.7982 102.7146)
		(end 75.8466 102.6662)
		(width 0.2032)
		(layer "F.Cu")
		(net "+3.3V")
	)
	(segment
		(start 170.2466 110.4162)
		(end 171.2216 110.4162)
		(width 0.254)
		(layer "F.Cu")
		(net "+3.3V")
	)
	(segment
		(start 120.3216 78.4662)
		(end 120.3216 77.5162)
		(width 0.254)
		(layer "F.Cu")
		(net "+3.3V")
	)
	(segment
		(start 66.1216 116.3662)
		(end 66.15076 116.33704)
		(width 0.254)
		(layer "F.Cu")
		(net "+3.3V")
	)
	(segment
		(start 175.9966 114.3662)
		(end 176.0466 114.3162)
		(width 0.254)
		(layer "F.Cu")
		(net "+3.3V")
	)
	(segment
		(start 67.4466 73.1162)
		(end 67.4466 73.0662)
		(width 0.254)
		(layer "F.Cu")
		(net "+3.3V")
	)
	(segment
		(start 123.8966 56.5162)
		(end 125.2216 56.5162)
		(width 0.254)
		(layer "F.Cu")
		(net "+3.3V")
	)
	(segment
		(start 72.19476 114.798)
		(end 72.19476 114.7162)
		(width 0.2032)
		(layer "F.Cu")
		(net "+3.3V")
	)
	(segment
		(start 109.4716 73.7286)
		(end 110.1216 73.7286)
		(width 1.27)
		(layer "F.Cu")
		(net "+3.3V")
	)
	(segment
		(start 106.15022 83.17365)
		(end 108.3216 83.17365)
		(width 0.762)
		(layer "F.Cu")
		(net "+3.3V")
	)
	(segment
		(start 106.15828 84.60942)
		(end 106.16635 84.61749)
		(width 0.762)
		(layer "F.Cu")
		(net "+3.3V")
	)
	(segment
		(start 175.7466 112.0162)
		(end 175.7466 110.9162)
		(width 0.254)
		(layer "F.Cu")
		(net "+3.3V")
	)
	(segment
		(start 66.15076 116.33704)
		(end 67.32576 116.33704)
		(width 0.254)
		(layer "F.Cu")
		(net "+3.3V")
	)
	(segment
		(start 105.27869 86.69208)
		(end 105.27869 85.89208)
		(width 0.2032)
		(layer "F.Cu")
		(net "+3.3V")
	)
	(segment
		(start 170.85457 87.8139)
		(end 170.85457 85.8162)
		(width 0.2032)
		(layer "F.Cu")
		(net "+3.3V")
	)
	(segment
		(start 69.4216 100.4162)
		(end 69.46284 100.4162)
		(width 0.254)
		(layer "F.Cu")
		(net "+3.3V")
	)
	(segment
		(start 171.53957 91.0162)
		(end 171.53957 85.8162)
		(width 0.2032)
		(layer "F.Cu")
		(net "+3.3V")
	)
	(segment
		(start 66.1466 102.8412)
		(end 67.4216 102.8412)
		(width 0.254)
		(layer "F.Cu")
		(net "+3.3V")
	)
	(segment
		(start 226.0216 102.38745)
		(end 227.4716 102.38745)
		(width 0.254)
		(layer "F.Cu")
		(net "+3.3V")
	)
	(segment
		(start 80.1716 52.1162)
		(end 81.4592 52.1162)
		(width 0.2032)
		(layer "F.Cu")
		(net "+3.3V")
	)
	(segment
		(start 118.7216 52.2162)
		(end 124.6216 52.2162)
		(width 0.254)
		(layer "F.Cu")
		(net "+3.3V")
	)
	(segment
		(start 75.3216 144.0162)
		(end 76.8966 144.0162)
		(width 0.254)
		(layer "F.Cu")
		(net "+3.3V")
	)
	(segment
		(start 66.1216 102.8662)
		(end 66.1466 102.8412)
		(width 0.254)
		(layer "F.Cu")
		(net "+3.3V")
	)
	(segment
		(start 179.95984 107.27795)
		(end 179.95984 106.18241)
		(width 0.2032)
		(layer "F.Cu")
		(net "+3.3V")
	)
	(segment
		(start 227.9266 70.9162)
		(end 229.1216 70.9162)
		(width 0.2032)
		(layer "F.Cu")
		(net "+3.3V")
	)
	(segment
		(start 219.2216 104.1162)
		(end 220.4216 104.1162)
		(width 0.254)
		(layer "F.Cu")
		(net "+3.3V")
	)
	(segment
		(start 171.4216 119.2412)
		(end 172.9216 119.2412)
		(width 0.254)
		(layer "F.Cu")
		(net "+3.3V")
	)
	(segment
		(start 112.0216 74.1162)
		(end 112.0216 65.72859)
		(width 0.762)
		(layer "F.Cu")
		(net "+3.3V")
	)
	(segment
		(start 226.58443 92.7562)
		(end 226.9216 92.7562)
		(width 0.254)
		(layer "F.Cu")
		(net "+3.3V")
	)
	(segment
		(start 224.0216 142.3162)
		(end 225.1716 142.3162)
		(width 0.762)
		(layer "F.Cu")
		(net "+3.3V")
	)
	(segment
		(start 67.32576 116.33704)
		(end 67.4466 116.2162)
		(width 0.254)
		(layer "F.Cu")
		(net "+3.3V")
	)
	(segment
		(start 225.4716 112.7162)
		(end 225.4716 111.1162)
		(width 0.254)
		(layer "F.Cu")
		(net "+3.3V")
	)
	(segment
		(start 226.12443 93.2162)
		(end 226.58443 92.7562)
		(width 0.254)
		(layer "F.Cu")
		(net "+3.3V")
	)
	(segment
		(start 143.7216 103.0162)
		(end 143.7216 101.2896)
		(width 0.2032)
		(layer "F.Cu")
		(net "+3.3V")
	)
	(via
		(at 105.20369 85.81708)
		(size 0.4064)
		(drill 0.2032)
		(layers "F.Cu" "B.Cu")
		(net "+3.3V")
	)
	(via
		(at 75.7216 129.87335)
		(size 0.4064)
		(drill 0.2032)
		(layers "F.Cu" "B.Cu")
		(net "+3.3V")
	)
	(via
		(at 165.3216 86.5162)
		(size 0.4064)
		(drill 0.254)
		(layers "F.Cu" "B.Cu")
		(net "+3.3V")
	)
	(via
		(at 219.2216 109.4737)
		(size 0.4064)
		(drill 0.2032)
		(layers "F.Cu" "B.Cu")
		(net "+3.3V")
	)
	(via
		(at 69.4216 100.4162)
		(size 0.4064)
		(drill 0.2032)
		(layers "F.Cu" "B.Cu")
		(tenting
			(front yes)
			(back yes)
		)
		(net "+3.3V")
	)
	(via
		(at 164.4216 95.9162)
		(size 0.4064)
		(drill 0.254)
		(layers "F.Cu" "B.Cu")
		(net "+3.3V")
	)
	(via
		(at 143.7216 103.0162)
		(size 0.4064)
		(drill 0.2032)
		(layers "F.Cu" "B.Cu")
		(net "+3.3V")
	)
	(via
		(at 224.2216 142.3162)
		(size 0.4064)
		(drill 0.2032)
		(layers "F.Cu" "B.Cu")
		(net "+3.3V")
	)
	(via
		(at 81.1216 68.0162)
		(size 0.4064)
		(drill 0.2032)
		(layers "F.Cu" "B.Cu")
		(net "+3.3V")
	)
	(via
		(at 128.8166 90.1212)
		(size 0.4064)
		(drill 0.2032)
		(layers "F.Cu" "B.Cu")
		(net "+3.3V")
	)
	(via
		(at 143.7644 93.52526)
		(size 0.4064)
		(drill 0.254)
		(layers "F.Cu" "B.Cu")
		(net "+3.3V")
	)
	(via
		(at 189.13371 146.34763)
		(size 0.4064)
		(drill 0.2032)
		(layers "F.Cu" "B.Cu")
		(net "+3.3V")
	)
	(via
		(at 209.1216 113.2162)
		(size 0.4064)
		(drill 0.254)
		(layers "F.Cu" "B.Cu")
		(net "+3.3V")
	)
	(via
		(at 143.7216 94.7162)
		(size 0.4064)
		(drill 0.254)
		(layers "F.Cu" "B.Cu")
		(net "+3.3V")
	)
	(via
		(at 165.0966 94.2162)
		(size 0.4064)
		(drill 0.2032)
		(layers "F.Cu" "B.Cu")
		(net "+3.3V")
	)
	(via
		(at 110.1216 75.5162)
		(size 0.4064)
		(drill 0.2032)
		(layers "F.Cu" "B.Cu")
		(net "+3.3V")
	)
	(via
		(at 85.45686 85.56371)
		(size 0.4064)
		(drill 0.2032)
		(layers "F.Cu" "B.Cu")
		(tenting
			(front yes)
			(back yes)
		)
		(net "+3.3V")
	)
	(via
		(at 67.39683 143.86615)
		(size 0.4064)
		(drill 0.2032)
		(layers "F.Cu" "B.Cu")
		(net "+3.3V")
	)
	(via
		(at 81.4216 55.6162)
		(size 0.4064)
		(drill 0.2032)
		(layers "F.Cu" "B.Cu")
		(tenting
			(front yes)
			(back yes)
		)
		(net "+3.3V")
	)
	(via
		(at 166.0216 86.5162)
		(size 0.4064)
		(drill 0.254)
		(layers "F.Cu" "B.Cu")
		(net "+3.3V")
	)
	(via
		(at 81.4216 53.8662)
		(size 0.4064)
		(drill 0.2032)
		(layers "F.Cu" "B.Cu")
		(tenting
			(front yes)
			(back yes)
		)
		(net "+3.3V")
	)
	(via
		(at 179.9216 107.3162)
		(size 0.4064)
		(drill 0.2032)
		(layers "F.Cu" "B.Cu")
		(net "+3.3V")
	)
	(via
		(at 175.7216 110.1162)
		(size 0.4064)
		(drill 0.2032)
		(layers "F.Cu" "B.Cu")
		(net "+3.3V")
	)
	(via
		(at 164.5216 86.5162)
		(size 0.4064)
		(drill 0.254)
		(layers "F.Cu" "B.Cu")
		(net "+3.3V")
	)
	(via
		(at 125.2216 57.0162)
		(size 0.4064)
		(drill 0.2032)
		(layers "F.Cu" "B.Cu")
		(net "+3.3V")
	)
	(via
		(at 166.0216 85.1162)
		(size 0.4064)
		(drill 0.254)
		(layers "F.Cu" "B.Cu")
		(net "+3.3V")
	)
	(via
		(at 164.5216 85.8162)
		(size 0.4064)
		(drill 0.254)
		(layers "F.Cu" "B.Cu")
		(net "+3.3V")
	)
	(via
		(at 77.1216 115.9162)
		(size 0.4064)
		(drill 0.2032)
		(layers "F.Cu" "B.Cu")
		(net "+3.3V")
	)
	(via
		(at 169.1216 119.7162)
		(size 0.4064)
		(drill 0.2032)
		(layers "F.Cu" "B.Cu")
		(net "+3.3V")
	)
	(via
		(at 66.1216 102.8662)
		(size 0.4064)
		(drill 0.2032)
		(layers "F.Cu" "B.Cu")
		(tenting
			(front yes)
			(back yes)
		)
		(net "+3.3V")
	)
	(via
		(at 112.1216 73.7162)
		(size 0.4064)
		(drill 0.2032)
		(layers "F.Cu" "B.Cu")
		(net "+3.3V")
	)
	(via
		(at 193.8716 129.95128)
		(size 0.4064)
		(drill 0.2032)
		(layers "F.Cu" "B.Cu")
		(net "+3.3V")
	)
	(via
		(at 165.65247 110.4162)
		(size 0.4064)
		(drill 0.2032)
		(layers "F.Cu" "B.Cu")
		(net "+3.3V")
	)
	(via
		(at 125.3216 73.4162)
		(size 0.4064)
		(drill 0.2032)
		(layers "F.Cu" "B.Cu")
		(net "+3.3V")
	)
	(via
		(at 159.79245 129.5162)
		(size 0.4064)
		(drill 0.2032)
		(layers "F.Cu" "B.Cu")
		(net "+3.3V")
	)
	(via
		(at 142.2466 93.8662)
		(size 0.4064)
		(drill 0.254)
		(layers "F.Cu" "B.Cu")
		(net "+3.3V")
	)
	(via
		(at 163.5216 96.0162)
		(size 0.4064)
		(drill 0.254)
		(layers "F.Cu" "B.Cu")
		(net "+3.3V")
	)
	(via
		(at 120.3216 77.5162)
		(size 0.4064)
		(drill 0.2032)
		(layers "F.Cu" "B.Cu")
		(net "+3.3V")
	)
	(via
		(at 165.3216 85.8162)
		(size 0.4064)
		(drill 0.254)
		(layers "F.Cu" "B.Cu")
		(net "+3.3V")
	)
	(via
		(at 154.0216 72.7162)
		(size 0.4064)
		(drill 0.254)
		(layers "F.Cu" "B.Cu")
		(net "+3.3V")
	)
	(via
		(at 197.0216 93.0162)
		(size 0.4064)
		(drill 0.254)
		(layers "F.Cu" "B.Cu")
		(net "+3.3V")
	)
	(via
		(at 166.88732 114.2912)
		(size 0.4064)
		(drill 0.2032)
		(layers "F.Cu" "B.Cu")
		(net "+3.3V")
	)
	(via
		(at 134.6216 72.9162)
		(size 0.4064)
		(drill 0.254)
		(layers "F.Cu" "B.Cu")
		(net "+3.3V")
	)
	(via
		(at 107.5216 85.3162)
		(size 0.4064)
		(drill 0.254)
		(layers "F.Cu" "B.Cu")
		(net "+3.3V")
	)
	(via
		(at 165.3216 85.1162)
		(size 0.4064)
		(drill 0.254)
		(layers "F.Cu" "B.Cu")
		(net "+3.3V")
	)
	(via
		(at 155.1216 72.7162)
		(size 0.4064)
		(drill 0.254)
		(layers "F.Cu" "B.Cu")
		(net "+3.3V")
	)
	(via
		(at 133.5216 72.9162)
		(size 0.4064)
		(drill 0.254)
		(layers "F.Cu" "B.Cu")
		(net "+3.3V")
	)
	(via
		(at 75.84659 115.4162)
		(size 0.4064)
		(drill 0.2032)
		(layers "F.Cu" "B.Cu")
		(net "+3.3V")
	)
	(via
		(at 134.43412 85.80879)
		(size 0.4064)
		(drill 0.2032)
		(layers "F.Cu" "B.Cu")
		(net "+3.3V")
	)
	(via
		(at 125.3216 56.0162)
		(size 0.4064)
		(drill 0.2032)
		(layers "F.Cu" "B.Cu")
		(net "+3.3V")
	)
	(via
		(at 107.7111 86.62449)
		(size 0.4064)
		(drill 0.2032)
		(layers "F.Cu" "B.Cu")
		(net "+3.3V")
	)
	(via
		(at 214.6216 101.7162)
		(size 0.4064)
		(drill 0.254)
		(layers "F.Cu" "B.Cu")
		(net "+3.3V")
	)
	(via
		(at 198.1216 92.0162)
		(size 0.4064)
		(drill 0.254)
		(layers "F.Cu" "B.Cu")
		(net "+3.3V")
	)
	(via
		(at 129.6216 63.4162)
		(size 0.4064)
		(drill 0.2032)
		(layers "F.Cu" "B.Cu")
		(net "+3.3V")
	)
	(via
		(at 229.1216 70.9162)
		(size 0.4064)
		(drill 0.2032)
		(layers "F.Cu" "B.Cu")
		(net "+3.3V")
	)
	(via
		(at 81.1216 88.0162)
		(size 0.4064)
		(drill 0.254)
		(layers "F.Cu" "B.Cu")
		(net "+3.3V")
	)
	(via
		(at 221.1216 95.4162)
		(size 0.4064)
		(drill 0.2032)
		(layers "F.Cu" "B.Cu")
		(net "+3.3V")
	)
	(via
		(at 134.5216 73.9162)
		(size 0.4064)
		(drill 0.254)
		(layers "F.Cu" "B.Cu")
		(net "+3.3V")
	)
	(via
		(at 155.1216 73.8162)
		(size 0.4064)
		(drill 0.254)
		(layers "F.Cu" "B.Cu")
		(net "+3.3V")
	)
	(via
		(at 83.45541 83.21562)
		(size 0.4064)
		(drill 0.2032)
		(layers "F.Cu" "B.Cu")
		(net "+3.3V")
	)
	(via
		(at 144.60919 94.35722)
		(size 0.4064)
		(drill 0.254)
		(layers "F.Cu" "B.Cu")
		(net "+3.3V")
	)
	(via
		(at 220.7216 122.7162)
		(size 0.4064)
		(drill 0.2032)
		(layers "F.Cu" "B.Cu")
		(net "+3.3V")
	)
	(via
		(at 152.8216 73.7162)
		(size 0.4064)
		(drill 0.254)
		(layers "F.Cu" "B.Cu")
		(net "+3.3V")
	)
	(via
		(at 72.19476 114.798)
		(size 0.4064)
		(drill 0.2032)
		(layers "F.Cu" "B.Cu")
		(net "+3.3V")
	)
	(via
		(at 170.85457 87.8139)
		(size 0.4064)
		(drill 0.2032)
		(layers "F.Cu" "B.Cu")
		(net "+3.3V")
	)
	(via
		(at 197.0216 92.0162)
		(size 0.4064)
		(drill 0.254)
		(layers "F.Cu" "B.Cu")
		(net "+3.3V")
	)
	(via
		(at 221.0216 100.5162)
		(size 0.4064)
		(drill 0.2032)
		(layers "F.Cu" "B.Cu")
		(net "+3.3V")
	)
	(via
		(at 71.8216 144.73521)
		(size 0.4064)
		(drill 0.2032)
		(layers "F.Cu" "B.Cu")
		(net "+3.3V")
	)
	(via
		(at 122.7166 82.02113)
		(size 0.4064)
		(drill 0.2032)
		(layers "F.Cu" "B.Cu")
		(net "+3.3V")
	)
	(via
		(at 175.9466 115.6162)
		(size 0.4064)
		(drill 0.2032)
		(layers "F.Cu" "B.Cu")
		(net "+3.3V")
	)
	(via
		(at 210.0216 113.2162)
		(size 0.4064)
		(drill 0.254)
		(layers "F.Cu" "B.Cu")
		(net "+3.3V")
	)
	(via
		(at 191.2216 65.2162)
		(size 0.4064)
		(drill 0.254)
		(layers "F.Cu" "B.Cu")
		(net "+3.3V")
	)
	(via
		(at 125.2216 56.5162)
		(size 0.4064)
		(drill 0.2032)
		(layers "F.Cu" "B.Cu")
		(net "+3.3V")
	)
	(via
		(at 70.9216 127.0162)
		(size 0.4064)
		(drill 0.2032)
		(layers "F.Cu" "B.Cu")
		(net "+3.3V")
	)
	(via
		(at 171.2216 110.4162)
		(size 0.4064)
		(drill 0.2032)
		(layers "F.Cu" "B.Cu")
		(net "+3.3V")
	)
	(via
		(at 154.0216 73.8162)
		(size 0.4064)
		(drill 0.254)
		(layers "F.Cu" "B.Cu")
		(net "+3.3V")
	)
	(via
		(at 81.4592 52.1162)
		(size 0.4064)
		(drill 0.2032)
		(layers "F.Cu" "B.Cu")
		(tenting
			(front yes)
			(back yes)
		)
		(net "+3.3V")
	)
	(via
		(at 189.9216 66.4162)
		(size 0.4064)
		(drill 0.254)
		(layers "F.Cu" "B.Cu")
		(net "+3.3V")
	)
	(via
		(at 77.12077 104.0162)
		(size 0.4064)
		(drill 0.2032)
		(layers "F.Cu" "B.Cu")
		(net "+3.3V")
	)
	(via
		(at 79.4216 88.0162)
		(size 0.4064)
		(drill 0.254)
		(layers "F.Cu" "B.Cu")
		(net "+3.3V")
	)
	(via
		(at 191.1216 66.4162)
		(size 0.4064)
		(drill 0.254)
		(layers "F.Cu" "B.Cu")
		(net "+3.3V")
	)
	(via
		(at 226.7216 111.1162)
		(size 0.4064)
		(drill 0.2032)
		(layers "F.Cu" "B.Cu")
		(net "+3.3V")
	)
	(via
		(at 195.6216 122.6162)
		(size 0.4064)
		(drill 0.2032)
		(layers "F.Cu" "B.Cu")
		(net "+3.3V")
	)
	(via
		(at 177.68978 146.14763)
		(size 0.4064)
		(drill 0.2032)
		(layers "F.Cu" "B.Cu")
		(net "+3.3V")
	)
	(via
		(at 88.9116 71.39368)
		(size 0.4064)
		(drill 0.2032)
		(layers "F.Cu" "B.Cu")
		(net "+3.3V")
	)
	(via
		(at 125.3216 74.0162)
		(size 0.4064)
		(drill 0.2032)
		(layers "F.Cu" "B.Cu")
		(net "+3.3V")
	)
	(via
		(at 188.6216 66.3162)
		(size 0.4064)
		(drill 0.254)
		(layers "F.Cu" "B.Cu")
		(net "+3.3V")
	)
	(via
		(at 110.67414 52.46365)
		(size 0.4064)
		(drill 0.2032)
		(layers "F.Cu" "B.Cu")
		(net "+3.3V")
	)
	(via
		(at 227.4716 102.38745)
		(size 0.4064)
		(drill 0.2032)
		(layers "F.Cu" "B.Cu")
		(net "+3.3V")
	)
	(via
		(at 75.6216 103.5162)
		(size 0.4064)
		(drill 0.2032)
		(layers "F.Cu" "B.Cu")
		(net "+3.3V")
	)
	(via
		(at 164.5216 85.1162)
		(size 0.4064)
		(drill 0.254)
		(layers "F.Cu" "B.Cu")
		(net "+3.3V")
	)
	(via
		(at 105.92869 89.79208)
		(size 0.4064)
		(drill 0.2032)
		(layers "F.Cu" "B.Cu")
		(net "+3.3V")
	)
	(via
		(at 189.9216 65.1162)
		(size 0.4064)
		(drill 0.254)
		(layers "F.Cu" "B.Cu")
		(net "+3.3V")
	)
	(via
		(at 133.5216 73.9162)
		(size 0.4064)
		(drill 0.254)
		(layers "F.Cu" "B.Cu")
		(net "+3.3V")
	)
	(via
		(at 210.22086 146.21546)
		(size 0.4064)
		(drill 0.2032)
		(layers "F.Cu" "B.Cu")
		(net "+3.3V")
	)
	(via
		(at 81.4216 50.3662)
		(size 0.4064)
		(drill 0.2032)
		(layers "F.Cu" "B.Cu")
		(tenting
			(front yes)
			(back yes)
		)
		(net "+3.3V")
	)
	(via
		(at 107.8216 84.7162)
		(size 0.4064)
		(drill 0.254)
		(layers "F.Cu" "B.Cu")
		(net "+3.3V")
	)
	(via
		(at 220.4216 104.1162)
		(size 0.4064)
		(drill 0.2032)
		(layers "F.Cu" "B.Cu")
		(net "+3.3V")
	)
	(via
		(at 152.8216 72.7162)
		(size 0.4064)
		(drill 0.254)
		(layers "F.Cu" "B.Cu")
		(net "+3.3V")
	)
	(via
		(at 189.7216 74.5162)
		(size 0.4064)
		(drill 0.2032)
		(layers "F.Cu" "B.Cu")
		(net "+3.3V")
	)
	(via
		(at 112.0216 65.7162)
		(size 0.4064)
		(drill 0.2032)
		(layers "F.Cu" "B.Cu")
		(tenting
			(front yes)
			(back yes)
		)
		(net "+3.3V")
	)
	(via
		(at 80.3216 88.0162)
		(size 0.4064)
		(drill 0.254)
		(layers "F.Cu" "B.Cu")
		(net "+3.3V")
	)
	(via
		(at 199.2216 92.1162)
		(size 0.4064)
		(drill 0.254)
		(layers "F.Cu" "B.Cu")
		(net "+3.3V")
	)
	(via
		(at 75.3216 143.8162)
		(size 0.4064)
		(drill 0.2032)
		(layers "F.Cu" "B.Cu")
		(net "+3.3V")
	)
	(via
		(at 214.6216 102.5162)
		(size 0.4064)
		(drill 0.254)
		(layers "F.Cu" "B.Cu")
		(net "+3.3V")
	)
	(via
		(at 224.25729 139.7762)
		(size 0.4064)
		(drill 0.2032)
		(layers "F.Cu" "B.Cu")
		(net "+3.3V")
	)
	(via
		(at 165.5216 95.9162)
		(size 0.4064)
		(drill 0.254)
		(layers "F.Cu" "B.Cu")
		(net "+3.3V")
	)
	(via
		(at 66.1216 129.8662)
		(size 0.4064)
		(drill 0.2032)
		(layers "F.Cu" "B.Cu")
		(tenting
			(front yes)
			(back yes)
		)
		(net "+3.3V")
	)
	(via
		(at 188.6216 65.1162)
		(size 0.4064)
		(drill 0.254)
		(layers "F.Cu" "B.Cu")
		(net "+3.3V")
	)
	(via
		(at 166.0216 85.8162)
		(size 0.4064)
		(drill 0.254)
		(layers "F.Cu" "B.Cu")
		(net "+3.3V")
	)
	(via
		(at 66.1216 116.3662)
		(size 0.4064)
		(drill 0.2032)
		(layers "F.Cu" "B.Cu")
		(tenting
			(front yes)
			(back yes)
		)
		(net "+3.3V")
	)
	(via
		(at 148.0216 123.6162)
		(size 0.4064)
		(drill 0.2032)
		(layers "F.Cu" "B.Cu")
		(net "+3.3V")
	)
	(via
		(at 199.00106 146.26546)
		(size 0.4064)
		(drill 0.2032)
		(layers "F.Cu" "B.Cu")
		(net "+3.3V")
	)
	(via
		(at 156.88492 116.0162)
		(size 0.4064)
		(drill 0.2032)
		(layers "F.Cu" "B.Cu")
		(net "+3.3V")
	)
	(segment
		(start 193.50119 131.04896)
		(end 193.50119 130.36294)
		(width 0.254)
		(layer "B.Cu")
		(net "+3.3V")
	)
	(segment
		(start 76.7216 130.3412)
		(end 78.0966 130.3412)
		(width 0.254)
		(layer "B.Cu")
		(net "+3.3V")
	)
	(segment
		(start 229.1216 70.9162)
		(end 229.1216 70.3162)
		(width 0.2032)
		(layer "B.Cu")
		(net "+3.3V")
	)
	(segment
		(start 166.88732 114.2912)
		(end 167.75606 114.2912)
		(width 0.254)
		(layer "B.Cu")
		(net "+3.3V")
	)
	(segment
		(start 110.67018 52.46762)
		(end 110.67414 52.46365)
		(width 0.254)
		(layer "B.Cu")
		(net "+3.3V")
	)
	(segment
		(start 88.5116 71.39368)
		(end 88.9116 71.39368)
		(width 0.2032)
		(layer "B.Cu")
		(net "+3.3V")
	)
	(segment
		(start 74.3216 104.1412)
		(end 75.6216 104.1412)
		(width 0.2032)
		(layer "B.Cu")
		(net "+3.3V")
	)
	(segment
		(start 221.0216 100.5162)
		(end 221.0466 100.4912)
		(width 0.254)
		(layer "B.Cu")
		(net "+3.3V")
	)
	(segment
		(start 146.6116 124.6162)
		(end 146.6116 124.4762)
		(width 0.254)
		(layer "B.Cu")
		(net "+3.3V")
	)
	(segment
		(start 210.7216 126.24394)
		(end 211.8216 125.14394)
		(width 0.254)
		(layer "B.Cu")
		(net "+3.3V")
	)
	(segment
		(start 193.86582 129.95707)
		(end 193.8716 129.95128)
		(width 0.254)
		(layer "B.Cu")
		(net "+3.3V")
	)
	(segment
		(start 122.7166 83.2212)
		(end 122.7166 82.02113)
		(width 0.2032)
		(layer "B.Cu")
		(net "+3.3V")
	)
	(segment
		(start 219.2641 109.5162)
		(end 220.0466 109.5162)
		(width 0.254)
		(layer "B.Cu")
		(net "+3.3V")
	)
	(segment
		(start 81.1216 93.3162)
		(end 82.1216 94.3162)
		(width 0.254)
		(layer "B.Cu")
		(net "+3.3V")
	)
	(segment
		(start 208.4616 125.1362)
		(end 210.5416 125.1362)
		(width 0.2032)
		(layer "B.Cu")
		(net "+3.3V")
	)
	(segment
		(start 87.1116 70.03347)
		(end 87.1116 69.77347)
		(width 0.2032)
		(layer "B.Cu")
		(net "+3.3V")
	)
	(segment
		(start 83.62142 67.68865)
		(end 83.9116 67.39847)
		(width 0.254)
		(layer "B.Cu")
		(net "+3.3V")
	)
	(segment
		(start 220.0466 107.6162)
		(end 220.0466 106.5912)
		(width 0.254)
		(layer "B.Cu")
		(net "+3.3V")
	)
	(segment
		(start 155.18714 116.0162)
		(end 156.88492 116.0162)
		(width 0.2032)
		(layer "B.Cu")
		(net "+3.3V")
	)
	(segment
		(start 212.98279 122.9162)
		(end 218.1216 122.9162)
		(width 0.254)
		(layer "B.Cu")
		(net "+3.3V")
	)
	(segment
		(start 158.68714 129.5162)
		(end 159.79245 129.5162)
		(width 0.2032)
		(layer "B.Cu")
		(net "+3.3V")
	)
	(segment
		(start 125.5216 64.51075)
		(end 126.04024 63.99211)
		(width 0.254)
		(layer "B.Cu")
		(net "+3.3V")
	)
	(segment
		(start 126.5216 56.5162)
		(end 126.5216 56.28174)
		(width 0.254)
		(layer "B.Cu")
		(net "+3.3V")
	)
	(segment
		(start 83.30308 68.0162)
		(end 83.62142 67.69786)
		(width 0.254)
		(layer "B.Cu")
		(net "+3.3V")
	)
	(segment
		(start 206.9916 126.54065)
		(end 206.9916 125.6362)
		(width 0.2032)
		(layer "B.Cu")
		(net "+3.3V")
	)
	(segment
		(start 146.8446 124.2432)
		(end 147.3946 124.2432)
		(width 0.254)
		(layer "B.Cu")
		(net "+3.3V")
	)
	(segment
		(start 124.20313 73.96419)
		(end 124.32891 73.96419)
		(width 0.254)
		(layer "B.Cu")
		(net "+3.3V")
	)
	(segment
		(start 207.4216 127.6162)
		(end 207.4216 126.97065)
		(width 0.2032)
		(layer "B.Cu")
		(net "+3.3V")
	)
	(segment
		(start 126.04024 63.99211)
		(end 126.8216 63.99211)
		(width 0.254)
		(layer "B.Cu")
		(net "+3.3V")
	)
	(segment
		(start 124.46434 74.0162)
		(end 125.3216 74.0162)
		(width 0.254)
		(layer "B.Cu")
		(net "+3.3V")
	)
	(segment
		(start 124.32891 73.96419)
		(end 124.35192 73.98721)
		(width 0.254)
		(layer "B.Cu")
		(net "+3.3V")
	)
	(segment
		(start 207.31727 126.86632)
		(end 207.4216 126.97065)
		(width 0.2032)
		(layer "B.Cu")
		(net "+3.3V")
	)
	(segment
		(start 120.3216 78.75066)
		(end 120.3216 77.5162)
		(width 0.254)
		(layer "B.Cu")
		(net "+3.3V")
	)
	(segment
		(start 87.1116 70.03347)
		(end 88.5116 70.03347)
		(width 0.2032)
		(layer "B.Cu")
		(net "+3.3V")
	)
	(segment
		(start 83.62142 67.69786)
		(end 83.62142 67.68865)
		(width 0.254)
		(layer "B.Cu")
		(net "+3.3V")
	)
	(segment
		(start 179.9216 106.30444)
		(end 180.30985 105.9162)
		(width 0.2032)
		(layer "B.Cu")
		(net "+3.3V")
	)
	(segment
		(start 170.85457 89.4162)
		(end 170.85457 87.8139)
		(width 0.2032)
		(layer "B.Cu")
		(net "+3.3V")
	)
	(segment
		(start 219.2216 109.4737)
		(end 219.2641 109.5162)
		(width 0.254)
		(layer "B.Cu")
		(net "+3.3V")
	)
	(segment
		(start 110.72193 73.1686)
		(end 111.67523 73.1686)
		(width 0.762)
		(layer "B.Cu")
		(net "+3.3V")
	)
	(segment
		(start 112.0092 65.7286)
		(end 112.0216 65.7162)
		(width 0.762)
		(layer "B.Cu")
		(net "+3.3V")
	)
	(segment
		(start 111.67523 73.1686)
		(end 112.1216 73.61497)
		(width 0.762)
		(layer "B.Cu")
		(net "+3.3V")
	)
	(segment
		(start 81.1216 93.3162)
		(end 81.1216 88.0162)
		(width 0.254)
		(layer "B.Cu")
		(net "+3.3V")
	)
	(segment
		(start 175.7216 110.1162)
		(end 177.1216 110.1162)
		(width 0.508)
		(layer "B.Cu")
		(net "+3.3V")
	)
	(segment
		(start 180.30985 105.9162)
		(end 180.38484 105.8412)
		(width 0.2032)
		(layer "B.Cu")
		(net "+3.3V")
	)
	(segment
		(start 122.4216 83.5162)
		(end 122.7166 83.2212)
		(width 0.2032)
		(layer "B.Cu")
		(net "+3.3V")
	)
	(segment
		(start 125.2216 56.5162)
		(end 126.5216 56.5162)
		(width 0.254)
		(layer "B.Cu")
		(net "+3.3V")
	)
	(segment
		(start 75.7216 130.3412)
		(end 76.7216 130.3412)
		(width 0.254)
		(layer "B.Cu")
		(net "+3.3V")
	)
	(segment
		(start 170.59457 91.0162)
		(end 170.85457 91.0162)
		(width 0.2032)
		(layer "B.Cu")
		(net "+3.3V")
	)
	(segment
		(start 211.8216 125.14394)
		(end 211.8216 124.07738)
		(width 0.254)
		(layer "B.Cu")
		(net "+3.3V")
	)
	(segment
		(start 110.66622 53.74896)
		(end 110.67018 53.745)
		(width 0.254)
		(layer "B.Cu")
		(net "+3.3V")
	)
	(segment
		(start 210.7216 126.24394)
		(end 210.7216 125.3162)
		(width 0.2032)
		(layer "B.Cu")
		(net "+3.3V")
	)
	(segment
		(start 112.1216 73.7162)
		(end 112.1216 73.61497)
		(width 0.762)
		(layer "B.Cu")
		(net "+3.3V")
	)
	(segment
		(start 124.07407 73.83513)
		(end 124.07407 73.80066)
		(width 0.254)
		(layer "B.Cu")
		(net "+3.3V")
	)
	(segment
		(start 193.8716 129.99252)
		(end 193.8716 129.95128)
		(width 0.254)
		(layer "B.Cu")
		(net "+3.3V")
	)
	(segment
		(start 179.9216 107.3162)
		(end 179.9216 106.30444)
		(width 0.2032)
		(layer "B.Cu")
		(net "+3.3V")
	)
	(segment
		(start 211.8216 124.07738)
		(end 212.98279 122.9162)
		(width 0.254)
		(layer "B.Cu")
		(net "+3.3V")
	)
	(segment
		(start 146.6116 124.4762)
		(end 146.8446 124.2432)
		(width 0.254)
		(layer "B.Cu")
		(net "+3.3V")
	)
	(segment
		(start 81.1216 68.0162)
		(end 83.30308 68.0162)
		(width 0.254)
		(layer "B.Cu")
		(net "+3.3V")
	)
	(segment
		(start 218.1216 122.9162)
		(end 218.3216 122.7162)
		(width 0.254)
		(layer "B.Cu")
		(net "+3.3V")
	)
	(segment
		(start 124.35192 73.98721)
		(end 124.43534 73.98721)
		(width 0.254)
		(layer "B.Cu")
		(net "+3.3V")
	)
	(segment
		(start 129.60855 63.40316)
		(end 129.6216 63.4162)
		(width 0.254)
		(layer "B.Cu")
		(net "+3.3V")
	)
	(segment
		(start 220.0466 106.5912)
		(end 220.4466 106.1912)
		(width 0.254)
		(layer "B.Cu")
		(net "+3.3V")
	)
	(segment
		(start 193.50119 130.36294)
		(end 193.8716 129.99252)
		(width 0.254)
		(layer "B.Cu")
		(net "+3.3V")
	)
	(segment
		(start 126.8216 63.99211)
		(end 126.8216 63.96711)
		(width 0.254)
		(layer "B.Cu")
		(net "+3.3V")
	)
	(segment
		(start 110.67018 53.745)
		(end 110.67018 52.46762)
		(width 0.254)
		(layer "B.Cu")
		(net "+3.3V")
	)
	(segment
		(start 126.8216 63.96711)
		(end 127.38555 63.40316)
		(width 0.254)
		(layer "B.Cu")
		(net "+3.3V")
	)
	(segment
		(start 126.5216 73.75066)
		(end 126.5216 73.4162)
		(width 0.254)
		(layer "B.Cu")
		(net "+3.3V")
	)
	(segment
		(start 218.3216 122.7162)
		(end 220.7216 122.7162)
		(width 0.254)
		(layer "B.Cu")
		(net "+3.3V")
	)
	(segment
		(start 112.0216 66.0162)
		(end 112.0216 65.7162)
		(width 0.762)
		(layer "B.Cu")
		(net "+3.3V")
	)
	(segment
		(start 124.07407 73.83513)
		(end 124.20313 73.96419)
		(width 0.254)
		(layer "B.Cu")
		(net "+3.3V")
	)
	(segment
		(start 229.1216 71.6162)
		(end 229.1216 70.9162)
		(width 0.2032)
		(layer "B.Cu")
		(net "+3.3V")
	)
	(segment
		(start 147.3946 124.2432)
		(end 148.0216 123.6162)
		(width 0.254)
		(layer "B.Cu")
		(net "+3.3V")
	)
	(segment
		(start 228.0216 71.6162)
		(end 229.1216 71.6162)
		(width 0.2032)
		(layer "B.Cu")
		(net "+3.3V")
	)
	(segment
		(start 207.4216 127.6162)
		(end 207.7465 127.9411)
		(width 0.2032)
		(layer "B.Cu")
		(net "+3.3V")
	)
	(segment
		(start 170.85457 91.0162)
		(end 170.85457 89.4162)
		(width 0.2032)
		(layer "B.Cu")
		(net "+3.3V")
	)
	(segment
		(start 210.5416 125.1362)
		(end 210.7216 125.3162)
		(width 0.2032)
		(layer "B.Cu")
		(net "+3.3V")
	)
	(segment
		(start 124.43534 73.98721)
		(end 124.46434 74.0162)
		(width 0.254)
		(layer "B.Cu")
		(net "+3.3V")
	)
	(segment
		(start 165.0966 94.2162)
		(end 166.88457 94.2162)
		(width 0.2032)
		(layer "B.Cu")
		(net "+3.3V")
	)
	(segment
		(start 221.0466 100.4912)
		(end 221.9216 100.4912)
		(width 0.254)
		(layer "B.Cu")
		(net "+3.3V")
	)
	(segment
		(start 125.3216 73.4162)
		(end 126.5216 73.4162)
		(width 0.254)
		(layer "B.Cu")
		(net "+3.3V")
	)
	(segment
		(start 123.8966 57.0162)
		(end 123.8966 56.23174)
		(width 0.254)
		(layer "B.Cu")
		(net "+3.3V")
	)
	(segment
		(start 194.48714 122.6162)
		(end 195.6216 122.6162)
		(width 0.254)
		(layer "B.Cu")
		(net "+3.3V")
	)
	(segment
		(start 206.9916 126.54065)
		(end 207.31727 126.86632)
		(width 0.2032)
		(layer "B.Cu")
		(net "+3.3V")
	)
	(segment
		(start 123.8966 57.0162)
		(end 125.2216 57.0162)
		(width 0.254)
		(layer "B.Cu")
		(net "+3.3V")
	)
	(segment
		(start 82.1216 94.3162)
		(end 83.2216 94.3162)
		(width 0.254)
		(layer "B.Cu")
		(net "+3.3V")
	)
	(segment
		(start 125.3216 56.0162)
		(end 125.3216 54.78173)
		(width 0.254)
		(layer "B.Cu")
		(net "+3.3V")
	)
	(segment
		(start 75.6216 104.1412)
		(end 75.6216 103.5162)
		(width 0.2032)
		(layer "B.Cu")
		(net "+3.3V")
	)
	(segment
		(start 220.4466 105.1162)
		(end 220.4466 104.1412)
		(width 0.254)
		(layer "B.Cu")
		(net "+3.3V")
	)
	(segment
		(start 143.7216 104.35066)
		(end 143.7216 103.0162)
		(width 0.2032)
		(layer "B.Cu")
		(net "+3.3V")
	)
	(segment
		(start 88.5116 71.39368)
		(end 88.5116 70.03347)
		(width 0.2032)
		(layer "B.Cu")
		(net "+3.3V")
	)
	(segment
		(start 109.87414 65.7286)
		(end 112.0092 65.7286)
		(width 0.762)
		(layer "B.Cu")
		(net "+3.3V")
	)
	(segment
		(start 220.4216 104.1162)
		(end 220.4466 104.1412)
		(width 0.254)
		(layer "B.Cu")
		(net "+3.3V")
	)
	(segment
		(start 220.4466 106.1912)
		(end 220.4466 105.1162)
		(width 0.254)
		(layer "B.Cu")
		(net "+3.3V")
	)
	(segment
		(start 221.1428 95.4374)
		(end 221.91312 95.4374)
		(width 0.254)
		(layer "B.Cu")
		(net "+3.3V")
	)
	(segment
		(start 210.3716 127.9411)
		(end 210.7216 127.5911)
		(width 0.2032)
		(layer "B.Cu")
		(net "+3.3V")
	)
	(segment
		(start 127.38555 63.40316)
		(end 128.2216 63.40316)
		(width 0.254)
		(layer "B.Cu")
		(net "+3.3V")
	)
	(segment
		(start 112.0216 66.0162)
		(end 113.5216 66.0162)
		(width 0.762)
		(layer "B.Cu")
		(net "+3.3V")
	)
	(segment
		(start 128.2216 63.40316)
		(end 129.60855 63.40316)
		(width 0.254)
		(layer "B.Cu")
		(net "+3.3V")
	)
	(segment
		(start 177.1216 110.1162)
		(end 179.9216 107.3162)
		(width 0.508)
		(layer "B.Cu")
		(net "+3.3V")
	)
	(segment
		(start 78.0966 130.3412)
		(end 78.0966 130.0162)
		(width 0.254)
		(layer "B.Cu")
		(net "+3.3V")
	)
	(segment
		(start 227.7616 70.3162)
		(end 229.1216 70.3162)
		(width 0.2032)
		(layer "B.Cu")
		(net "+3.3V")
	)
	(segment
		(start 221.1216 95.4162)
		(end 221.1428 95.4374)
		(width 0.254)
		(layer "B.Cu")
		(net "+3.3V")
	)
	(segment
		(start 180.38484 105.8412)
		(end 181.90985 105.8412)
		(width 0.2032)
		(layer "B.Cu")
		(net "+3.3V")
	)
	(segment
		(start 210.7216 127.5911)
		(end 210.7216 126.24394)
		(width 0.2032)
		(layer "B.Cu")
		(net "+3.3V")
	)
	(segment
		(start 207.7465 127.9411)
		(end 210.3716 127.9411)
		(width 0.2032)
		(layer "B.Cu")
		(net "+3.3V")
	)
	(segment
		(start 125.5216 64.53575)
		(end 125.5216 64.51075)
		(width 0.254)
		(layer "B.Cu")
		(net "+3.3V")
	)
	(segment
		(start 75.7216 130.3412)
		(end 75.7216 129.87335)
		(width 0.254)
		(layer "B.Cu")
		(net "+3.3V")
	)
	(segment
		(start 66.1216 116.9162)
		(end 66.1216 116.3662)
		(width 0.381)
		(layer "In2.Cu")
		(net "+3.3V")
	)
	(segment
		(start 82.1216 58.1224)
		(end 82.1216 56.3162)
		(width 0.381)
		(layer "In2.Cu")
		(net "+3.3V")
	)
	(segment
		(start 72.19476 114.798)
		(end 72.19476 113.48205)
		(width 0.381)
		(layer "In2.Cu")
		(net "+3.3V")
	)
	(segment
		(start 169.1216 119.7162)
		(end 169.3216 119.5162)
		(width 1.016)
		(layer "In2.Cu")
		(net "+3.3V")
	)
	(segment
		(start 125.3216 80.6162)
		(end 125.3216 76.0162)
		(width 0.508)
		(layer "In2.Cu")
		(net "+3.3V")
	)
	(segment
		(start 194.5788 124.47092)
		(end 194.5788 123.659)
		(width 0.254)
		(layer "In2.Cu")
		(net "+3.3V")
	)
	(segment
		(start 70.4216 61.5162)
		(end 70.8216 61.5162)
		(width 0.381)
		(layer "In2.Cu")
		(net "+3.3V")
	)
	(segment
		(start 70.9216 127.0162)
		(end 74.9216 127.0162)
		(width 0.381)
		(layer "In2.Cu")
		(net "+3.3V")
	)
	(segment
		(start 67.39683 143.86615)
		(end 70.8635 143.86615)
		(width 0.381)
		(layer "In2.Cu")
		(net "+3.3V")
	)
	(segment
		(start 165.65247 113.05635)
		(end 165.65247 110.62183)
		(width 1.016)
		(layer "In2.Cu")
		(net "+3.3V")
	)
	(segment
		(start 70.8635 143.86615)
		(end 70.8635 141.5162)
		(width 0.381)
		(layer "In2.Cu")
		(net "+3.3V")
	)
	(segment
		(start 164.01436 112.25994)
		(end 165.65247 110.62183)
		(width 1.016)
		(layer "In2.Cu")
		(net "+3.3V")
	)
	(segment
		(start 192.46296 129.54505)
		(end 192.86919 129.95128)
		(width 0.254)
		(layer "In2.Cu")
		(net "+3.3V")
	)
	(segment
		(start 72.19476 113.48205)
		(end 74.8216 113.48205)
		(width 0.381)
		(layer "In2.Cu")
		(net "+3.3V")
	)
	(segment
		(start 192.46296 129.54505)
		(end 192.46296 127.35744)
		(width 0.254)
		(layer "In2.Cu")
		(net "+3.3V")
	)
	(segment
		(start 121.0216 77.5162)
		(end 122.6216 75.9162)
		(width 0.508)
		(layer "In2.Cu")
		(net "+3.3V")
	)
	(segment
		(start 81.4592 52.10933)
		(end 81.9216 51.64692)
		(width 0.381)
		(layer "In2.Cu")
		(net "+3.3V")
	)
	(segment
		(start 156.88492 115.05288)
		(end 159.67786 112.25994)
		(width 1.016)
		(layer "In2.Cu")
		(net "+3.3V")
	)
	(segment
		(start 194.5788 123.659)
		(end 195.6216 122.6162)
		(width 0.254)
		(layer "In2.Cu")
		(net "+3.3V")
	)
	(segment
		(start 192.46296 127.35744)
		(end 194.2216 125.5988)
		(width 0.254)
		(layer "In2.Cu")
		(net "+3.3V")
	)
	(segment
		(start 69.4216 100.4162)
		(end 74.86335 100.4162)
		(width 0.381)
		(layer "In2.Cu")
		(net "+3.3V")
	)
	(segment
		(start 75.2216 60.4162)
		(end 76.9216 58.7162)
		(width 0.381)
		(layer "In2.Cu")
		(net "+3.3V")
	)
	(segment
		(start 74.6216 144.73521)
		(end 74.6216 144.7162)
		(width 0.381)
		(layer "In2.Cu")
		(net "+3.3V")
	)
	(segment
		(start 81.4216 55.6162)
		(end 81.97155 55.06624)
		(width 0.381)
		(layer "In2.Cu")
		(net "+3.3V")
	)
	(segment
		(start 81.4216 50.37307)
		(end 81.9216 50.87307)
		(width 0.381)
		(layer "In2.Cu")
		(net "+3.3V")
	)
	(segment
		(start 81.4592 52.1162)
		(end 82.0216 52.6786)
		(width 0.381)
		(layer "In2.Cu")
		(net "+3.3V")
	)
	(segment
		(start 81.5278 58.7162)
		(end 82.1216 58.1224)
		(width 0.381)
		(layer "In2.Cu")
		(net "+3.3V")
	)
	(segment
		(start 81.4216 50.37307)
		(end 81.4216 50.3662)
		(width 0.381)
		(layer "In2.Cu")
		(net "+3.3V")
	)
	(segment
		(start 74.27518 130.32702)
		(end 74.27518 129.8662)
		(width 0.381)
		(layer "In2.Cu")
		(net "+3.3V")
	)
	(segment
		(start 76.9216 58.7162)
		(end 81.5278 58.7162)
		(width 0.381)
		(layer "In2.Cu")
		(net "+3.3V")
	)
	(segment
		(start 66.1216 129.8662)
		(end 74.27518 129.8662)
		(width 0.381)
		(layer "In2.Cu")
		(net "+3.3V")
	)
	(segment
		(start 192.86919 129.95128)
		(end 193.8716 129.95128)
		(width 0.254)
		(layer "In2.Cu")
		(net "+3.3V")
	)
	(segment
		(start 166.88732 114.2912)
		(end 169.3216 116.72548)
		(width 1.016)
		(layer "In2.Cu")
		(net "+3.3V")
	)
	(segment
		(start 194.2216 124.82812)
		(end 194.5788 124.47092)
		(width 0.254)
		(layer "In2.Cu")
		(net "+3.3V")
	)
	(segment
		(start 159.67786 112.25994)
		(end 164.01436 112.25994)
		(width 1.016)
		(layer "In2.Cu")
		(net "+3.3V")
	)
	(segment
		(start 122.7166 82.02113)
		(end 123.91667 82.02113)
		(width 0.508)
		(layer "In2.Cu")
		(net "+3.3V")
	)
	(segment
		(start 81.97155 55.06624)
		(end 81.97155 54.41616)
		(width 0.381)
		(layer "In2.Cu")
		(net "+3.3V")
	)
	(segment
		(start 156.04927 120.18853)
		(end 156.04927 116.85184)
		(width 1.016)
		(layer "In2.Cu")
		(net "+3.3V")
	)
	(segment
		(start 74.9216 127.2162)
		(end 74.9216 127.0162)
		(width 0.381)
		(layer "In2.Cu")
		(net "+3.3V")
	)
	(segment
		(start 71.8216 144.73521)
		(end 74.6216 144.73521)
		(width 0.381)
		(layer "In2.Cu")
		(net "+3.3V")
	)
	(segment
		(start 194.2216 125.5988)
		(end 194.2216 124.82812)
		(width 0.254)
		(layer "In2.Cu")
		(net "+3.3V")
	)
	(segment
		(start 66.1216 116.9162)
		(end 74.7216 116.9162)
		(width 0.381)
		(layer "In2.Cu")
		(net "+3.3V")
	)
	(segment
		(start 71.9216 60.4162)
		(end 75.2216 60.4162)
		(width 0.381)
		(layer "In2.Cu")
		(net "+3.3V")
	)
	(segment
		(start 66.1216 103.9162)
		(end 66.1216 102.8662)
		(width 0.381)
		(layer "In2.Cu")
		(net "+3.3V")
	)
	(segment
		(start 165.65247 113.05635)
		(end 166.88732 114.2912)
		(width 1.016)
		(layer "In2.Cu")
		(net "+3.3V")
	)
	(segment
		(start 122.6216 75.9162)
		(end 123.5216 75.9162)
		(width 0.508)
		(layer "In2.Cu")
		(net "+3.3V")
	)
	(segment
		(start 81.4216 53.8662)
		(end 81.97155 54.41616)
		(width 0.381)
		(layer "In2.Cu")
		(net "+3.3V")
	)
	(segment
		(start 74.82001 103.9162)
		(end 74.82001 103.77312)
		(width 0.381)
		(layer "In2.Cu")
		(net "+3.3V")
	)
	(segment
		(start 169.3216 119.5162)
		(end 169.3216 116.72548)
		(width 1.016)
		(layer "In2.Cu")
		(net "+3.3V")
	)
	(segment
		(start 81.4592 52.1162)
		(end 81.4592 52.10933)
		(width 0.381)
		(layer "In2.Cu")
		(net "+3.3V")
	)
	(segment
		(start 123.91667 82.02113)
		(end 125.3216 80.6162)
		(width 0.508)
		(layer "In2.Cu")
		(net "+3.3V")
	)
	(segment
		(start 156.88492 116.0162)
		(end 156.88492 115.05288)
		(width 1.016)
		(layer "In2.Cu")
		(net "+3.3V")
	)
	(segment
		(start 74.86335 100.47444)
		(end 74.86335 100.4162)
		(width 0.381)
		(layer "In2.Cu")
		(net "+3.3V")
	)
	(segment
		(start 148.0216 123.6162)
		(end 152.6216 123.6162)
		(width 1.016)
		(layer "In2.Cu")
		(net "+3.3V")
	)
	(segment
		(start 81.4216 55.6162)
		(end 82.1216 56.3162)
		(width 0.381)
		(layer "In2.Cu")
		(net "+3.3V")
	)
	(segment
		(start 70.8216 61.5162)
		(end 71.9216 60.4162)
		(width 0.381)
		(layer "In2.Cu")
		(net "+3.3V")
	)
	(segment
		(start 74.7216 116.9162)
		(end 74.7216 116.6162)
		(width 0.381)
		(layer "In2.Cu")
		(net "+3.3V")
	)
	(segment
		(start 165.65247 110.62183)
		(end 165.65247 110.4162)
		(width 1.016)
		(layer "In2.Cu")
		(net "+3.3V")
	)
	(segment
		(start 70.8635 141.5162)
		(end 74.92696 141.5162)
		(width 0.381)
		(layer "In2.Cu")
		(net "+3.3V")
	)
	(segment
		(start 81.4216 53.8662)
		(end 82.0216 53.2662)
		(width 0.381)
		(layer "In2.Cu")
		(net "+3.3V")
	)
	(segment
		(start 81.9216 51.64692)
		(end 81.9216 50.87307)
		(width 0.381)
		(layer "In2.Cu")
		(net "+3.3V")
	)
	(segment
		(start 82.0216 53.2662)
		(end 82.0216 52.6786)
		(width 0.381)
		(layer "In2.Cu")
		(net "+3.3V")
	)
	(segment
		(start 156.04927 116.85184)
		(end 156.88492 116.0162)
		(width 1.016)
		(layer "In2.Cu")
		(net "+3.3V")
	)
	(segment
		(start 66.1216 103.9162)
		(end 74.82001 103.9162)
		(width 0.381)
		(layer "In2.Cu")
		(net "+3.3V")
	)
	(segment
		(start 120.3216 77.5162)
		(end 121.0216 77.5162)
		(width 0.508)
		(layer "In2.Cu")
		(net "+3.3V")
	)
	(segment
		(start 152.6216 123.6162)
		(end 156.04927 120.18853)
		(width 1.016)
		(layer "In2.Cu")
		(net "+3.3V")
	)
	(segment
		(start 171.2216 110.4162)
		(end 171.2216 106.4162)
		(width 0.508)
		(layer "In3.Cu")
		(net "+3.3V")
	)
	(segment
		(start 154.4716 128.86854)
		(end 156.91032 128.86854)
		(width 0.381)
		(layer "In3.Cu")
		(net "+3.3V")
	)
	(segment
		(start 166.92405 105.61374)
		(end 166.92405 104.9683)
		(width 0.508)
		(layer "In3.Cu")
		(net "+3.3V")
	)
	(segment
		(start 142.7695 128.79301)
		(end 142.7695 126.3683)
		(width 0.381)
		(layer "In3.Cu")
		(net "+3.3V")
	)
	(segment
		(start 142.7695 128.79301)
		(end 142.99269 129.0162)
		(width 0.381)
		(layer "In3.Cu")
		(net "+3.3V")
	)
	(segment
		(start 133.12671 87.1162)
		(end 134.43412 85.80879)
		(width 0.508)
		(layer "In3.Cu")
		(net "+3.3V")
	)
	(segment
		(start 173.26222 109.97557)
		(end 175.58098 109.97557)
		(width 0.508)
		(layer "In3.Cu")
		(net "+3.3V")
	)
	(segment
		(start 172.8216 110.4162)
		(end 173.26222 109.97557)
		(width 0.508)
		(layer "In3.Cu")
		(net "+3.3V")
	)
	(segment
		(start 85.53412 68.0162)
		(end 88.9116 71.39368)
		(width 0.381)
		(layer "In3.Cu")
		(net "+3.3V")
	)
	(segment
		(start 143.7216 125.4162)
		(end 146.2216 125.4162)
		(width 0.381)
		(layer "In3.Cu")
		(net "+3.3V")
	)
	(segment
		(start 176.4216 115.1412)
		(end 176.4216 110.8162)
		(width 0.508)
		(layer "In3.Cu")
		(net "+3.3V")
	)
	(segment
		(start 171.2216 110.4162)
		(end 172.8216 110.4162)
		(width 0.508)
		(layer "In3.Cu")
		(net "+3.3V")
	)
	(segment
		(start 152.85798 129.7162)
		(end 153.62394 129.7162)
		(width 0.381)
		(layer "In3.Cu")
		(net "+3.3V")
	)
	(segment
		(start 153.62394 129.7162)
		(end 154.4716 128.86854)
		(width 0.381)
		(layer "In3.Cu")
		(net "+3.3V")
	)
	(segment
		(start 148.28979 128.8162)
		(end 151.95798 128.8162)
		(width 0.381)
		(layer "In3.Cu")
		(net "+3.3V")
	)
	(segment
		(start 146.1875 128.6955)
		(end 146.26602 128.77402)
		(width 0.381)
		(layer "In3.Cu")
		(net "+3.3V")
	)
	(segment
		(start 167.38839 104.50396)
		(end 169.30937 104.50396)
		(width 0.508)
		(layer "In3.Cu")
		(net "+3.3V")
	)
	(segment
		(start 165.65247 110.4162)
		(end 165.65247 106.88533)
		(width 0.508)
		(layer "In3.Cu")
		(net "+3.3V")
	)
	(segment
		(start 165.65247 106.88533)
		(end 166.92405 105.61374)
		(width 0.508)
		(layer "In3.Cu")
		(net "+3.3V")
	)
	(segment
		(start 128.8166 90.1212)
		(end 131.8216 87.1162)
		(width 0.508)
		(layer "In3.Cu")
		(net "+3.3V")
	)
	(segment
		(start 151.95798 128.8162)
		(end 152.85798 129.7162)
		(width 0.381)
		(layer "In3.Cu")
		(net "+3.3V")
	)
	(segment
		(start 142.7695 126.3683)
		(end 143.7216 125.4162)
		(width 0.381)
		(layer "In3.Cu")
		(net "+3.3V")
	)
	(segment
		(start 142.99269 129.0162)
		(end 143.6216 129.0162)
		(width 0.381)
		(layer "In3.Cu")
		(net "+3.3V")
	)
	(segment
		(start 143.6216 129.0162)
		(end 143.9423 128.6955)
		(width 0.381)
		(layer "In3.Cu")
		(net "+3.3V")
	)
	(segment
		(start 81.1216 68.0162)
		(end 85.53412 68.0162)
		(width 0.381)
		(layer "In3.Cu")
		(net "+3.3V")
	)
	(segment
		(start 131.8216 87.1162)
		(end 133.12671 87.1162)
		(width 0.508)
		(layer "In3.Cu")
		(net "+3.3V")
	)
	(segment
		(start 148.2476 128.77402)
		(end 148.28979 128.8162)
		(width 0.381)
		(layer "In3.Cu")
		(net "+3.3V")
	)
	(segment
		(start 175.7216 110.1162)
		(end 176.4216 110.8162)
		(width 0.508)
		(layer "In3.Cu")
		(net "+3.3V")
	)
	(segment
		(start 156.91032 128.86854)
		(end 157.55798 129.5162)
		(width 0.381)
		(layer "In3.Cu")
		(net "+3.3V")
	)
	(segment
		(start 146.26602 128.77402)
		(end 148.2476 128.77402)
		(width 0.381)
		(layer "In3.Cu")
		(net "+3.3V")
	)
	(segment
		(start 169.30937 104.50396)
		(end 171.2216 106.4162)
		(width 0.508)
		(layer "In3.Cu")
		(net "+3.3V")
	)
	(segment
		(start 146.2216 125.4162)
		(end 148.0216 123.6162)
		(width 0.381)
		(layer "In3.Cu")
		(net "+3.3V")
	)
	(segment
		(start 166.92405 104.9683)
		(end 167.38839 104.50396)
		(width 0.508)
		(layer "In3.Cu")
		(net "+3.3V")
	)
	(segment
		(start 143.9423 128.6955)
		(end 146.1875 128.6955)
		(width 0.381)
		(layer "In3.Cu")
		(net "+3.3V")
	)
	(segment
		(start 175.58098 109.97557)
		(end 175.7216 110.1162)
		(width 0.508)
		(layer "In3.Cu")
		(net "+3.3V")
	)
	(segment
		(start 157.55798 129.5162)
		(end 159.79245 129.5162)
		(width 0.381)
		(layer "In3.Cu")
		(net "+3.3V")
	)
	(segment
		(start 175.9466 115.6162)
		(end 176.4216 115.1412)
		(width 0.508)
		(layer "In3.Cu")
		(net "+3.3V")
	)
	(segment
		(start 140.46126 110.22059)
		(end 143.43793 110.22059)
		(width 0.2032)
		(layer "F.Cu")
		(net "FPGA_TDO")
	)
	(segment
		(start 178.99944 139.19405)
		(end 183.8216 144.0162)
		(width 0.2032)
		(layer "F.Cu")
		(net "FPGA_TDO")
	)
	(segment
		(start 152.86106 123.7162)
		(end 176.9216 123.7162)
		(width 0.2032)
		(layer "F.Cu")
		(net "FPGA_TDO")
	)
	(segment
		(start 178.99944 139.19405)
		(end 178.99944 125.79404)
		(width 0.2032)
		(layer "F.Cu")
		(net "FPGA_TDO")
	)
	(segment
		(start 191.6216 144.0162)
		(end 192.2076 144.60221)
		(width 0.2032)
		(layer "F.Cu")
		(net "FPGA_TDO")
	)
	(segment
		(start 192.2076 144.60221)
		(end 194.40761 144.60221)
		(width 0.2032)
		(layer "F.Cu")
		(net "FPGA_TDO")
	)
	(segment
		(start 143.43793 110.22059)
		(end 148.66248 115.44515)
		(width 0.2032)
		(layer "F.Cu")
		(net "FPGA_TDO")
	)
	(segment
		(start 194.40761 145.69763)
		(end 194.40761 144.60221)
		(width 0.2032)
		(layer "F.Cu")
		(net "FPGA_TDO")
	)
	(segment
		(start 183.8216 144.0162)
		(end 191.6216 144.0162)
		(width 0.2032)
		(layer "F.Cu")
		(net "FPGA_TDO")
	)
	(segment
		(start 148.66248 119.51763)
		(end 148.66248 115.44515)
		(width 0.2032)
		(layer "F.Cu")
		(net "FPGA_TDO")
	)
	(segment
		(start 176.9216 123.7162)
		(end 178.99944 125.79404)
		(width 0.2032)
		(layer "F.Cu")
		(net "FPGA_TDO")
	)
	(segment
		(start 148.66248 119.51763)
		(end 152.86106 123.7162)
		(width 0.2032)
		(layer "F.Cu")
		(net "FPGA_TDO")
	)
	(segment
		(start 192.3076 145.69763)
		(end 194.40761 145.69763)
		(width 0.2032)
		(layer "F.Cu")
		(net "FPGA_TDO")
	)
	(segment
		(start 178.33701 139.43161)
		(end 178.33701 125.83161)
		(width 0.2032)
		(layer "F.Cu")
		(net "FPGA_TCK")
	)
	(segment
		(start 142.9216 110.72072)
		(end 148.1216 115.92072)
		(width 0.2032)
		(layer "F.Cu")
		(net "FPGA_TCK")
	)
	(segment
		(start 148.1216 120.1162)
		(end 152.6216 124.6162)
		(width 0.2032)
		(layer "F.Cu")
		(net "FPGA_TCK")
	)
	(segment
		(start 178.33701 139.43161)
		(end 183.1216 144.2162)
		(width 0.2032)
		(layer "F.Cu")
		(net "FPGA_TCK")
	)
	(segment
		(start 183.10761 145.49763)
		(end 183.10761 144.23019)
		(width 0.2032)
		(layer "F.Cu")
		(net "FPGA_TCK")
	)
	(segment
		(start 148.1216 120.1162)
		(end 148.1216 115.92072)
		(width 0.2032)
		(layer "F.Cu")
		(net "FPGA_TCK")
	)
	(segment
		(start 140.46126 110.72072)
		(end 142.9216 110.72072)
		(width 0.2032)
		(layer "F.Cu")
		(net "FPGA_TCK")
	)
	(segment
		(start 183.10761 144.23019)
		(end 183.1216 144.2162)
		(width 0.2032)
		(layer "F.Cu")
		(net "FPGA_TCK")
	)
	(segment
		(start 177.1216 124.6162)
		(end 178.33701 125.83161)
		(width 0.2032)
		(layer "F.Cu")
		(net "FPGA_TCK")
	)
	(segment
		(start 152.6216 124.6162)
		(end 177.1216 124.6162)
		(width 0.2032)
		(layer "F.Cu")
		(net "FPGA_TCK")
	)
	(segment
		(start 180.93261 145.49763)
		(end 183.10761 145.49763)
		(width 0.2032)
		(layer "F.Cu")
		(net "FPGA_TCK")
	)
	(segment
		(start 224.5716 69.7162)
		(end 225.3866 69.7162)
		(width 0.254)
		(layer "F.Cu")
		(net "+12V")
	)
	(segment
		(start 225.3866 70.9162)
		(end 225.3866 69.7162)
		(width 0.254)
		(layer "F.Cu")
		(net "+12V")
	)
	(segment
		(start 224.5716 69.7162)
		(end 224.5716 68.4162)
		(width 0.254)
		(layer "F.Cu")
		(net "+12V")
	)
	(via
		(at 186.3216 86.0162)
		(size 0.4064)
		(drill 0.254)
		(layers "F.Cu" "B.Cu")
		(net "+12V")
	)
	(via
		(at 100.21119 54.71266)
		(size 0.4064)
		(drill 0.254)
		(layers "F.Cu" "B.Cu")
		(net "+12V")
	)
	(via
		(at 186.3216 86.8162)
		(size 0.4064)
		(drill 0.254)
		(layers "F.Cu" "B.Cu")
		(net "+12V")
	)
	(via
		(at 153.1216 65.2162)
		(size 0.4064)
		(drill 0.254)
		(layers "F.Cu" "B.Cu")
		(net "+12V")
	)
	(via
		(at 142.3907 87.83401)
		(size 0.4064)
		(drill 0.254)
		(layers "F.Cu" "B.Cu")
		(net "+12V")
	)
	(via
		(at 154.4216 65.2162)
		(size 0.4064)
		(drill 0.254)
		(layers "F.Cu" "B.Cu")
		(net "+12V")
	)
	(via
		(at 198.2216 61.2162)
		(size 0.4064)
		(drill 0.254)
		(layers "F.Cu" "B.Cu")
		(net "+12V")
	)
	(via
		(at 82.2216 62.6162)
		(size 0.4064)
		(drill 0.254)
		(layers "F.Cu" "B.Cu")
		(net "+12V")
	)
	(via
		(at 228.6216 67.2162)
		(size 0.4064)
		(drill 0.254)
		(layers "F.Cu" "B.Cu")
		(net "+12V")
	)
	(via
		(at 185.3216 87.7162)
		(size 0.4064)
		(drill 0.254)
		(layers "F.Cu" "B.Cu")
		(net "+12V")
	)
	(via
		(at 198.2216 60.2162)
		(size 0.4064)
		(drill 0.254)
		(layers "F.Cu" "B.Cu")
		(net "+12V")
	)
	(via
		(at 229.3216 68.0162)
		(size 0.4064)
		(drill 0.254)
		(layers "F.Cu" "B.Cu")
		(net "+12V")
	)
	(via
		(at 154.4216 64.2162)
		(size 0.4064)
		(drill 0.254)
		(layers "F.Cu" "B.Cu")
		(net "+12V")
	)
	(via
		(at 199.3216 61.3162)
		(size 0.4064)
		(drill 0.254)
		(layers "F.Cu" "B.Cu")
		(net "+12V")
	)
	(via
		(at 92.1216 52.6162)
		(size 0.4064)
		(drill 0.254)
		(layers "F.Cu" "B.Cu")
		(net "+12V")
	)
	(via
		(at 144.8216 86.8162)
		(size 0.4064)
		(drill 0.254)
		(layers "F.Cu" "B.Cu")
		(net "+12V")
	)
	(via
		(at 92.1216 53.4162)
		(size 0.4064)
		(drill 0.254)
		(layers "F.Cu" "B.Cu")
		(net "+12V")
	)
	(via
		(at 81.19738 57.6162)
		(size 0.4064)
		(drill 0.254)
		(layers "F.Cu" "B.Cu")
		(net "+12V")
	)
	(via
		(at 92.1216 54.2162)
		(size 0.4064)
		(drill 0.254)
		(layers "F.Cu" "B.Cu")
		(net "+12V")
	)
	(via
		(at 153.1216 66.1162)
		(size 0.4064)
		(drill 0.254)
		(layers "F.Cu" "B.Cu")
		(net "+12V")
	)
	(via
		(at 224.3216 67.8162)
		(size 0.4064)
		(drill 0.254)
		(layers "F.Cu" "B.Cu")
		(net "+12V")
	)
	(via
		(at 224.9216 68.7162)
		(size 0.4064)
		(drill 0.254)
		(layers "F.Cu" "B.Cu")
		(net "+12V")
	)
	(via
		(at 144.4216 87.7162)
		(size 0.4064)
		(drill 0.254)
		(layers "F.Cu" "B.Cu")
		(net "+12V")
	)
	(via
		(at 186.3216 87.7162)
		(size 0.4064)
		(drill 0.254)
		(layers "F.Cu" "B.Cu")
		(net "+12V")
	)
	(via
		(at 154.4216 66.0162)
		(size 0.4064)
		(drill 0.254)
		(layers "F.Cu" "B.Cu")
		(net "+12V")
	)
	(via
		(at 200.4216 60.2162)
		(size 0.4064)
		(drill 0.254)
		(layers "F.Cu" "B.Cu")
		(net "+12V")
	)
	(via
		(at 143.6216 86.7162)
		(size 0.4064)
		(drill 0.254)
		(layers "F.Cu" "B.Cu")
		(net "+12V")
	)
	(via
		(at 100.7216 55.0162)
		(size 0.4064)
		(drill 0.254)
		(layers "F.Cu" "B.Cu")
		(net "+12V")
	)
	(via
		(at 84.1716 62.0662)
		(size 0.4064)
		(drill 0.254)
		(layers "F.Cu" "B.Cu")
		(net "+12V")
	)
	(via
		(at 153.1216 64.2162)
		(size 0.4064)
		(drill 0.254)
		(layers "F.Cu" "B.Cu")
		(net "+12V")
	)
	(via
		(at 199.3216 60.2162)
		(size 0.4064)
		(drill 0.254)
		(layers "F.Cu" "B.Cu")
		(net "+12V")
	)
	(via
		(at 226.9466 68.1162)
		(size 0.4064)
		(drill 0.254)
		(layers "F.Cu" "B.Cu")
		(net "+12V")
	)
	(via
		(at 92.1216 51.2162)
		(size 0.4064)
		(drill 0.254)
		(layers "F.Cu" "B.Cu")
		(net "+12V")
	)
	(via
		(at 200.4216 61.2162)
		(size 0.4064)
		(drill 0.254)
		(layers "F.Cu" "B.Cu")
		(net "+12V")
	)
	(via
		(at 82.2216 61.7162)
		(size 0.4064)
		(drill 0.254)
		(layers "F.Cu" "B.Cu")
		(net "+12V")
	)
	(via
		(at 227.9216 68.0162)
		(size 0.4064)
		(drill 0.254)
		(layers "F.Cu" "B.Cu")
		(net "+12V")
	)
	(via
		(at 81.19738 59.9162)
		(size 0.4064)
		(drill 0.254)
		(layers "F.Cu" "B.Cu")
		(net "+12V")
	)
	(via
		(at 84.1716 60.5162)
		(size 0.4064)
		(drill 0.254)
		(layers "F.Cu" "B.Cu")
		(net "+12V")
	)
	(via
		(at 92.1216 50.5162)
		(size 0.4064)
		(drill 0.254)
		(layers "F.Cu" "B.Cu")
		(net "+12V")
	)
	(via
		(at 226.2216 68.0162)
		(size 0.4064)
		(drill 0.254)
		(layers "F.Cu" "B.Cu")
		(net "+12V")
	)
	(via
		(at 99.511 57.7062)
		(size 0.4064)
		(drill 0.254)
		(layers "F.Cu" "B.Cu")
		(net "+12V")
	)
	(via
		(at 99.6216 55.0162)
		(size 0.4064)
		(drill 0.254)
		(layers "F.Cu" "B.Cu")
		(net "+12V")
	)
	(segment
		(start 95.6881 59.4037)
		(end 95.7006 59.4162)
		(width 0.254)
		(layer "B.Cu")
		(net "+12V")
	)
	(segment
		(start 177.4617 83.6563)
		(end 180.6216 86.8162)
		(width 0.254)
		(layer "B.Cu")
		(net "+12V")
	)
	(segment
		(start 98.20311 55.0162)
		(end 99.6216 55.0162)
		(width 0.254)
		(layer "B.Cu")
		(net "+12V")
	)
	(segment
		(start 87.7466 57.1912)
		(end 87.7466 56.5662)
		(width 0.254)
		(layer "B.Cu")
		(net "+12V")
	)
	(segment
		(start 85.6466 57.36402)
		(end 85.6466 56.5662)
		(width 0.254)
		(layer "B.Cu")
		(net "+12V")
	)
	(segment
		(start 180.1216 81.9162)
		(end 180.8216 81.9162)
		(width 0.254)
		(layer "B.Cu")
		(net "+12V")
	)
	(segment
		(start 87.5216 57.4162)
		(end 87.7466 57.1912)
		(width 0.254)
		(layer "B.Cu")
		(net "+12V")
	)
	(segment
		(start 95.6756 58.4511)
		(end 95.6881 58.4636)
		(width 0.254)
		(layer "B.Cu")
		(net "+12V")
	)
	(segment
		(start 85.6466 57.36402)
		(end 85.69878 57.4162)
		(width 0.254)
		(layer "B.Cu")
		(net "+12V")
	)
	(segment
		(start 95.6756 57.54371)
		(end 98.20311 55.0162)
		(width 0.254)
		(layer "B.Cu")
		(net "+12V")
	)
	(segment
		(start 85.6466 59.0412)
		(end 85.6466 57.36402)
		(width 0.254)
		(layer "B.Cu")
		(net "+12V")
	)
	(segment
		(start 180.8216 81.9162)
		(end 184.9216 86.0162)
		(width 0.254)
		(layer "B.Cu")
		(net "+12V")
	)
	(segment
		(start 84.1716 60.5162)
		(end 85.6466 59.0412)
		(width 0.254)
		(layer "B.Cu")
		(net "+12V")
	)
	(segment
		(start 184.3216 91.7912)
		(end 184.3216 88.7162)
		(width 0.254)
		(layer "B.Cu")
		(net "+12V")
	)
	(segment
		(start 184.9216 86.0162)
		(end 186.3216 86.0162)
		(width 0.254)
		(layer "B.Cu")
		(net "+12V")
	)
	(segment
		(start 180.6216 86.8162)
		(end 186.3216 86.8162)
		(width 0.254)
		(layer "B.Cu")
		(net "+12V")
	)
	(segment
		(start 95.6881 59.4037)
		(end 95.6881 58.4636)
		(width 0.254)
		(layer "B.Cu")
		(net "+12V")
	)
	(segment
		(start 95.6756 58.4511)
		(end 95.6756 57.54371)
		(width 0.254)
		(layer "B.Cu")
		(net "+12V")
	)
	(segment
		(start 186.3216 87.7162)
		(end 187.1466 88.5412)
		(width 0.254)
		(layer "B.Cu")
		(net "+12V")
	)
	(segment
		(start 184.3216 88.7162)
		(end 185.3216 87.7162)
		(width 0.254)
		(layer "B.Cu")
		(net "+12V")
	)
	(segment
		(start 177.4617 83.6563)
		(end 177.4617 81.69562)
		(width 0.254)
		(layer "B.Cu")
		(net "+12V")
	)
	(segment
		(start 85.69878 57.4162)
		(end 87.5216 57.4162)
		(width 0.254)
		(layer "B.Cu")
		(net "+12V")
	)
	(segment
		(start 187.1466 91.7912)
		(end 187.1466 88.5412)
		(width 0.254)
		(layer "B.Cu")
		(net "+12V")
	)
	(segment
		(start 102.9741 73.7286)
		(end 105.0266 73.7286)
		(width 0.762)
		(layer "F.Cu")
		(net "+5.0V")
	)
	(segment
		(start 102.43399 65.72859)
		(end 105.0266 65.72859)
		(width 0.762)
		(layer "F.Cu")
		(net "+5.0V")
	)
	(segment
		(start 114.07537 80.52063)
		(end 114.10436 80.54962)
		(width 0.254)
		(layer "F.Cu")
		(net "+5.0V")
	)
	(segment
		(start 114.10436 80.54962)
		(end 114.8216 80.54962)
		(width 0.254)
		(layer "F.Cu")
		(net "+5.0V")
	)
	(segment
		(start 88.9116 67.39847)
		(end 93.9216 67.39847)
		(width 0.508)
		(layer "F.Cu")
		(net "+5.0V")
	)
	(segment
		(start 113.6366 81.31362)
		(end 113.6436 81.30662)
		(width 0.254)
		(layer "F.Cu")
		(net "+5.0V")
	)
	(segment
		(start 93.3216 78.5162)
		(end 93.3216 77.4162)
		(width 0.254)
		(layer "F.Cu")
		(net "+5.0V")
	)
	(segment
		(start 102.9741 74.05812)
		(end 102.9741 73.7286)
		(width 0.762)
		(layer "F.Cu")
		(net "+5.0V")
	)
	(segment
		(start 113.6436 80.52063)
		(end 114.07537 80.52063)
		(width 0.254)
		(layer "F.Cu")
		(net "+5.0V")
	)
	(segment
		(start 93.3216 78.5162)
		(end 95.5716 78.5162)
		(width 0.254)
		(layer "F.Cu")
		(net "+5.0V")
	)
	(segment
		(start 113.90781 81.30662)
		(end 114.10436 81.11007)
		(width 0.254)
		(layer "F.Cu")
		(net "+5.0V")
	)
	(segment
		(start 113.6366 80.51363)
		(end 113.6436 80.52063)
		(width 0.254)
		(layer "F.Cu")
		(net "+5.0V")
	)
	(segment
		(start 102.2216 65.5162)
		(end 102.43399 65.72859)
		(width 0.762)
		(layer "F.Cu")
		(net "+5.0V")
	)
	(segment
		(start 114.10436 81.11007)
		(end 114.10436 80.54962)
		(width 0.254)
		(layer "F.Cu")
		(net "+5.0V")
	)
	(segment
		(start 98.4216 64.8162)
		(end 101.0646 64.8162)
		(width 0.762)
		(layer "F.Cu")
		(net "+5.0V")
	)
	(segment
		(start 113.6436 81.30662)
		(end 113.90781 81.30662)
		(width 0.254)
		(layer "F.Cu")
		(net "+5.0V")
	)
	(via
		(at 146.0216 65.5162)
		(size 0.4064)
		(drill 0.254)
		(layers "F.Cu" "B.Cu")
		(net "+5.0V")
	)
	(via
		(at 147.1216 65.5162)
		(size 0.4064)
		(drill 0.254)
		(layers "F.Cu" "B.Cu")
		(net "+5.0V")
	)
	(via
		(at 192.0216 111.8162)
		(size 0.4064)
		(drill 0.2032)
		(layers "F.Cu" "B.Cu")
		(tenting
			(front yes)
			(back yes)
		)
		(net "+5.0V")
	)
	(via
		(at 142.2466 90.9662)
		(size 0.4064)
		(drill 0.254)
		(layers "F.Cu" "B.Cu")
		(net "+5.0V")
	)
	(via
		(at 94.1216 69.4162)
		(size 0.4064)
		(drill 0.254)
		(layers "F.Cu" "B.Cu")
		(net "+5.0V")
	)
	(via
		(at 94.6216 66.9162)
		(size 0.4064)
		(drill 0.254)
		(layers "F.Cu" "B.Cu")
		(net "+5.0V")
	)
	(via
		(at 93.7216 74.8162)
		(size 0.4064)
		(drill 0.254)
		(layers "F.Cu" "B.Cu")
		(net "+5.0V")
	)
	(via
		(at 93.7216 68.8162)
		(size 0.4064)
		(drill 0.254)
		(layers "F.Cu" "B.Cu")
		(net "+5.0V")
	)
	(via
		(at 181.34668 111.73687)
		(size 0.4064)
		(drill 0.2032)
		(layers "F.Cu" "B.Cu")
		(tenting
			(front yes)
			(back yes)
		)
		(net "+5.0V")
	)
	(via
		(at 214.5216 123.5162)
		(size 0.4064)
		(drill 0.2032)
		(layers "F.Cu" "B.Cu")
		(net "+5.0V")
	)
	(via
		(at 181.34668 110.73688)
		(size 0.4064)
		(drill 0.2032)
		(layers "F.Cu" "B.Cu")
		(tenting
			(front yes)
			(back yes)
		)
		(net "+5.0V")
	)
	(via
		(at 146.0216 64.1162)
		(size 0.4064)
		(drill 0.254)
		(layers "F.Cu" "B.Cu")
		(net "+5.0V")
	)
	(via
		(at 102.9741 74.05812)
		(size 0.4064)
		(drill 0.2032)
		(layers "F.Cu" "B.Cu")
		(net "+5.0V")
	)
	(via
		(at 147.1216 64.1162)
		(size 0.4064)
		(drill 0.254)
		(layers "F.Cu" "B.Cu")
		(net "+5.0V")
	)
	(via
		(at 192.0216 110.3162)
		(size 0.4064)
		(drill 0.2032)
		(layers "F.Cu" "B.Cu")
		(tenting
			(front yes)
			(back yes)
		)
		(net "+5.0V")
	)
	(via
		(at 102.2216 65.5162)
		(size 0.4064)
		(drill 0.2032)
		(layers "F.Cu" "B.Cu")
		(net "+5.0V")
	)
	(via
		(at 95.3216 64.0162)
		(size 0.4064)
		(drill 0.254)
		(layers "F.Cu" "B.Cu")
		(net "+5.0V")
	)
	(via
		(at 93.7216 67.0162)
		(size 0.4064)
		(drill 0.254)
		(layers "F.Cu" "B.Cu")
		(net "+5.0V")
	)
	(via
		(at 97.8216 64.9162)
		(size 0.4064)
		(drill 0.254)
		(layers "F.Cu" "B.Cu")
		(net "+5.0V")
	)
	(via
		(at 94.6216 68.8162)
		(size 0.4064)
		(drill 0.254)
		(layers "F.Cu" "B.Cu")
		(net "+5.0V")
	)
	(via
		(at 93.7216 68.0162)
		(size 0.4064)
		(drill 0.254)
		(layers "F.Cu" "B.Cu")
		(net "+5.0V")
	)
	(via
		(at 181.34668 110.23687)
		(size 0.4064)
		(drill 0.2032)
		(layers "F.Cu" "B.Cu")
		(tenting
			(front yes)
			(back yes)
		)
		(net "+5.0V")
	)
	(via
		(at 146.0216 66.6162)
		(size 0.4064)
		(drill 0.254)
		(layers "F.Cu" "B.Cu")
		(net "+5.0V")
	)
	(via
		(at 192.0216 110.8162)
		(size 0.4064)
		(drill 0.2032)
		(layers "F.Cu" "B.Cu")
		(tenting
			(front yes)
			(back yes)
		)
		(net "+5.0V")
	)
	(via
		(at 114.8216 80.54962)
		(size 0.4064)
		(drill 0.2032)
		(layers "F.Cu" "B.Cu")
		(net "+5.0V")
	)
	(via
		(at 192.0216 111.3162)
		(size 0.4064)
		(drill 0.2032)
		(layers "F.Cu" "B.Cu")
		(tenting
			(front yes)
			(back yes)
		)
		(net "+5.0V")
	)
	(via
		(at 94.6216 68.0162)
		(size 0.4064)
		(drill 0.254)
		(layers "F.Cu" "B.Cu")
		(net "+5.0V")
	)
	(via
		(at 144.3216 91.7162)
		(size 0.4064)
		(drill 0.254)
		(layers "F.Cu" "B.Cu")
		(net "+5.0V")
	)
	(via
		(at 181.34668 111.23687)
		(size 0.4064)
		(drill 0.2032)
		(layers "F.Cu" "B.Cu")
		(tenting
			(front yes)
			(back yes)
		)
		(net "+5.0V")
	)
	(via
		(at 94.1216 65.1162)
		(size 0.4064)
		(drill 0.254)
		(layers "F.Cu" "B.Cu")
		(net "+5.0V")
	)
	(via
		(at 143.4216 90.1162)
		(size 0.4064)
		(drill 0.254)
		(layers "F.Cu" "B.Cu")
		(net "+5.0V")
	)
	(via
		(at 147.2216 66.6162)
		(size 0.4064)
		(drill 0.254)
		(layers "F.Cu" "B.Cu")
		(net "+5.0V")
	)
	(via
		(at 144.7216 90.1162)
		(size 0.4064)
		(drill 0.254)
		(layers "F.Cu" "B.Cu")
		(net "+5.0V")
	)
	(segment
		(start 214.5216 123.5162)
		(end 216.1216 123.5162)
		(width 0.254)
		(layer "B.Cu")
		(net "+5.0V")
	)
	(segment
		(start 212.2534 124.1844)
		(end 212.9216 123.5162)
		(width 0.254)
		(layer "B.Cu")
		(net "+5.0V")
	)
	(segment
		(start 94.1216 71.32482)
		(end 95.54332 72.74654)
		(width 0.762)
		(layer "B.Cu")
		(net "+5.0V")
	)
	(segment
		(start 216.44031 124.21991)
		(end 216.63831 124.41792)
		(width 0.254)
		(layer "B.Cu")
		(net "+5.0V")
	)
	(segment
		(start 104.0026 65.35345)
		(end 104.0026 64.4352)
		(width 0.762)
		(layer "B.Cu")
		(net "+5.0V")
	)
	(segment
		(start 114.0216 80.2162)
		(end 114.2446 80.4392)
		(width 0.254)
		(layer "B.Cu")
		(net "+5.0V")
	)
	(segment
		(start 103.53985 65.8162)
		(end 104.0026 65.35345)
		(width 0.762)
		(layer "B.Cu")
		(net "+5.0V")
	)
	(segment
		(start 101.9216 74.0162)
		(end 102.93219 74.0162)
		(width 0.762)
		(layer "B.Cu")
		(net "+5.0V")
	)
	(segment
		(start 216.44031 124.21991)
		(end 216.44031 123.83491)
		(width 0.254)
		(layer "B.Cu")
		(net "+5.0V")
	)
	(segment
		(start 216.1216 123.5162)
		(end 216.44031 123.83491)
		(width 0.254)
		(layer "B.Cu")
		(net "+5.0V")
	)
	(segment
		(start 216.63831 124.41792)
		(end 217.07331 124.85291)
		(width 0.254)
		(layer "B.Cu")
		(net "+5.0V")
	)
	(segment
		(start 102.9741 74.05812)
		(end 102.9741 71.7286)
		(width 0.762)
		(layer "B.Cu")
		(net "+5.0V")
	)
	(segment
		(start 212.9216 123.5162)
		(end 214.5216 123.5162)
		(width 0.254)
		(layer "B.Cu")
		(net "+5.0V")
	)
	(segment
		(start 102.93219 74.0162)
		(end 102.9741 74.05812)
		(width 0.762)
		(layer "B.Cu")
		(net "+5.0V")
	)
	(segment
		(start 212.4905 125.86791)
		(end 215.60331 125.86791)
		(width 0.254)
		(layer "B.Cu")
		(net "+5.0V")
	)
	(segment
		(start 212.2534 125.63082)
		(end 212.4905 125.86791)
		(width 0.254)
		(layer "B.Cu")
		(net "+5.0V")
	)
	(segment
		(start 104.0026 64.4352)
		(end 104.1216 64.3162)
		(width 0.762)
		(layer "B.Cu")
		(net "+5.0V")
	)
	(segment
		(start 114.78036 80.54962)
		(end 114.8216 80.54962)
		(width 0.254)
		(layer "B.Cu")
		(net "+5.0V")
	)
	(segment
		(start 114.2446 80.4392)
		(end 114.66994 80.4392)
		(width 0.254)
		(layer "B.Cu")
		(net "+5.0V")
	)
	(segment
		(start 103.4491 65.90695)
		(end 103.53985 65.8162)
		(width 0.762)
		(layer "B.Cu")
		(net "+5.0V")
	)
	(segment
		(start 103.4491 67.15612)
		(end 103.4491 65.90695)
		(width 0.762)
		(layer "B.Cu")
		(net "+5.0V")
	)
	(segment
		(start 102.5216 65.8162)
		(end 103.53985 65.8162)
		(width 0.762)
		(layer "B.Cu")
		(net "+5.0V")
	)
	(segment
		(start 94.1216 71.32482)
		(end 94.1216 69.4162)
		(width 0.762)
		(layer "B.Cu")
		(net "+5.0V")
	)
	(segment
		(start 114.66994 80.4392)
		(end 114.78036 80.54962)
		(width 0.254)
		(layer "B.Cu")
		(net "+5.0V")
	)
	(segment
		(start 102.9741 71.7286)
		(end 103.2741 71.7286)
		(width 0.762)
		(layer "B.Cu")
		(net "+5.0V")
	)
	(segment
		(start 93.7216 74.7162)
		(end 95.94304 74.7162)
		(width 0.762)
		(layer "B.Cu")
		(net "+5.0V")
	)
	(segment
		(start 102.2216 65.5162)
		(end 102.5216 65.8162)
		(width 0.762)
		(layer "B.Cu")
		(net "+5.0V")
	)
	(segment
		(start 217.07331 125.36791)
		(end 217.07331 124.85291)
		(width 0.254)
		(layer "B.Cu")
		(net "+5.0V")
	)
	(segment
		(start 100.65193 72.74654)
		(end 101.9216 74.0162)
		(width 0.762)
		(layer "B.Cu")
		(net "+5.0V")
	)
	(segment
		(start 95.54332 72.74654)
		(end 100.65193 72.74654)
		(width 0.762)
		(layer "B.Cu")
		(net "+5.0V")
	)
	(segment
		(start 212.2534 125.63082)
		(end 212.2534 124.1844)
		(width 0.254)
		(layer "B.Cu")
		(net "+5.0V")
	)
	(segment
		(start 93.7216 74.8162)
		(end 93.7216 74.7162)
		(width 0.762)
		(layer "B.Cu")
		(net "+5.0V")
	)
	(segment
		(start 203.3216 142.9162)
		(end 204.4216 144.0162)
		(width 0.2032)
		(layer "F.Cu")
		(net "FPGA_TDI")
	)
	(segment
		(start 135.43435 106.7162)
		(end 140.1216 106.7162)
		(width 0.2032)
		(layer "F.Cu")
		(net "FPGA_TDI")
	)
	(segment
		(start 180.01756 138.21216)
		(end 180.01756 124.81216)
		(width 0.2032)
		(layer "F.Cu")
		(net "FPGA_TDI")
	)
	(segment
		(start 177.6216 122.4162)
		(end 180.01756 124.81216)
		(width 0.2032)
		(layer "F.Cu")
		(net "FPGA_TDI")
	)
	(segment
		(start 140.1216 106.7162)
		(end 141.6752 108.2698)
		(width 0.2032)
		(layer "F.Cu")
		(net "FPGA_TDI")
	)
	(segment
		(start 134.89668 110.72072)
		(end 134.89668 110.70807)
		(width 0.2032)
		(layer "F.Cu")
		(net "FPGA_TDI")
	)
	(segment
		(start 142.8752 108.2698)
		(end 149.4518 114.8464)
		(width 0.2032)
		(layer "F.Cu")
		(net "FPGA_TDI")
	)
	(segment
		(start 204.4216 145.09546)
		(end 204.4216 144.0162)
		(width 0.2032)
		(layer "F.Cu")
		(net "FPGA_TDI")
	)
	(segment
		(start 134.89668 110.72072)
		(end 136.41149 110.72072)
		(width 0.2032)
		(layer "F.Cu")
		(net "FPGA_TDI")
	)
	(segment
		(start 134.36789 110.17928)
		(end 134.89668 110.70807)
		(width 0.2032)
		(layer "F.Cu")
		(net "FPGA_TDI")
	)
	(segment
		(start 202.0666 145.61546)
		(end 204.5416 145.61546)
		(width 0.2032)
		(layer "F.Cu")
		(net "FPGA_TDI")
	)
	(segment
		(start 184.7216 142.9162)
		(end 203.3216 142.9162)
		(width 0.2032)
		(layer "F.Cu")
		(net "FPGA_TDI")
	)
	(segment
		(start 153.14063 122.4162)
		(end 177.6216 122.4162)
		(width 0.2032)
		(layer "F.Cu")
		(net "FPGA_TDI")
	)
	(segment
		(start 180.01756 138.21216)
		(end 184.7216 142.9162)
		(width 0.2032)
		(layer "F.Cu")
		(net "FPGA_TDI")
	)
	(segment
		(start 149.4518 118.72737)
		(end 149.4518 114.8464)
		(width 0.2032)
		(layer "F.Cu")
		(net "FPGA_TDI")
	)
	(segment
		(start 134.36789 110.17928)
		(end 134.36789 107.78267)
		(width 0.2032)
		(layer "F.Cu")
		(net "FPGA_TDI")
	)
	(segment
		(start 141.6752 108.2698)
		(end 142.8752 108.2698)
		(width 0.2032)
		(layer "F.Cu")
		(net "FPGA_TDI")
	)
	(segment
		(start 134.36789 107.78267)
		(end 135.43435 106.7162)
		(width 0.2032)
		(layer "F.Cu")
		(net "FPGA_TDI")
	)
	(segment
		(start 204.2216 145.29546)
		(end 204.5416 145.61546)
		(width 0.2032)
		(layer "F.Cu")
		(net "FPGA_TDI")
	)
	(segment
		(start 204.2216 145.29546)
		(end 204.4216 145.09546)
		(width 0.2032)
		(layer "F.Cu")
		(net "FPGA_TDI")
	)
	(segment
		(start 149.4518 118.72737)
		(end 153.14063 122.4162)
		(width 0.2032)
		(layer "F.Cu")
		(net "FPGA_TDI")
	)
	(zone
		(net "+12V")
		(layer "F.Cu")
		(hatch edge 0.5)
		(priority 73)
		(connect_pads yes
			(clearance 0.5)
		)
		(min_thickness 0.25)
		(fill yes
			(thermal_gap 0.2032)
			(thermal_bridge_width 0.254)
			(island_removal_mode 0)
		)
		(polygon
			(pts
				(xy 141.5354 88.8162) (xy 145.8854 88.8162) (xy 145.8854 85.5662) (xy 141.5854 85.5662) (xy 141.5854 86.4662)
			)
		)
	)
	(zone
		(net "+5.0V")
		(layer "F.Cu")
		(hatch edge 0.5)
		(priority 87)
		(connect_pads yes
			(clearance 0.5)
		)
		(min_thickness 0.25)
		(fill yes
			(thermal_gap 0.2032)
			(thermal_bridge_width 0.254)
			(island_removal_mode 0)
		)
		(polygon
			(pts
				(xy 141.5854 89.3662) (xy 145.3854 89.3662) (xy 145.3854 92.2662) (xy 141.5854 92.2662)
			)
		)
	)
	(zone
		(net "GND")
		(layer "F.Cu")
		(hatch edge 0.5)
		(priority 50)
		(connect_pads yes
			(clearance 0.5)
		)
		(min_thickness 0.25)
		(fill yes
			(thermal_gap 0.2032)
			(thermal_bridge_width 0.254)
			(island_removal_mode 0)
		)
		(polygon
			(pts
				(xy 215.7216 51.0162) (xy 220.5216 51.0162) (xy 220.5216 59.6162) (xy 216.0216 59.6162) (xy 216.0216 59.4162)
				(xy 215.7216 59.4162)
			)
		)
	)
	(zone
		(net "P3V3_SENSE")
		(layer "F.Cu")
		(hatch edge 0.5)
		(priority 65)
		(connect_pads yes
			(clearance 0.5)
		)
		(min_thickness 0.25)
		(fill yes
			(thermal_gap 0.2032)
			(thermal_bridge_width 0.254)
			(island_removal_mode 0)
		)
		(polygon
			(pts
				(xy 178.7716 90.6662) (xy 176.6716 90.6662) (xy 176.6716 92.2162) (xy 172.3216 92.2162) (xy 172.3216 81.4162)
				(xy 178.3661 81.4162) (xy 178.3661 84.84531) (xy 176.934 84.84531) (xy 176.934 85.55632) (xy 174.9216 85.55632)
				(xy 174.9216 89.4162) (xy 178.7716 89.4162) (xy 178.7716 89.86482)
			)
		)
	)
	(zone
		(net "GND")
		(layer "F.Cu")
		(hatch edge 0.5)
		(priority 62)
		(connect_pads yes
			(clearance 0.5)
		)
		(min_thickness 0.25)
		(fill yes
			(thermal_gap 0.2032)
			(thermal_bridge_width 0.254)
			(island_removal_mode 0)
		)
		(polygon
			(pts
				(xy 158.0216 97.3162) (xy 158.0216 85.0162) (xy 155.5216 85.0162) (xy 155.5216 97.3162) (xy 157.9216 97.3162)
			)
		)
	)
	(zone
		(net "+3.3V")
		(layer "F.Cu")
		(hatch edge 0.5)
		(priority 17)
		(connect_pads yes
			(clearance 0.5)
		)
		(min_thickness 0.25)
		(fill yes
			(thermal_gap 0.2032)
			(thermal_bridge_width 0.254)
			(island_removal_mode 0)
		)
		(polygon
			(pts
				(xy 71.0216 64.8162) (xy 80.6216 64.8162) (xy 80.6216 72.75481) (xy 87.2216 72.75481) (xy 87.2216 88.6162)
				(xy 68.6216 88.6162) (xy 68.6216 60.6162) (xy 71.0216 60.6162)
			)
		)
	)
	(zone
		(net "+3.3V")
		(layer "F.Cu")
		(hatch edge 0.5)
		(priority 14)
		(connect_pads yes
			(clearance 0.5)
		)
		(min_thickness 0.25)
		(fill yes
			(thermal_gap 0.2032)
			(thermal_bridge_width 0.254)
			(island_removal_mode 0)
		)
		(polygon
			(pts
				(xy 210.9216 101.1162) (xy 208.2216 103.8162) (xy 208.2216 115.9162) (xy 215.9216 115.9162) (xy 215.9216 120.66797)
				(xy 220.8216 120.66797) (xy 220.8216 115.4162) (xy 219.0216 115.4162) (xy 219.0216 110.2162) (xy 220.0216 110.2162)
				(xy 220.0216 103.04177) (xy 218.1216 101.14177)
			)
		)
	)
	(zone
		(layer "F.Cu")
		(hatch edge 0.5)
		(connect_pads
			(clearance 0)
		)
		(min_thickness 0.25)
		(keepout
			(tracks allowed)
			(vias allowed)
			(pads allowed)
			(copperpour not_allowed)
			(footprints allowed)
		)
		(placement
			(enabled no)
			(sheetname "")
		)
		(fill
			(thermal_gap 0.5)
			(thermal_bridge_width 0.5)
			(island_removal_mode 0)
		)
		(polygon
			(pts
				(xy 184.46976 112.41327) (xy 184.46976 108.69194) (xy 187.61381 108.69194) (xy 187.61381 112.41885)
			)
		)
	)
	(zone
		(net "GND")
		(layer "F.Cu")
		(hatch edge 0.5)
		(priority 44)
		(connect_pads yes
			(clearance 0.5)
		)
		(min_thickness 0.25)
		(fill yes
			(thermal_gap 0.2032)
			(thermal_bridge_width 0.254)
			(island_removal_mode 0)
		)
		(polygon
			(pts
				(xy 213.1216 69.3162) (xy 213.1216 74.2162) (xy 209.1216 74.2162) (xy 209.1216 69.3162) (xy 210.3216 69.3162)
			)
		)
	)
	(zone
		(net "+12V")
		(layer "F.Cu")
		(hatch edge 0.5)
		(priority 60)
		(connect_pads yes
			(clearance 0.5)
		)
		(min_thickness 0.25)
		(fill yes
			(thermal_gap 0.2032)
			(thermal_bridge_width 0.254)
			(island_removal_mode 0)
		)
		(polygon
			(pts
				(xy 99.1554 58.646) (xy 99.83954 58.646) (xy 99.83954 58.06093) (xy 101.1391 58.06093) (xy 101.1391 53.7162)
				(xy 94.5216 53.7162) (xy 94.5216 50.0162) (xy 89.5366 50.0162) (xy 89.5366 54.82197) (xy 99.1554 54.82197)
				(xy 99.1554 56.7664)
			)
		)
	)
	(zone
		(layer "F.Cu")
		(hatch edge 0.5)
		(connect_pads
			(clearance 0)
		)
		(min_thickness 0.25)
		(keepout
			(tracks allowed)
			(vias allowed)
			(pads allowed)
			(copperpour not_allowed)
			(footprints allowed)
		)
		(placement
			(enabled no)
			(sheetname "")
		)
		(fill
			(thermal_gap 0.5)
			(thermal_bridge_width 0.5)
			(island_removal_mode 0)
		)
		(polygon
			(pts
				(arc
					(start 125.78218 116.9786)
					(mid 126.326056 118.291634)
					(end 127.63909 118.83551)
				)
				(arc
					(start 127.63909 118.83551)
					(mid 128.952124 118.291634)
					(end 129.496 116.9786)
				)
				(arc
					(start 129.496 116.9786)
					(mid 128.952124 115.665566)
					(end 127.63909 115.12169)
				)
				(arc
					(start 127.63909 115.12169)
					(mid 126.326056 115.665566)
					(end 125.78218 116.9786)
				)
			)
		)
	)
	(zone
		(net "GND")
		(layer "F.Cu")
		(hatch edge 0.5)
		(priority 64)
		(connect_pads yes
			(clearance 0.5)
		)
		(min_thickness 0.25)
		(fill yes
			(thermal_gap 0.2032)
			(thermal_bridge_width 0.254)
			(island_removal_mode 0)
		)
		(polygon
			(pts
				(xy 177.8716 93.6162) (xy 177.8716 91.2162) (xy 180.2716 91.2162) (xy 180.2716 89.55244) (xy 181.57107 89.55244)
				(xy 181.57107 93.6162) (xy 183.7716 93.6162) (xy 183.7716 94.7312) (xy 188.93189 94.7312) (xy 188.93189 98.1162)
				(xy 182.0216 98.1162) (xy 182.0216 94.6162) (xy 178.7716 94.6162) (xy 178.7716 97.0162) (xy 174.4466 97.0162)
				(xy 174.4466 93.6162) (xy 175.9716 93.6162)
			)
		)
	)
	(zone
		(net "+12V_SENS")
		(layer "F.Cu")
		(hatch edge 0.5)
		(priority 45)
		(connect_pads yes
			(clearance 0.5)
		)
		(min_thickness 0.25)
		(fill yes
			(thermal_gap 0.2032)
			(thermal_bridge_width 0.254)
			(island_removal_mode 0)
		)
		(polygon
			(pts
				(xy 222.7216 69.6162) (xy 222.7216 74.2162) (xy 217.45928 74.2162) (xy 217.45928 68.4062) (xy 219.5216 68.4062)
				(xy 219.5216 67.7162) (xy 220.9216 67.7162)
			)
		)
	)
	(zone
		(net "+12V")
		(layer "F.Cu")
		(hatch edge 0.5)
		(priority 70)
		(connect_pads yes
			(clearance 0.5)
		)
		(min_thickness 0.25)
		(fill yes
			(thermal_gap 0.2032)
			(thermal_bridge_width 0.254)
			(island_removal_mode 0)
		)
		(polygon
			(pts
				(xy 185.0016 92.4162) (xy 185.0016 90.4162) (xy 190.2216 90.4162) (xy 190.2216 88.5862) (xy 188.0216 88.5862)
				(xy 188.0216 85.0212) (xy 189.4866 85.0212) (xy 189.4866 83.0312) (xy 186.0216 83.0312) (xy 186.0216 85.9162)
				(xy 183.3216 85.9162) (xy 183.3216 86.0162) (xy 179.2918 86.0162) (xy 179.2918 87.48682) (xy 182.4216 87.48682)
				(xy 182.4216 92.4162)
			)
		)
	)
	(zone
		(net "+12V")
		(layer "F.Cu")
		(hatch edge 0.5)
		(priority 56)
		(connect_pads yes
			(clearance 0.5)
		)
		(min_thickness 0.25)
		(fill yes
			(thermal_gap 0.2032)
			(thermal_bridge_width 0.254)
			(island_removal_mode 0)
		)
		(polygon
			(pts
				(xy 80.62006 56.7631) (xy 80.62006 61.2162) (xy 81.8216 61.2162) (xy 81.8216 63.1412) (xy 85.3216 63.1412)
				(xy 85.3216 59.3162) (xy 82.6466 59.3162) (xy 82.6466 56.7631) (xy 81.19738 56.7631)
			)
		)
	)
	(zone
		(layer "F.Cu")
		(hatch edge 0.5)
		(connect_pads
			(clearance 0)
		)
		(min_thickness 0.25)
		(keepout
			(tracks allowed)
			(vias allowed)
			(pads allowed)
			(copperpour not_allowed)
			(footprints allowed)
		)
		(placement
			(enabled no)
			(sheetname "")
		)
		(fill
			(thermal_gap 0.5)
			(thermal_bridge_width 0.5)
			(island_removal_mode 0)
		)
		(polygon
			(pts
				(arc
					(start 85.18218 137.2786)
					(mid 85.726056 138.591634)
					(end 87.03909 139.13551)
				)
				(arc
					(start 87.03909 139.13551)
					(mid 88.352124 138.591634)
					(end 88.896 137.2786)
				)
				(arc
					(start 88.896 137.2786)
					(mid 88.352124 135.965566)
					(end 87.03909 135.42169)
				)
				(arc
					(start 87.03909 135.42169)
					(mid 85.726056 135.965566)
					(end 85.18218 137.2786)
				)
			)
		)
	)
	(zone
		(net "GND")
		(layer "F.Cu")
		(hatch edge 0.5)
		(priority 42)
		(connect_pads yes
			(clearance 0.5)
		)
		(min_thickness 0.25)
		(fill yes
			(thermal_gap 0.2032)
			(thermal_bridge_width 0.254)
			(island_removal_mode 0)
		)
		(polygon
			(pts
				(xy 228.5216 65.3412) (xy 228.5216 64.6162) (xy 231.3216 64.6162) (xy 231.3216 61.6162) (xy 226.7216 61.6162)
				(xy 226.7216 65.3412) (xy 226.9716 65.3412)
			)
		)
	)
	(zone
		(net "+3.3V")
		(layer "F.Cu")
		(hatch edge 0.5)
		(priority 81)
		(connect_pads yes
			(clearance 0.5)
		)
		(min_thickness 0.25)
		(fill yes
			(thermal_gap 0.2032)
			(thermal_bridge_width 0.254)
			(island_removal_mode 0)
		)
		(polygon
			(pts
				(xy 141.7854 92.9662) (xy 145.2854 92.9662) (xy 145.2854 96.0662) (xy 141.7854 96.0662)
			)
		)
	)
	(zone
		(net "GND")
		(locked yes)
		(layer "F.Cu")
		(hatch edge 0.5)
		(priority 105)
		(connect_pads yes
			(clearance 0.5)
		)
		(min_thickness 0.25)
		(fill yes
			(thermal_gap 0.2032)
			(thermal_bridge_width 0.254)
			(island_removal_mode 0)
		)
		(polygon
			(pts
				(xy 132.6405 91.51569) (xy 81.8905 91.51569) (xy 81.8905 142.26569) (xy 132.6405 142.26569)
			)
		)
	)
	(zone
		(net "GND")
		(layer "F.Cu")
		(hatch edge 0.5)
		(priority 55)
		(connect_pads yes
			(clearance 0.5)
		)
		(min_thickness 0.25)
		(fill yes
			(thermal_gap 0.2032)
			(thermal_bridge_width 0.254)
			(island_removal_mode 0)
		)
		(polygon
			(pts
				(xy 86.95004 61.65227) (xy 86.95004 64.6162) (xy 85.6216 64.6162) (xy 85.6216 58.6162) (xy 83.4716 58.6162)
				(xy 83.4716 55.6162) (xy 82.3216 55.6162) (xy 82.3216 49.6162) (xy 85.46531 49.6162) (xy 85.46531 57.6162)
				(xy 88.4716 57.6162) (xy 88.4716 55.4912) (xy 91.9216 55.4912) (xy 91.9216 59.1162) (xy 89.6216 59.1162)
				(xy 89.6216 61.0162) (xy 86.9716 61.0162) (xy 86.9716 62.5662)
			)
		)
	)
	(zone
		(net "+3.3V")
		(layer "F.Cu")
		(hatch edge 0.5)
		(priority 63)
		(connect_pads yes
			(clearance 0.5)
		)
		(min_thickness 0.25)
		(fill yes
			(thermal_gap 0.2032)
			(thermal_bridge_width 0.254)
			(island_removal_mode 0)
		)
		(polygon
			(pts
				(xy 171.64869 83.74964) (xy 170.33718 83.74964) (xy 170.33718 83.90025) (xy 168.6466 83.90025) (xy 168.6466 82.5162)
				(xy 166.90466 82.5162) (xy 166.90466 84.6162) (xy 163.3216 84.6162) (xy 163.3216 83.12996) (xy 162.39716 83.12996)
				(xy 162.39716 96.5162) (xy 165.88147 96.5162) (xy 165.88147 87.1162) (xy 172.04767 87.1162) (xy 172.04767 83.80784)
			)
		)
	)
	(zone
		(net "+12V_PCIE")
		(layer "F.Cu")
		(hatch edge 0.5)
		(priority 43)
		(connect_pads yes
			(clearance 0.5)
		)
		(min_thickness 0.25)
		(fill yes
			(thermal_gap 0.2032)
			(thermal_bridge_width 0.254)
			(island_removal_mode 0)
		)
		(polygon
			(pts
				(xy 225.2716 63.0662) (xy 225.2716 60.6162) (xy 223.3716 60.6162) (xy 223.3716 63.0662)
			)
		)
	)
	(zone
		(net "NetCR1_2")
		(layer "F.Cu")
		(hatch edge 0.5)
		(priority 48)
		(connect_pads yes
			(clearance 0.5)
		)
		(min_thickness 0.25)
		(fill yes
			(thermal_gap 0.2032)
			(thermal_bridge_width 0.254)
			(island_removal_mode 0)
		)
		(polygon
			(pts
				(xy 222.9216 61.6603) (xy 222.9216 64.4162) (xy 220.546 64.4162) (xy 220.546 67.1721) (xy 214.6278 67.1721)
				(xy 214.6278 61.6603)
			)
		)
	)
	(zone
		(net "+3.3V")
		(layer "F.Cu")
		(hatch edge 0.5)
		(priority 29)
		(connect_pads yes
			(clearance 0.5)
		)
		(min_thickness 0.25)
		(fill yes
			(thermal_gap 0.2032)
			(thermal_bridge_width 0.254)
			(island_removal_mode 0)
		)
		(polygon
			(pts
				(xy 156.28478 71.9162) (xy 156.28478 79.0162) (xy 132.40793 79.0162) (xy 132.40793 57.4162) (xy 123.8966 57.4162)
				(xy 123.8966 51.6162) (xy 138.3216 51.6162) (xy 138.3216 71.9162)
			)
		)
	)
	(zone
		(net "+12V_PCIE")
		(layer "F.Cu")
		(hatch edge 0.5)
		(priority 49)
		(connect_pads yes
			(clearance 0.5)
		)
		(min_thickness 0.25)
		(fill yes
			(thermal_gap 0.2032)
			(thermal_bridge_width 0.254)
			(island_removal_mode 0)
		)
		(polygon
			(pts
				(xy 212.1216 65.4162) (xy 212.1216 68.0162) (xy 208.7216 68.0162) (xy 208.7216 70.0162) (xy 206.2216 70.0162)
				(xy 206.2216 65.4162) (xy 212.0216 65.4162)
			)
		)
	)
	(zone
		(net "GND")
		(layer "F.Cu")
		(hatch edge 0.5)
		(priority 68)
		(connect_pads yes
			(clearance 0.5)
		)
		(min_thickness 0.25)
		(fill yes
			(thermal_gap 0.2032)
			(thermal_bridge_width 0.254)
			(island_removal_mode 0)
		)
		(polygon
			(pts
				(xy 179.2918 84.84531) (xy 181.1714 84.84531) (xy 181.1714 83.16861) (xy 185.6216 83.16861) (xy 185.6216 79.6162)
				(xy 179.7216 79.6162) (xy 179.7216 82.73711) (xy 179.2918 82.73711)
			)
		)
	)
	(zone
		(net "MAC_VCC")
		(layer "F.Cu")
		(hatch edge 0.5)
		(priority 86)
		(connect_pads yes
			(clearance 0.5)
		)
		(min_thickness 0.25)
		(fill yes
			(thermal_gap 0.2032)
			(thermal_bridge_width 0.254)
			(island_removal_mode 0)
		)
		(polygon
			(pts
				(xy 135.8854 94.7662) (xy 135.8854 85.5662) (xy 139.8854 85.5662) (xy 139.8854 94.7662)
			)
		)
	)
	(zone
		(net "GND")
		(layer "F.Cu")
		(hatch edge 0.5)
		(priority 59)
		(connect_pads yes
			(clearance 0.5)
		)
		(min_thickness 0.25)
		(fill yes
			(thermal_gap 0.2032)
			(thermal_bridge_width 0.254)
			(island_removal_mode 0)
		)
		(polygon
			(pts
				(xy 97.9173 56.7664) (xy 96.2216 56.7664) (xy 96.2216 55.2162) (xy 93.1216 55.2162) (xy 93.1216 57.9799)
				(xy 95.8091 57.9799) (xy 95.8091 59.2162) (xy 98.2155 59.2162) (xy 98.2155 60.4607) (xy 98.9216 60.4607)
				(xy 98.9216 62.6162) (xy 99.78536 62.6162) (xy 99.78536 58.87286) (xy 97.9173 58.87286) (xy 97.9173 57.7062)
			)
		)
	)
	(zone
		(net "+5.0V")
		(layer "F.Cu")
		(hatch edge 0.5)
		(priority 26)
		(connect_pads yes
			(clearance 0.5)
		)
		(min_thickness 0.25)
		(fill yes
			(thermal_gap 0.2032)
			(thermal_bridge_width 0.254)
			(island_removal_mode 0)
		)
		(polygon
			(pts
				(xy 144.1216 73.9162) (xy 196.9216 73.9162) (xy 196.9216 85.26153) (xy 192.43528 85.26153) (xy 192.43528 102.42639)
				(xy 183.01818 102.42639) (xy 183.01818 108.8162) (xy 180.9216 108.8162) (xy 180.9216 112.2162) (xy 194.9216 112.2162)
				(xy 194.9216 104.5162) (xy 200.2216 104.5162) (xy 200.2216 90.7162) (xy 203.4216 90.7162) (xy 203.4216 68.8162)
				(xy 150.8216 68.8162) (xy 150.8216 63.2162) (xy 144.1216 63.2162)
			)
		)
	)
	(zone
		(layer "F.Cu")
		(hatch edge 0.5)
		(connect_pads
			(clearance 0)
		)
		(min_thickness 0.25)
		(keepout
			(tracks allowed)
			(vias allowed)
			(pads allowed)
			(copperpour not_allowed)
			(footprints allowed)
		)
		(placement
			(enabled no)
			(sheetname "")
		)
		(fill
			(thermal_gap 0.5)
			(thermal_bridge_width 0.5)
			(island_removal_mode 0)
		)
		(polygon
			(pts
				(arc
					(start 125.78218 96.6786)
					(mid 126.326056 97.991634)
					(end 127.63909 98.53551)
				)
				(arc
					(start 127.63909 98.53551)
					(mid 128.952124 97.991634)
					(end 129.496 96.6786)
				)
				(arc
					(start 129.496 96.6786)
					(mid 128.952124 95.365566)
					(end 127.63909 94.82169)
				)
				(arc
					(start 127.63909 94.82169)
					(mid 126.326056 95.365566)
					(end 125.78218 96.6786)
				)
			)
		)
	)
	(zone
		(net "+5.0V")
		(layer "F.Cu")
		(hatch edge 0.5)
		(priority 57)
		(connect_pads yes
			(clearance 0.5)
		)
		(min_thickness 0.25)
		(fill yes
			(thermal_gap 0.2032)
			(thermal_bridge_width 0.254)
			(island_removal_mode 0)
		)
		(polygon
			(pts
				(xy 93.8216 63.7162) (xy 93.5966 63.7162) (xy 103.0216 63.7162) (xy 103.0216 65.82781) (xy 96.1716 65.82781)
				(xy 96.1716 72.3162) (xy 94.5216 72.3162) (xy 94.5216 77.9162) (xy 89.1216 77.9162) (xy 89.1216 72.0162)
				(xy 93.1216 72.0162) (xy 93.1216 63.7162) (xy 94.0216 63.7162)
			)
		)
	)
	(zone
		(net "+5.0V")
		(layer "F.Cu")
		(hatch edge 0.5)
		(priority 72)
		(connect_pads yes
			(clearance 0.5)
		)
		(min_thickness 0.25)
		(fill yes
			(thermal_gap 0.2032)
			(thermal_bridge_width 0.254)
			(island_removal_mode 0)
		)
		(polygon
			(pts
				(xy 180.9216 109.7162) (xy 180.9216 112.1162) (xy 185.0216 112.1162) (xy 185.0216 109.7162)
			)
		)
	)
	(zone
		(net "+12V")
		(layer "F.Cu")
		(hatch edge 0.5)
		(priority 46)
		(connect_pads yes
			(clearance 0.5)
		)
		(min_thickness 0.25)
		(fill yes
			(thermal_gap 0.2032)
			(thermal_bridge_width 0.254)
			(island_removal_mode 0)
		)
		(polygon
			(pts
				(xy 223.8557 67.1162) (xy 226.9716 67.1162) (xy 226.9716 65.6912) (xy 231.2216 65.6912) (xy 231.2216 69.3412)
				(xy 223.8216 69.3412)
			)
		)
	)
	(zone
		(net "P5V_SENSE")
		(layer "F.Cu")
		(hatch edge 0.5)
		(priority 58)
		(connect_pads yes
			(clearance 0.5)
		)
		(min_thickness 0.25)
		(fill yes
			(thermal_gap 0.2032)
			(thermal_bridge_width 0.254)
			(island_removal_mode 0)
		)
		(polygon
			(pts
				(xy 97.9173 59.5717) (xy 97.9173 60.89208) (xy 98.57157 60.89208) (xy 98.57157 63.4162) (xy 92.59077 63.4162)
				(xy 92.59077 66.4162) (xy 90.0216 66.4162) (xy 90.0216 63.9162) (xy 88.4216 63.9162) (xy 88.4216 61.5162)
				(xy 90.2216 61.5162) (xy 90.2216 59.8162) (xy 95.8091 59.8162) (xy 95.8091 59.5717)
			)
		)
	)
	(zone
		(net "P5V_MUN_PHASE")
		(layer "F.Cu")
		(hatch edge 0.5)
		(priority 61)
		(connect_pads yes
			(clearance 0.5)
		)
		(min_thickness 0.25)
		(fill yes
			(thermal_gap 0.2032)
			(thermal_bridge_width 0.254)
			(island_removal_mode 0)
		)
		(polygon
			(pts
				(xy 98.8534 58.646) (xy 98.8534 56.2286) (xy 98.6216 56.2286) (xy 98.6216 55.0162) (xy 96.7216 55.0162)
				(xy 96.7216 56.4162) (xy 98.193 56.4162) (xy 98.193 58.646)
			)
		)
	)
	(zone
		(net "+12V_SENS")
		(layer "F.Cu")
		(hatch edge 0.5)
		(priority 47)
		(connect_pads yes
			(clearance 0.5)
		)
		(min_thickness 0.25)
		(fill yes
			(thermal_gap 0.2032)
			(thermal_bridge_width 0.254)
			(island_removal_mode 0)
		)
		(polygon
			(pts
				(xy 223.3716 65.1462) (xy 223.3716 64.5662) (xy 226.3216 64.5662) (xy 226.3216 66.7162) (xy 222.7216 66.7162)
				(xy 222.7216 69.6162) (xy 220.2216 69.6162) (xy 220.2216 67.4912) (xy 221.1716 67.4912) (xy 221.1716 65.1162)
				(xy 222.6216 65.1162) (xy 222.6216 65.1462)
			)
		)
	)
	(zone
		(net "P3V3_MUN_PHASE")
		(layer "F.Cu")
		(hatch edge 0.5)
		(priority 69)
		(connect_pads yes
			(clearance 0.5)
		)
		(min_thickness 0.25)
		(fill yes
			(thermal_gap 0.2032)
			(thermal_bridge_width 0.254)
			(island_removal_mode 0)
		)
		(polygon
			(pts
				(xy 179.47636 85.22081) (xy 181.7216 85.22081) (xy 181.7216 83.4162) (xy 183.3216 83.4162) (xy 183.3216 85.78142)
				(xy 179.2918 85.78142) (xy 179.2918 85.12102)
			)
		)
	)
	(zone
		(layer "F.Cu")
		(hatch edge 0.5)
		(connect_pads
			(clearance 0)
		)
		(min_thickness 0.25)
		(keepout
			(tracks not_allowed)
			(vias not_allowed)
			(pads not_allowed)
			(copperpour not_allowed)
			(footprints allowed)
		)
		(placement
			(enabled no)
			(sheetname "")
		)
		(fill
			(thermal_gap 0.5)
			(thermal_bridge_width 0.5)
			(island_removal_mode 0)
		)
		(polygon
			(pts
				(arc
					(start 64.82122 156.0786)
					(mid 64.835976 156.114224)
					(end 64.8716 156.12898)
				)
				(arc
					(start 79.8716 156.12898)
					(mid 79.907224 156.114224)
					(end 79.92198 156.0786)
				)
				(xy 79.92198 147.87898) (xy 98.17122 147.87898)
				(arc
					(start 98.17122 152.6286)
					(mid 98.185976 152.664224)
					(end 98.2216 152.67898)
				)
				(arc
					(start 106.2216 152.67898)
					(mid 106.257224 152.664224)
					(end 106.27198 152.6286)
				)
				(xy 106.271977 152.628094) (xy 106.27198 152.62809)
				(arc
					(start 106.27198 149.6536)
					(mid 108.0466 147.87898)
					(end 109.82122 149.6536)
				)
				(arc
					(start 109.82122 149.6536)
					(mid 109.8716 149.70398)
					(end 109.92198 149.6536)
				)
				(arc
					(start 109.92198 146.8286)
					(mid 109.907224 146.792976)
					(end 109.8716 146.77822)
				)
				(arc
					(start 64.8716 146.77822)
					(mid 64.835976 146.792976)
					(end 64.82122 146.8286)
				)
			)
		)
	)
	(zone
		(net "+3.3V")
		(layer "F.Cu")
		(hatch edge 0.5)
		(priority 13)
		(connect_pads yes
			(clearance 0.5)
		)
		(min_thickness 0.25)
		(fill yes
			(thermal_gap 0.2032)
			(thermal_bridge_width 0.254)
			(island_removal_mode 0)
		)
		(polygon
			(pts
				(xy 200.84861 120.66882) (xy 196.9216 120.66882) (xy 196.9216 115.4162) (xy 203.5216 108.8162) (xy 210.2216 108.8162)
				(xy 210.4216 108.6162) (xy 210.4216 115.9162) (xy 210.2216 116.1162) (xy 202.6216 116.1162) (xy 200.8216 117.9162)
				(xy 200.8216 120.6162)
			)
		)
	)
	(zone
		(net "GND")
		(layer "F.Cu")
		(hatch edge 0.5)
		(priority 67)
		(connect_pads yes
			(clearance 0.5)
		)
		(min_thickness 0.25)
		(fill yes
			(thermal_gap 0.2032)
			(thermal_bridge_width 0.254)
			(island_removal_mode 0)
		)
		(polygon
			(pts
				(xy 178.3661 85.14352) (xy 178.3661 87.3162) (xy 175.2216 87.3162) (xy 175.2216 85.82321) (xy 177.17461 85.82321)
				(xy 177.17461 85.14352) (xy 177.9216 85.14352)
			)
		)
	)
	(zone
		(net "GND")
		(layer "F.Cu")
		(hatch edge 0.5)
		(priority 41)
		(connect_pads yes
			(clearance 0.5)
		)
		(min_thickness 0.25)
		(fill yes
			(thermal_gap 0.2032)
			(thermal_bridge_width 0.254)
			(island_removal_mode 0)
		)
		(polygon
			(pts
				(xy 64.61718 89.62909) (xy 81.2216 89.62909) (xy 81.2216 145.8162) (xy 64.61718 145.8162) (xy 64.61718 145.86853)
			)
		)
	)
	(zone
		(net "+5.0V")
		(layer "F.Cu")
		(hatch edge 0.5)
		(priority 71)
		(connect_pads yes
			(clearance 0.5)
		)
		(min_thickness 0.25)
		(fill yes
			(thermal_gap 0.2032)
			(thermal_bridge_width 0.254)
			(island_removal_mode 0)
		)
		(polygon
			(pts
				(xy 190.8216 109.8162) (xy 190.8216 112.0162) (xy 187.0216 112.0162) (xy 187.0216 109.8162) (xy 187.9216 109.8162)
			)
		)
	)
	(zone
		(net "NetCR1_1")
		(layer "F.Cu")
		(hatch edge 0.5)
		(priority 51)
		(connect_pads yes
			(clearance 0.5)
		)
		(min_thickness 0.25)
		(fill yes
			(thermal_gap 0.2032)
			(thermal_bridge_width 0.254)
			(island_removal_mode 0)
		)
		(polygon
			(pts
				(xy 214.7216 50.9162) (xy 214.7216 60.7162) (xy 212.1216 60.7162) (xy 212.1216 63.7162) (xy 204.7216 63.7162)
				(xy 204.7216 57.7162) (xy 206.5216 57.7162) (xy 206.5216 55.1162) (xy 210.4216 55.1162) (xy 210.4216 50.9162)
				(xy 211.7216 50.9162)
			)
		)
	)
	(zone
		(layers "F.Cu" "B.Cu" "In1.Cu" "In2.Cu" "In3.Cu" "In4.Cu")
		(hatch edge 0.5)
		(connect_pads
			(clearance 0)
		)
		(min_thickness 0.25)
		(keepout
			(tracks not_allowed)
			(vias not_allowed)
			(pads not_allowed)
			(copperpour not_allowed)
			(footprints allowed)
		)
		(placement
			(enabled no)
			(sheetname "")
		)
		(fill
			(thermal_gap 0.5)
			(thermal_bridge_width 0.5)
			(island_removal_mode 0)
		)
		(polygon
			(pts
				(xy 98.2216 156.0786) (xy 106.2216 156.0786) (xy 106.2216 152.6286) (xy 98.2216 152.6286)
			)
		)
	)
	(zone
		(layer "F.Mask")
		(hatch edge 0.5)
		(priority 143)
		(connect_pads yes
			(clearance 0.5)
		)
		(min_thickness 0.25)
		(fill yes
			(thermal_gap 0.2032)
			(thermal_bridge_width 0.254)
			(island_removal_mode 0)
		)
		(polygon
			(pts
				(xy 132.5716 91.5162) (xy 81.8216 91.5162) (xy 81.8216 142.2662) (xy 132.5716 142.2662)
			)
		)
	)
	(zone
		(net "+5.0V")
		(layer "B.Cu")
		(hatch edge 0.5)
		(priority 23)
		(connect_pads yes
			(clearance 0.5)
		)
		(min_thickness 0.25)
		(fill yes
			(thermal_gap 0.2032)
			(thermal_bridge_width 0.254)
			(island_removal_mode 0)
		)
		(polygon
			(pts
				(xy 95.0966 65.4949) (xy 95.0966 69.8162) (xy 93.0216 69.8162) (xy 93.0216 65.5162) (xy 94.0216 65.5162)
			)
		)
	)
	(zone
		(net "FTDI_P3V3")
		(layer "B.Cu")
		(hatch edge 0.5)
		(priority 39)
		(connect_pads yes
			(clearance 0.5)
		)
		(min_thickness 0.25)
		(fill yes
			(thermal_gap 0.2032)
			(thermal_bridge_width 0.254)
			(island_removal_mode 0)
		)
		(polygon
			(pts
				(xy 221.5633 126.11428) (xy 221.5633 126.76292) (xy 219.40548 126.76292) (xy 219.40548 126.11428)
				(xy 221.3783 126.11428)
			)
		)
	)
	(zone
		(net "+3.3V")
		(layer "B.Cu")
		(hatch edge 0.5)
		(priority 7)
		(connect_pads yes
			(clearance 0.5)
		)
		(min_thickness 0.25)
		(fill yes
			(thermal_gap 0.2032)
			(thermal_bridge_width 0.254)
			(island_removal_mode 0)
		)
		(polygon
			(pts
				(xy 186.9216 63.8162) (xy 186.9216 70.3162) (xy 197.3216 70.3162) (xy 197.3216 89.7162) (xy 195.2216 89.7162)
				(xy 195.2216 94.6162) (xy 202.3216 94.6162) (xy 202.3216 63.8162)
			)
		)
	)
	(zone
		(net "+3.3V")
		(layer "B.Cu")
		(hatch edge 0.5)
		(priority 3)
		(connect_pads yes
			(clearance 0.5)
		)
		(min_thickness 0.25)
		(fill yes
			(thermal_gap 0.2032)
			(thermal_bridge_width 0.254)
			(island_removal_mode 0)
		)
		(polygon
			(pts
				(xy 166.03957 97.32505) (xy 161.24111 97.32505) (xy 161.24111 83.80916) (xy 167.60201 83.80916)
				(xy 167.60201 93.4162) (xy 164.50523 93.4162) (xy 164.50523 95.05977) (xy 166.03957 95.05977)
			)
		)
	)
	(zone
		(net "+12V")
		(layer "B.Cu")
		(hatch edge 0.5)
		(priority 11)
		(connect_pads yes
			(clearance 0.5)
		)
		(min_thickness 0.25)
		(fill yes
			(thermal_gap 0.2032)
			(thermal_bridge_width 0.254)
			(island_removal_mode 0)
		)
		(polygon
			(pts
				(xy 139.7216 89.1162) (xy 145.9216 89.1162) (xy 145.9216 71.48549) (xy 157.3216 71.48549) (xy 157.3216 62.2162)
				(xy 148.4216 62.2162) (xy 148.4216 67.4162) (xy 139.7216 67.4162)
			)
		)
	)
	(zone
		(net "GNSS2_P3V3")
		(layer "B.Cu")
		(hatch edge 0.5)
		(priority 1)
		(connect_pads yes
			(clearance 0.5)
		)
		(min_thickness 0.25)
		(fill yes
			(thermal_gap 0.2032)
			(thermal_bridge_width 0.254)
			(island_removal_mode 0)
		)
		(polygon
			(pts
				(xy 207.4466 132.0662) (xy 207.0592 132.0662) (xy 207.0592 135.0162) (xy 202.3216 135.0162) (xy 202.3216 128.1162)
				(xy 199.8716 128.1162) (xy 199.8716 122.14402) (xy 203.5716 122.14402) (xy 203.5716 125.9162) (xy 204.6216 125.9162)
				(xy 204.6216 129.80361) (xy 207.4466 129.80361) (xy 207.4466 131.5162)
			)
		)
	)
	(zone
		(net "+5.0V")
		(layer "B.Cu")
		(hatch edge 0.5)
		(priority 37)
		(connect_pads yes
			(clearance 0.5)
		)
		(min_thickness 0.25)
		(fill yes
			(thermal_gap 0.2032)
			(thermal_bridge_width 0.254)
			(island_removal_mode 0)
		)
		(polygon
			(pts
				(xy 93.8216 63.7162) (xy 100.02329 63.7162) (xy 100.02329 66.6162) (xy 98.6216 66.6162) (xy 98.6216 66.4162)
				(xy 93.5716 66.4162) (xy 93.5716 63.7162)
			)
		)
	)
	(zone
		(net "+3.3V")
		(layer "B.Cu")
		(hatch edge 0.5)
		(priority 5)
		(connect_pads yes
			(clearance 0.5)
		)
		(min_thickness 0.25)
		(fill yes
			(thermal_gap 0.2032)
			(thermal_bridge_width 0.254)
			(island_removal_mode 0)
		)
		(polygon
			(pts
				(xy 163.45775 87.3162) (xy 170.41905 87.3162) (xy 170.41905 88.88816) (xy 172.0216 88.88816) (xy 172.0216 99.09384)
				(xy 162.42394 99.09384) (xy 162.42394 109.30275) (xy 164.0138 109.30275) (xy 164.0138 113.6412)
				(xy 168.4966 113.6412) (xy 168.4966 101.4162) (xy 172.5216 101.4162) (xy 175.56482 98.37298) (xy 175.56482 90.35942)
				(xy 173.3216 88.1162) (xy 173.3216 83.81288) (xy 162.9216 83.81288) (xy 162.9216 87.3162)
			)
		)
	)
	(zone
		(net "GNSS2_P3V3")
		(layer "B.Cu")
		(hatch edge 0.5)
		(priority 2)
		(connect_pads yes
			(clearance 0.5)
		)
		(min_thickness 0.25)
		(fill yes
			(thermal_gap 0.2032)
			(thermal_bridge_width 0.254)
			(island_removal_mode 0)
		)
		(polygon
			(pts
				(xy 197.2216 116.4162) (xy 204.5216 116.4162) (xy 211.0216 116.4162) (xy 211.0216 118.9162) (xy 219.7216 118.9162)
				(xy 219.7216 123.0162) (xy 197.2216 123.0162) (xy 197.2216 121.0882)
			)
		)
	)
	(zone
		(layer "B.Cu")
		(hatch edge 0.5)
		(connect_pads
			(clearance 0)
		)
		(min_thickness 0.25)
		(keepout
			(tracks not_allowed)
			(vias not_allowed)
			(pads not_allowed)
			(copperpour not_allowed)
			(footprints allowed)
		)
		(placement
			(enabled no)
			(sheetname "")
		)
		(fill
			(thermal_gap 0.5)
			(thermal_bridge_width 0.5)
			(island_removal_mode 0)
		)
		(polygon
			(pts
				(arc
					(start 64.82122 156.0786)
					(mid 64.835976 156.114224)
					(end 64.8716 156.12898)
				)
				(arc
					(start 79.8716 156.12898)
					(mid 79.907224 156.114224)
					(end 79.92198 156.0786)
				)
				(xy 79.92198 147.87898) (xy 98.17122 147.87898)
				(arc
					(start 98.17122 152.6286)
					(mid 98.185976 152.664224)
					(end 98.2216 152.67898)
				)
				(arc
					(start 106.2216 152.67898)
					(mid 106.257224 152.664224)
					(end 106.27198 152.6286)
				)
				(xy 106.271977 152.628094) (xy 106.27198 152.62809)
				(arc
					(start 106.27198 149.6536)
					(mid 108.0466 147.87898)
					(end 109.82122 149.6536)
				)
				(arc
					(start 109.82122 149.6536)
					(mid 109.8716 149.70398)
					(end 109.92198 149.6536)
				)
				(arc
					(start 109.92198 146.8286)
					(mid 109.907224 146.792976)
					(end 109.8716 146.77822)
				)
				(arc
					(start 64.8716 146.77822)
					(mid 64.835976 146.792976)
					(end 64.82122 146.8286)
				)
			)
		)
	)
	(zone
		(layer "In1.Cu")
		(hatch edge 0.5)
		(connect_pads
			(clearance 0)
		)
		(min_thickness 0.25)
		(keepout
			(tracks allowed)
			(vias allowed)
			(pads allowed)
			(copperpour not_allowed)
			(footprints allowed)
		)
		(placement
			(enabled no)
			(sheetname "")
		)
		(fill
			(thermal_gap 0.5)
			(thermal_bridge_width 0.5)
			(island_removal_mode 0)
		)
		(polygon
			(pts
				(xy 109.7216 160.9286) (xy 109.7216 154.8536) (xy 144.4716 154.8536) (xy 144.4716 161.1786)
			)
		)
	)
	(zone
		(net "GND")
		(layer "In1.Cu")
		(hatch edge 0.5)
		(priority 127)
		(connect_pads yes
			(clearance 0.5)
		)
		(min_thickness 0.25)
		(fill yes
			(thermal_gap 0.2032)
			(thermal_bridge_width 0.254)
			(island_removal_mode 0)
		)
		(polygon
			(pts
				(xy 79.6504 155.8018) (xy 79.6504 147.5722) (xy 98.4464 147.5722) (xy 98.4464 155.8018) (xy 105.9902 155.8018)
				(xy 105.9902 148.639) (xy 107.1332 147.496) (xy 108.962 147.496) (xy 110.1304 148.6644) (xy 110.1304 160.0436)
				(xy 110.4098 160.323) (xy 120.519 160.323) (xy 120.8238 160.0182) (xy 120.8238 152.6014) (xy 121.6366 151.7886)
				(xy 122.3478 151.7886) (xy 123.1606 152.6014) (xy 123.1606 160.0436) (xy 123.4908 160.3738) (xy 143.633 160.3738)
				(xy 143.9886 160.0182) (xy 143.9886 147.6484) (xy 250.12158 147.64841) (xy 250.12159 49.6786) (xy 65.37759 49.67861)
				(xy 65.0708 49.9854) (xy 65.0708 155.8018)
			)
		)
	)
	(zone
		(net "+3.3V")
		(layer "In2.Cu")
		(hatch edge 0.5)
		(priority 4)
		(connect_pads yes
			(clearance 0.5)
		)
		(min_thickness 0.25)
		(fill yes
			(thermal_gap 0.2032)
			(thermal_bridge_width 0.254)
			(island_removal_mode 0)
		)
		(polygon
			(pts
				(xy 144.7216 75.0162) (xy 137.24579 81.2162) (xy 128.0216 81.2162) (xy 126.7216 82.5162) (xy 94.15014 82.5162)
				(xy 94.15014 80.34473) (xy 82.0216 68.2162) (xy 82.0216 65.7162) (xy 81.8216 65.5162) (xy 72.9216 65.5162)
				(xy 71.3216 63.9162) (xy 71.3216 61.44791) (xy 69.95574 60.08206) (xy 67.05574 60.08206) (xy 66.9216 60.2162)
				(xy 66.9216 69.1162) (xy 87.88907 90.08367) (xy 118.35413 90.08367) (xy 119.81785 88.61995) (xy 132.91785 88.61995)
				(xy 134.5216 87.0162) (xy 145.1216 87.0162)
			)
		)
	)
	(zone
		(net "+12V")
		(layer "In2.Cu")
		(hatch edge 0.5)
		(priority 25)
		(connect_pads yes
			(clearance 0.5)
		)
		(min_thickness 0.25)
		(fill yes
			(thermal_gap 0.2032)
			(thermal_bridge_width 0.254)
			(island_removal_mode 0)
		)
		(polygon
			(pts
				(xy 101.1216 50.2162) (xy 83.1216 50.2162) (xy 83.1216 62.1162) (xy 158.4216 62.1162) (xy 158.4216 61.5349)
				(xy 194.4216 61.5349) (xy 194.4216 69.1162) (xy 204.5216 69.1162) (xy 204.5216 56.0039) (xy 101.1216 56.0039)
			)
		)
	)
	(zone
		(net "+3.3V")
		(layer "In2.Cu")
		(hatch edge 0.5)
		(priority 34)
		(connect_pads yes
			(clearance 0.5)
		)
		(min_thickness 0.25)
		(fill yes
			(thermal_gap 0.2032)
			(thermal_bridge_width 0.254)
			(island_removal_mode 0)
		)
		(polygon
			(pts
				(xy 158.8216 87.8162) (xy 158.8216 83.9162) (xy 149.5216 83.9162) (xy 149.5216 96.4162) (xy 140.7716 96.4162)
				(xy 140.7716 74.9162) (xy 148.67942 74.9162) (xy 148.67942 70.2162) (xy 171.3216 70.2162) (xy 171.3216 73.9162)
				(xy 175.2216 73.9162) (xy 175.2216 87.8162) (xy 166.2216 87.8162)
			)
		)
	)
	(zone
		(net "+5.0V")
		(layer "In2.Cu")
		(hatch edge 0.5)
		(priority 36)
		(connect_pads yes
			(clearance 0.5)
		)
		(min_thickness 0.25)
		(fill yes
			(thermal_gap 0.2032)
			(thermal_bridge_width 0.254)
			(island_removal_mode 0)
		)
		(polygon
			(pts
				(xy 92.9216 66.50412) (xy 92.9216 72.7162) (xy 101.2216 72.7162) (xy 101.2216 75.8258) (xy 111.6216 75.8258)
				(xy 111.6216 81.1162) (xy 116.7267 81.1162) (xy 116.7267 66.50412) (xy 101.4216 66.50412)
			)
		)
	)
	(zone
		(net "+5.0V")
		(layer "In2.Cu")
		(hatch edge 0.5)
		(priority 32)
		(connect_pads yes
			(clearance 0.5)
		)
		(min_thickness 0.25)
		(fill yes
			(thermal_gap 0.2032)
			(thermal_bridge_width 0.254)
			(island_removal_mode 0)
		)
		(polygon
			(pts
				(xy 92.9216 66.50412) (xy 92.9216 62.7162) (xy 148.1216 62.7162) (xy 148.1216 70.6162) (xy 93.0216 70.6162)
				(xy 93.0216 66.3162)
			)
		)
	)
	(zone
		(net "+12V_PCIE")
		(layer "In2.Cu")
		(hatch edge 0.5)
		(priority 19)
		(connect_pads yes
			(clearance 0.5)
		)
		(min_thickness 0.25)
		(fill yes
			(thermal_gap 0.2032)
			(thermal_bridge_width 0.254)
			(island_removal_mode 0)
		)
		(polygon
			(pts
				(xy 113.6216 147.3162) (xy 113.6216 142.0162) (xy 111.4216 142.0162) (xy 111.4216 133.3162) (xy 136.9216 133.3162)
				(xy 186.85014 135.36556) (xy 186.85014 127.23341) (xy 189.46055 124.623) (xy 189.46055 114.47724)
				(xy 190.7216 113.2162) (xy 190.7216 99.0162) (xy 214.0216 75.7162) (xy 214.0216 65.2162) (xy 206.4216 65.2162)
				(xy 206.2216 65.4162) (xy 206.2216 70.3162) (xy 179.48161 97.05619) (xy 179.48161 116.55619) (xy 167.5216 128.5162)
				(xy 142.01711 123.8162) (xy 99.4216 123.8162) (xy 99.4216 147.3162)
			)
		)
	)
	(zone
		(net "MAC_VCC")
		(layer "In2.Cu")
		(hatch edge 0.5)
		(priority 40)
		(connect_pads yes
			(clearance 0.5)
		)
		(min_thickness 0.25)
		(fill yes
			(thermal_gap 0.2032)
			(thermal_bridge_width 0.254)
			(island_removal_mode 0)
		)
		(polygon
			(pts
				(xy 138.67655 86.5162) (xy 138.67655 96.0162) (xy 131.5216 96.0162) (xy 131.5216 98.3162) (xy 125.6216 98.3162)
				(xy 125.6216 91.6162) (xy 135.1216 91.6162) (xy 135.1216 86.5162)
			)
		)
	)
	(zone
		(net "+3.3V")
		(layer "In2.Cu")
		(hatch edge 0.5)
		(priority 16)
		(connect_pads yes
			(clearance 0.5)
		)
		(min_thickness 0.25)
		(fill yes
			(thermal_gap 0.2032)
			(thermal_bridge_width 0.254)
			(island_removal_mode 0)
		)
		(polygon
			(pts
				(xy 82.3216 87.0162) (xy 82.3216 146.6162) (xy 74.1216 146.6162) (xy 74.1216 87.0162)
			)
		)
	)
	(zone
		(net "GNSS2_P5V0")
		(layer "In2.Cu")
		(hatch edge 0.5)
		(connect_pads yes
			(clearance 0.5)
		)
		(min_thickness 0.25)
		(fill yes
			(thermal_gap 0.2032)
			(thermal_bridge_width 0.254)
			(island_removal_mode 0)
		)
		(polygon
			(pts
				(xy 219.40548 125.2962) (xy 219.40548 128.73033) (xy 206.1216 128.73033) (xy 206.1216 137.90043)
				(xy 215.8216 137.90043) (xy 215.8216 142.34447) (xy 200.95554 142.34447) (xy 200.95554 125.2962)
			)
		)
	)
	(zone
		(net "+12V_PCIE")
		(layer "In2.Cu")
		(hatch edge 0.5)
		(priority 38)
		(connect_pads yes
			(clearance 0.5)
		)
		(min_thickness 0.25)
		(fill yes
			(thermal_gap 0.2032)
			(thermal_bridge_width 0.254)
			(island_removal_mode 0)
		)
		(polygon
			(pts
				(xy 225.8216 60.8162) (xy 225.8216 66.0162) (xy 213.8216 66.0162) (xy 213.8216 69.1162) (xy 206.2216 69.1162)
				(xy 206.2216 60.8162) (xy 214.2216 60.8162)
			)
		)
	)
	(zone
		(net "+3.3V")
		(layer "In2.Cu")
		(hatch edge 0.5)
		(priority 28)
		(connect_pads yes
			(clearance 0.5)
		)
		(min_thickness 0.25)
		(fill yes
			(thermal_gap 0.2032)
			(thermal_bridge_width 0.254)
			(island_removal_mode 0)
		)
		(polygon
			(pts
				(xy 135.6216 76.4162) (xy 123.3216 76.4162) (xy 123.3216 71.0162) (xy 135.6216 71.0162) (xy 135.6216 72.3162)
			)
		)
	)
	(zone
		(net "+3.3V")
		(layer "In2.Cu")
		(hatch edge 0.5)
		(priority 15)
		(connect_pads yes
			(clearance 0.5)
		)
		(min_thickness 0.25)
		(fill yes
			(thermal_gap 0.2032)
			(thermal_bridge_width 0.254)
			(island_removal_mode 0)
		)
		(polygon
			(pts
				(xy 209.72009 101.31771) (xy 209.6216 93.5162) (xy 223.1216 80.0162) (xy 223.1216 73.0162) (xy 226.7966 69.3412)
				(xy 231.2216 69.3412) (xy 231.2216 114.2472) (xy 225.83768 119.63112) (xy 225.83768 138.63228) (xy 226.9216 139.7162)
				(xy 226.9216 146.1162) (xy 227.1216 146.3162) (xy 226.4216 147.0162) (xy 175.3216 147.0162) (xy 175.3216 143.0162)
				(xy 177.5216 140.8162) (xy 185.13507 140.8162) (xy 186.86757 142.5487) (xy 216.19572 142.5487) (xy 216.19572 128.49798)
				(xy 220.2216 128.49798) (xy 220.2216 104.79975) (xy 218.73805 103.3162) (xy 217.50515 103.3162)
				(xy 209.72009 103.3162)
			)
		)
	)
	(zone
		(net "+12V")
		(layer "In2.Cu")
		(hatch edge 0.5)
		(priority 8)
		(connect_pads yes
			(clearance 0.5)
		)
		(min_thickness 0.25)
		(fill yes
			(thermal_gap 0.2032)
			(thermal_bridge_width 0.254)
			(island_removal_mode 0)
		)
		(polygon
			(pts
				(xy 86.95003 59.10672) (xy 86.95003 63.1412) (xy 81.22221 63.1412) (xy 81.22221 59.3162) (xy 85.1216 59.3162)
				(xy 85.1216 59.7162)
			)
		)
	)
	(zone
		(net "+5.0V")
		(layer "In2.Cu")
		(hatch edge 0.5)
		(priority 33)
		(connect_pads yes
			(clearance 0.5)
		)
		(min_thickness 0.25)
		(fill yes
			(thermal_gap 0.2032)
			(thermal_bridge_width 0.254)
			(island_removal_mode 0)
		)
		(polygon
			(pts
				(xy 191.43686 112.3162) (xy 212.3216 112.3162) (xy 212.3216 120.4912) (xy 212.3216 124.93985) (xy 219.1216 124.93985)
				(xy 219.1216 104.0162) (xy 191.43686 104.0162)
			)
		)
	)
	(zone
		(net "+12V")
		(layer "In3.Cu")
		(hatch edge 0.5)
		(priority 22)
		(connect_pads yes
			(clearance 0.5)
		)
		(min_thickness 0.25)
		(fill yes
			(thermal_gap 0.2032)
			(thermal_bridge_width 0.254)
			(island_removal_mode 0)
		)
		(polygon
			(pts
				(xy 195.6216 63.9162) (xy 210.74929 63.9162) (xy 210.74929 73.92924) (xy 230.5216 73.92924) (xy 230.5216 59.0162)
				(xy 206.8216 59.0162) (xy 206.8216 56.4162) (xy 195.6216 56.4162) (xy 195.6216 57.8162)
			)
		)
	)
	(zone
		(net "+12V")
		(layer "In3.Cu")
		(hatch edge 0.5)
		(priority 24)
		(connect_pads yes
			(clearance 0.5)
		)
		(min_thickness 0.25)
		(fill yes
			(thermal_gap 0.2032)
			(thermal_bridge_width 0.254)
			(island_removal_mode 0)
		)
		(polygon
			(pts
				(xy 183.46949 86.96831) (xy 183.46949 89.6662) (xy 199.4716 89.6662) (xy 206.9216 82.2162) (xy 212.7216 82.2162)
				(xy 216.9216 78.0162) (xy 216.9216 77.3162) (xy 223.9216 70.3162) (xy 229.5216 70.3162) (xy 230.6216 69.2162)
				(xy 230.6216 65.0162) (xy 219.2216 65.0162) (xy 212.6216 71.6162) (xy 212.6216 73.9162) (xy 209.9216 76.6162)
				(xy 202.4216 76.6162) (xy 195.71559 83.32221) (xy 187.11559 83.32221) (xy 185.5216 84.9162)
			)
		)
	)
	(zone
		(net "+3.3V")
		(layer "In3.Cu")
		(hatch edge 0.5)
		(priority 35)
		(connect_pads yes
			(clearance 0.5)
		)
		(min_thickness 0.25)
		(fill yes
			(thermal_gap 0.2032)
			(thermal_bridge_width 0.254)
			(island_removal_mode 0)
		)
		(polygon
			(pts
				(xy 112.1216 74.9162) (xy 112.1216 79.01995) (xy 110.1716 80.96994) (xy 110.1716 86.11409) (xy 107.28114 89.00455)
				(xy 104.97403 89.00455) (xy 104.2216 88.25213) (xy 104.2216 84.01232) (xy 107.3216 80.91232) (xy 107.3216 75.4162)
				(xy 107.8216 74.9162)
			)
		)
	)
	(zone
		(net "+5.0V")
		(layer "In3.Cu")
		(hatch edge 0.5)
		(priority 31)
		(connect_pads yes
			(clearance 0.5)
		)
		(min_thickness 0.25)
		(fill yes
			(thermal_gap 0.2032)
			(thermal_bridge_width 0.254)
			(island_removal_mode 0)
		)
		(polygon
			(pts
				(xy 92.2216 64.7162) (xy 117.6216 64.7162) (xy 117.6216 66.8662) (xy 136.18913 66.8662) (xy 146.4216 76.89034)
				(xy 146.4216 92.5162) (xy 139.8216 92.5162) (xy 139.0216 91.7162) (xy 139.0216 82.2162) (xy 137.4216 80.6162)
				(xy 120.9216 80.6162) (xy 119.3216 82.2162) (xy 115.04774 82.2162) (xy 113.4516 80.62006) (xy 113.4516 78.02561)
				(xy 113.46101 78.0162) (xy 118.0216 78.0162) (xy 118.8216 77.2162) (xy 118.8216 76.3162) (xy 92.2216 76.3162)
				(xy 92.2216 68.9162)
			)
		)
	)
	(zone
		(net "+3.3V")
		(layer "In3.Cu")
		(hatch edge 0.5)
		(priority 6)
		(connect_pads yes
			(clearance 0.5)
		)
		(min_thickness 0.25)
		(fill yes
			(thermal_gap 0.2032)
			(thermal_bridge_width 0.254)
			(island_removal_mode 0)
		)
		(polygon
			(pts
				(xy 182.6216 85.2162) (xy 182.6216 90.5162) (xy 205.0216 90.5162) (xy 205.0216 92.8162) (xy 216.5216 92.8162)
				(xy 216.5216 107.7162) (xy 191.3216 107.7162) (xy 191.3216 98.3162) (xy 179.34133 98.3162) (xy 172.54133 91.5162)
				(xy 167.51814 91.5162) (xy 166.6216 90.61966) (xy 166.6216 86.3162)
			)
		)
	)
	(zone
		(net "+3.3V")
		(layer "In3.Cu")
		(hatch edge 0.5)
		(priority 27)
		(connect_pads yes
			(clearance 0.5)
		)
		(min_thickness 0.25)
		(fill yes
			(thermal_gap 0.2032)
			(thermal_bridge_width 0.254)
			(island_removal_mode 0)
		)
		(polygon
			(pts
				(xy 163.8216 87.3162) (xy 163.09391 87.3162) (xy 181.5216 87.3162) (xy 194.0216 73.6162) (xy 197.2216 73.6162)
				(xy 197.2216 64.3162) (xy 180.58033 64.3162) (xy 180.58033 70.6162) (xy 160.3216 70.6162) (xy 160.3216 82.5162)
				(xy 162.5216 82.5162) (xy 162.5216 87.3162) (xy 165.5216 87.3162)
			)
		)
	)
	(zone
		(net "+5.0V")
		(layer "In3.Cu")
		(hatch edge 0.5)
		(priority 12)
		(connect_pads yes
			(clearance 0.5)
		)
		(min_thickness 0.25)
		(fill yes
			(thermal_gap 0.2032)
			(thermal_bridge_width 0.254)
			(island_removal_mode 0)
		)
		(polygon
			(pts
				(xy 180.9216 108.5162) (xy 193.4216 108.5162) (xy 193.4216 113.8162) (xy 185.0216 113.8162) (xy 185.0216 112.5162)
				(xy 180.9216 112.5162)
			)
		)
	)
	(zone
		(layer "In3.Cu")
		(hatch edge 0.5)
		(connect_pads
			(clearance 0)
		)
		(min_thickness 0.25)
		(keepout
			(tracks allowed)
			(vias allowed)
			(pads allowed)
			(copperpour not_allowed)
			(footprints allowed)
		)
		(placement
			(enabled no)
			(sheetname "")
		)
		(fill
			(thermal_gap 0.5)
			(thermal_bridge_width 0.5)
			(island_removal_mode 0)
		)
		(polygon
			(pts
				(xy 126.4216 80.6162) (xy 126.4216 78.3162) (xy 130.93525 78.3162) (xy 130.93525 81.0162) (xy 126.56861 81.0162)
				(xy 126.56861 80.8162)
			)
		)
	)
	(zone
		(net "+12V")
		(layer "In3.Cu")
		(hatch edge 0.5)
		(priority 20)
		(connect_pads yes
			(clearance 0.5)
		)
		(min_thickness 0.25)
		(fill yes
			(thermal_gap 0.2032)
			(thermal_bridge_width 0.254)
			(island_removal_mode 0)
		)
		(polygon
			(pts
				(xy 150.8216 67.5162) (xy 150.8216 55.8162) (xy 204.0216 55.8162) (xy 204.0216 61.5376) (xy 158.5216 61.5376)
				(xy 158.5216 67.5162) (xy 155.3216 67.5162)
			)
		)
	)
	(zone
		(layer "In4.Cu")
		(hatch edge 0.5)
		(connect_pads
			(clearance 0)
		)
		(min_thickness 0.25)
		(keepout
			(tracks allowed)
			(vias allowed)
			(pads allowed)
			(copperpour not_allowed)
			(footprints allowed)
		)
		(placement
			(enabled no)
			(sheetname "")
		)
		(fill
			(thermal_gap 0.5)
			(thermal_bridge_width 0.5)
			(island_removal_mode 0)
		)
		(polygon
			(pts
				(xy 109.7216 160.9286) (xy 109.7216 154.8536) (xy 144.4716 154.8536) (xy 144.4716 161.1786)
			)
		)
	)
	(zone
		(net "GND")
		(layer "In4.Cu")
		(hatch edge 0.5)
		(priority 125)
		(connect_pads yes
			(clearance 0.5)
		)
		(min_thickness 0.25)
		(fill yes
			(thermal_gap 0.2032)
			(thermal_bridge_width 0.254)
			(island_removal_mode 0)
		)
		(polygon
			(pts
				(xy 79.5254 155.9016) (xy 79.5254 147.672) (xy 98.3214 147.672) (xy 98.3214 155.9016) (xy 105.8652 155.9016)
				(xy 105.8652 148.7388) (xy 107.0082 147.5958) (xy 108.837 147.5958) (xy 110.0054 148.7642) (xy 110.0054 160.1434)
				(xy 110.2848 160.4228) (xy 120.394 160.4228) (xy 120.6988 160.118) (xy 120.6988 152.7012) (xy 121.5116 151.8884)
				(xy 122.2228 151.8884) (xy 123.0356 152.7012) (xy 123.0356 160.1434) (xy 123.3658 160.4736) (xy 143.508 160.4736)
				(xy 143.8636 160.118) (xy 143.8636 147.7482) (xy 250.12159 147.7482) (xy 250.12159 50.009) (xy 65.022 50.009)
				(xy 64.9458 50.0852) (xy 64.9458 155.9016)
			)
		)
	)
)
